G04 ================== begin FILE IDENTIFICATION RECORD ==================*
G04 Layout Name:  12432-1.brd*
G04 Film Name:    12432-1_X_Y*
G04 File Format:  Gerber RS274X*
G04 File Origin:  Cadence Allegro 16.2-S037*
G04 Origin Date:  Wed Oct 17 10:59:34 2012*
G04 *
G04 Layer:  BOARD GEOMETRY/PANEL_DRAWING*
G04 *
G04 Offset:    (0.00 0.00)*
G04 Mirror:    No*
G04 Mode:      Positive*
G04 Rotation:  0*
G04 FullContactRelief:  No*
G04 UndefLineWidth:     6.00*
G04 ================== end FILE IDENTIFICATION RECORD ====================*
%FSLAX35Y35*MOIN*%
%IR0*IPPOS*OFA0.00000B0.00000*MIA0B0*SFA1.00000B1.00000*%
%ADD10C,.006*%
G75*
%LPD*%
G75*
G54D10*
G01X-436785Y-70025D02*
Y2126667D01*
G01X2687821Y-70025D02*
X-436785D01*
G01X-429678Y53452D02*
X-428965Y52311D01*
X-428110Y51551D01*
X-427111Y51171D01*
X-425970Y51551D01*
X-425115Y52311D01*
X-424259Y53452D01*
X-423974Y54973D01*
Y62578D01*
G01X-436785Y164793D02*
X-417848D01*
G01X-428537Y278460D02*
X-425115D01*
G01X-426826D02*
Y267053D01*
G01X-428537D02*
X-425115D01*
G01X-436785Y380675D02*
X-417848D01*
G01X-436785D02*
X-417848D01*
G01X-429821Y482745D02*
Y494152D01*
G01X-423831D02*
Y482745D01*
G01Y488448D02*
X-429821D01*
G01X-436785Y596557D02*
X-417848D01*
G01X-436785D02*
X-417848D01*
G01X-425970Y704330D02*
X-423118D01*
Y700908D01*
X-423974Y699767D01*
X-424972Y699007D01*
X-426398Y698627D01*
X-427824Y699007D01*
X-428822Y699767D01*
X-429678Y700908D01*
X-430249Y702239D01*
X-430534Y703760D01*
Y705091D01*
X-430249Y706231D01*
X-429678Y707563D01*
X-428822Y708703D01*
X-427967Y709463D01*
X-426826Y710034D01*
X-425828D01*
X-424687Y709654D01*
X-423831Y708893D01*
G01X-436785Y812440D02*
X-417848D01*
G01X-436785D02*
X-417848D01*
G01X-429913Y914699D02*
Y926106D01*
X-424495D01*
G01X-426491Y920593D02*
X-429913D01*
G01X-436785Y1028321D02*
X-417848D01*
G01X-436785D02*
X-417848D01*
G01X-436785D02*
X-417848D01*
G01X-423974Y1130770D02*
X-429678D01*
Y1142177D01*
X-423974D01*
G01X-426256Y1136664D02*
X-429678D01*
G01X-436785Y1244203D02*
X-417848D01*
G01X-436785D02*
X-417848D01*
G01X-429963Y1346462D02*
Y1357869D01*
X-427111D01*
X-425970Y1357298D01*
X-425115Y1356538D01*
X-424402Y1355398D01*
X-423831Y1354066D01*
X-423689Y1352165D01*
X-423831Y1350264D01*
X-424402Y1348933D01*
X-425115Y1347793D01*
X-425970Y1347032D01*
X-427111Y1346462D01*
X-429963D01*
G01X-436785Y1460084D02*
X-417848D01*
G01X-436785D02*
X-417848D01*
G01X-423689Y1572990D02*
X-424544Y1573561D01*
X-425542Y1573941D01*
X-426683D01*
X-427967Y1573370D01*
X-428965Y1572420D01*
X-429678Y1571279D01*
X-430249Y1569378D01*
X-430391Y1567667D01*
X-430106Y1565956D01*
X-429678Y1564815D01*
X-428822Y1563674D01*
X-427824Y1562914D01*
X-426826Y1562534D01*
X-425828D01*
X-424830Y1562914D01*
X-423974Y1563484D01*
X-423261Y1564245D01*
G01X-436785Y1675966D02*
X-417848D01*
G01X-436785D02*
X-417848D01*
G01X-425685Y1784311D02*
X-425115Y1784881D01*
X-424687Y1785831D01*
X-424402Y1787163D01*
X-424687Y1788303D01*
X-425257Y1789063D01*
X-426256Y1789634D01*
X-430106D01*
Y1778227D01*
X-425400D01*
X-424402Y1778987D01*
X-423831Y1780128D01*
X-423546Y1781459D01*
X-423831Y1782790D01*
X-424687Y1783930D01*
X-425685Y1784311D01*
X-430106D01*
G01X-436785Y1891848D02*
X-417848D01*
G01X-430391Y1994108D02*
X-426826Y2005515D01*
X-423261Y1994108D01*
G01X-424544Y1998100D02*
X-429108D01*
G01X-436785Y2126667D02*
X2687821D01*
G01X-417848Y-51088D02*
Y2107730D01*
G01X2668884Y-51088D02*
X-417848D01*
G01Y2107730D02*
X2668884D01*
G01X-299948Y-66238D02*
Y-54831D01*
X-301659Y-57112D01*
G01Y-66238D02*
X-298237D01*
G01X-299948Y2111517D02*
Y2122924D01*
X-301659Y2120643D01*
G01Y2111517D02*
X-298237D01*
G01X-192497Y-51088D02*
Y-70025D01*
G01Y2126667D02*
Y2107730D01*
G01X-159606Y1989386D02*
X-159008Y1988721D01*
X-158309Y1988322D01*
X-157411Y1988189D01*
X-156512Y1988455D01*
X-155814Y1988987D01*
X-155314Y1989919D01*
X-155215Y1990984D01*
X-155414Y1992048D01*
X-155913Y1992714D01*
X-156612Y1993246D01*
X-157311Y1993379D01*
X-158009Y1993246D01*
X-158908Y1992714D01*
X-158608Y1996174D01*
X-155913D01*
G01X-149426D02*
X-150224Y1995908D01*
X-150823Y1995242D01*
X-151222Y1994444D01*
X-151522Y1993379D01*
X-151621Y1992181D01*
X-151522Y1990984D01*
X-151222Y1989919D01*
X-150823Y1989120D01*
X-150224Y1988455D01*
X-149426Y1988189D01*
X-148627Y1988455D01*
X-148028Y1989120D01*
X-147629Y1989919D01*
X-147329Y1990984D01*
X-147230Y1992181D01*
X-147329Y1993379D01*
X-147629Y1994444D01*
X-148028Y1995242D01*
X-148627Y1995908D01*
X-149426Y1996174D01*
G01X-143337Y1991516D02*
X-142638Y1992448D01*
X-142039Y1992980D01*
X-141241Y1993246D01*
X-140542Y1992980D01*
X-140043Y1992448D01*
X-139644Y1991649D01*
X-139544Y1990718D01*
X-139644Y1989919D01*
X-140043Y1989120D01*
X-140642Y1988455D01*
X-141341Y1988189D01*
X-142139Y1988455D01*
X-142838Y1989253D01*
X-143237Y1990451D01*
X-143337Y1991782D01*
X-143137Y1993512D01*
X-142838Y1994444D01*
X-142339Y1995375D01*
X-141640Y1996041D01*
X-140941Y1996174D01*
X-140243Y1995908D01*
X-139744Y1995242D01*
G01X-133456Y1987923D02*
X-133655Y1988056D01*
Y1988322D01*
X-133456Y1988455D01*
X-133256Y1988322D01*
Y1988056D01*
X-133456Y1987923D01*
G01X-125471Y1996174D02*
X-126269Y1995908D01*
X-126868Y1995242D01*
X-127267Y1994444D01*
X-127567Y1993379D01*
X-127666Y1992181D01*
X-127567Y1990984D01*
X-127267Y1989919D01*
X-126868Y1989120D01*
X-126269Y1988455D01*
X-125471Y1988189D01*
X-124672Y1988455D01*
X-124073Y1989120D01*
X-123674Y1989919D01*
X-123374Y1990984D01*
X-123275Y1992181D01*
X-123374Y1993379D01*
X-123674Y1994444D01*
X-124073Y1995242D01*
X-124672Y1995908D01*
X-125471Y1996174D01*
G01X-117486D02*
X-118284Y1995908D01*
X-118883Y1995242D01*
X-119282Y1994444D01*
X-119582Y1993379D01*
X-119681Y1992181D01*
X-119582Y1990984D01*
X-119282Y1989919D01*
X-118883Y1989120D01*
X-118284Y1988455D01*
X-117486Y1988189D01*
X-116687Y1988455D01*
X-116088Y1989120D01*
X-115689Y1989919D01*
X-115389Y1990984D01*
X-115290Y1992181D01*
X-115389Y1993379D01*
X-115689Y1994444D01*
X-116088Y1995242D01*
X-116687Y1995908D01*
X-117486Y1996174D01*
G01X-141663Y4048D02*
X-142461Y3782D01*
X-143060Y3116D01*
X-143459Y2318D01*
X-143759Y1253D01*
X-143858Y55D01*
X-143759Y-1142D01*
X-143459Y-2207D01*
X-143060Y-3006D01*
X-142461Y-3671D01*
X-141663Y-3937D01*
X-140864Y-3671D01*
X-140265Y-3006D01*
X-139866Y-2207D01*
X-139566Y-1142D01*
X-139467Y55D01*
X-139566Y1253D01*
X-139866Y2318D01*
X-140265Y3116D01*
X-140864Y3782D01*
X-141663Y4048D01*
G01X-133678Y-4203D02*
X-133877Y-4070D01*
Y-3804D01*
X-133678Y-3671D01*
X-133478Y-3804D01*
Y-4070D01*
X-133678Y-4203D01*
G01X-125693Y4048D02*
X-126491Y3782D01*
X-127090Y3116D01*
X-127489Y2318D01*
X-127789Y1253D01*
X-127888Y55D01*
X-127789Y-1142D01*
X-127489Y-2207D01*
X-127090Y-3006D01*
X-126491Y-3671D01*
X-125693Y-3937D01*
X-124894Y-3671D01*
X-124295Y-3006D01*
X-123896Y-2207D01*
X-123596Y-1142D01*
X-123497Y55D01*
X-123596Y1253D01*
X-123896Y2318D01*
X-124295Y3116D01*
X-124894Y3782D01*
X-125693Y4048D01*
G01X-117708D02*
X-118506Y3782D01*
X-119105Y3116D01*
X-119504Y2318D01*
X-119804Y1253D01*
X-119903Y55D01*
X-119804Y-1142D01*
X-119504Y-2207D01*
X-119105Y-3006D01*
X-118506Y-3671D01*
X-117708Y-3937D01*
X-116909Y-3671D01*
X-116310Y-3006D01*
X-115911Y-2207D01*
X-115611Y-1142D01*
X-115512Y55D01*
X-115611Y1253D01*
X-115911Y2318D01*
X-116310Y3116D01*
X-116909Y3782D01*
X-117708Y4048D01*
G01X-49030Y0D02*
X-124618D01*
G01X24550Y1992126D02*
X-124618D01*
G01X-84881Y-56732D02*
X-84026Y-55592D01*
X-83028Y-55021D01*
X-81887Y-54831D01*
X-80461Y-55211D01*
X-79463Y-56162D01*
X-79177Y-57302D01*
X-79320Y-58443D01*
X-79890Y-59394D01*
X-82742Y-61295D01*
X-84026Y-62626D01*
X-84881Y-64527D01*
X-85167Y-66238D01*
X-79177D01*
G01X-78740Y15000D02*
G03X-63740Y0I15000J0D01*
G01X-78740Y15000D02*
Y319646D01*
G01X-63740Y334646D02*
G03X-78740Y319646I0J-15000D01*
G01Y908315D02*
G03X-63740Y893315I15000J0D01*
G01X-78740Y908315D02*
Y1304286D01*
G01X-63740Y1319286D02*
G03X-78740Y1304286I0J-15000D01*
G01Y1892953D02*
G03X-63740Y1877953I15000J0D01*
G01X-78740Y1892953D02*
Y1977126D01*
G01Y1943898D02*
Y2064661D01*
G01X-63740Y1992126D02*
G03X-78740Y1977126I0J-15000D01*
G01X-82788Y2068010D02*
X-82522Y2067212D01*
X-81856Y2066613D01*
X-81058Y2066214D01*
X-79993Y2065914D01*
X-78795Y2065815D01*
X-77598Y2065914D01*
X-76533Y2066214D01*
X-75734Y2066613D01*
X-75069Y2067212D01*
X-74803Y2068010D01*
X-75069Y2068809D01*
X-75734Y2069408D01*
X-76533Y2069807D01*
X-77598Y2070107D01*
X-78795Y2070206D01*
X-79993Y2070107D01*
X-81058Y2069807D01*
X-81856Y2069408D01*
X-82522Y2068809D01*
X-82788Y2068010D01*
G01X-74537Y2075995D02*
X-74670Y2075796D01*
X-74936D01*
X-75069Y2075995D01*
X-74936Y2076195D01*
X-74670D01*
X-74537Y2075995D01*
G01X-82788Y2083980D02*
X-82522Y2083182D01*
X-81856Y2082583D01*
X-81058Y2082184D01*
X-79993Y2081884D01*
X-78795Y2081785D01*
X-77598Y2081884D01*
X-76533Y2082184D01*
X-75734Y2082583D01*
X-75069Y2083182D01*
X-74803Y2083980D01*
X-75069Y2084779D01*
X-75734Y2085378D01*
X-76533Y2085777D01*
X-77598Y2086077D01*
X-78795Y2086176D01*
X-79993Y2086077D01*
X-81058Y2085777D01*
X-81856Y2085378D01*
X-82522Y2084779D01*
X-82788Y2083980D01*
G01Y2091965D02*
X-82522Y2091167D01*
X-81856Y2090568D01*
X-81058Y2090169D01*
X-79993Y2089869D01*
X-78795Y2089770D01*
X-77598Y2089869D01*
X-76533Y2090169D01*
X-75734Y2090568D01*
X-75069Y2091167D01*
X-74803Y2091965D01*
X-75069Y2092764D01*
X-75734Y2093363D01*
X-76533Y2093762D01*
X-77598Y2094062D01*
X-78795Y2094161D01*
X-79993Y2094062D01*
X-81058Y2093762D01*
X-81856Y2093363D01*
X-82522Y2092764D01*
X-82788Y2091965D01*
G01X-84881Y2121023D02*
X-84026Y2122163D01*
X-83028Y2122734D01*
X-81887Y2122924D01*
X-80461Y2122544D01*
X-79463Y2121593D01*
X-79177Y2120453D01*
X-79320Y2119312D01*
X-79890Y2118361D01*
X-82742Y2116460D01*
X-84026Y2115129D01*
X-84881Y2113228D01*
X-85167Y2111517D01*
X-79177D01*
G01X-7874Y0D02*
X-63740D01*
G01X-46666Y39522D02*
X-30666D01*
G01X-46666Y55522D02*
Y39522D01*
G01Y55522D02*
X-30666D01*
G01X-7874Y334646D02*
X-63740D01*
G01X-7874Y893315D02*
X-63740D01*
G01X-7874Y1319286D02*
X-63740D01*
G01X-7874Y1877953D02*
X-63740D01*
G01X-45468Y1955630D02*
X-29468D01*
G01X-45468Y1939630D02*
X-29468D01*
G01X-45468Y1955630D02*
Y1939630D01*
G01X-7874Y1992126D02*
X-63740D01*
G01X-34145Y23634D02*
G03I-4292J0D01*
G01X-30666Y39522D02*
Y55522D01*
G01X-41166Y45022D02*
X-36166D01*
G01Y50022D02*
X-41166D01*
G01Y45022D02*
Y50022D01*
G01X-36166D02*
Y45022D01*
G01X-38666Y50022D02*
Y45022D01*
G01X-41166Y47522D02*
X-36166D01*
G01X-39607Y364601D02*
X-34602Y368104D01*
G01X-24843Y360270D02*
Y379916D01*
G01X-27992Y360270D02*
Y379916D01*
G01X-33701Y366136D02*
Y362199D01*
G01X-36811Y414628D02*
Y366558D01*
G01X-39607Y360270D02*
Y710624D01*
G01X-34602Y368104D02*
X-8898D01*
G01X-39607Y366136D02*
X-33701D01*
G01X-39607Y363419D02*
X-27992D01*
G01X-33701Y362199D02*
X-39607D01*
G01Y360270D02*
X-24843D01*
G01Y360230D02*
X-39607D01*
G01X0D02*
X-24843D01*
G01X-38108Y388174D02*
X-35350Y388439D01*
G01D02*
X-38108Y388174D01*
G01Y384237D02*
X-35350Y384502D01*
G01D02*
X-38108Y384237D01*
G01Y380300D02*
X-35350Y380565D01*
G01D02*
X-38108Y380300D01*
G01Y376363D02*
X-35350Y376628D01*
G01D02*
X-38108Y376363D01*
G01Y372426D02*
X-35350Y372691D01*
G01D02*
X-38108Y372426D01*
G01X-24121Y386818D02*
Y388564D01*
G01Y382881D02*
Y384627D01*
G01Y378944D02*
Y380690D01*
G01Y375007D02*
Y376753D01*
G01Y371070D02*
Y372816D01*
G01D02*
Y371070D01*
G01Y376753D02*
Y375007D01*
G01Y384627D02*
Y382881D01*
G01Y380690D02*
Y378944D01*
G01Y388564D02*
Y386818D01*
G01X-24508Y373124D02*
Y370762D01*
G01Y377061D02*
Y374699D01*
G01Y380998D02*
Y378636D01*
G01Y384935D02*
Y382573D01*
G01Y388872D02*
Y386510D01*
G01Y392809D02*
Y390447D01*
G01X-24843Y383892D02*
Y403538D01*
G01X-26565Y386845D02*
Y388537D01*
G01Y382908D02*
Y384600D01*
G01Y378971D02*
Y380663D01*
G01Y375034D02*
Y376726D01*
G01Y371097D02*
Y372789D01*
G01D02*
Y371097D01*
G01Y380663D02*
Y378971D01*
G01Y376726D02*
Y375034D01*
G01Y384600D02*
Y382908D01*
G01Y388537D02*
Y386845D01*
G01X-26942Y386849D02*
Y388533D01*
G01Y382912D02*
Y384596D01*
G01Y378975D02*
Y380659D01*
G01Y375038D02*
Y376722D01*
G01Y371101D02*
Y372785D01*
G01D02*
Y371101D01*
G01Y376722D02*
Y375038D01*
G01Y380659D02*
Y378975D01*
G01Y384596D02*
Y382912D01*
G01Y388533D02*
Y386849D01*
G01X-27264Y373124D02*
Y370762D01*
G01Y377061D02*
Y374699D01*
G01Y384935D02*
Y382573D01*
G01Y380998D02*
Y378636D01*
G01Y388872D02*
Y386510D01*
G01Y392809D02*
Y390447D01*
G01X-27992Y383892D02*
Y403538D01*
G01X-31941Y386905D02*
Y388477D01*
G01Y382968D02*
Y384540D01*
G01Y379031D02*
Y380603D01*
G01Y375094D02*
Y376666D01*
G01Y371157D02*
Y372729D01*
G01D02*
Y371157D01*
G01Y376666D02*
Y375094D01*
G01Y384540D02*
Y382968D01*
G01Y380603D02*
Y379031D01*
G01Y388477D02*
Y386905D01*
G01X-32318Y386909D02*
Y388473D01*
G01Y379035D02*
Y380599D01*
G01Y382972D02*
Y384536D01*
G01Y375098D02*
Y376662D01*
G01Y371161D02*
Y372725D01*
G01D02*
Y371161D01*
G01Y376662D02*
Y375098D01*
G01Y384536D02*
Y382972D01*
G01Y380599D02*
Y379035D01*
G01Y388473D02*
Y386909D01*
G01X-33153Y386919D02*
Y388464D01*
G01Y382982D02*
Y384527D01*
G01Y379045D02*
Y380590D01*
G01Y375108D02*
Y376653D01*
G01Y371171D02*
Y372716D01*
G01D02*
Y371171D01*
G01Y380590D02*
Y379045D01*
G01Y376653D02*
Y375108D01*
G01Y384527D02*
Y382982D01*
G01Y388464D02*
Y386919D01*
G01X-34136Y386930D02*
Y388453D01*
G01Y379056D02*
Y380579D01*
G01Y382993D02*
Y384516D01*
G01Y375119D02*
Y376642D01*
G01Y371182D02*
Y372705D01*
G01D02*
Y371182D01*
G01Y376642D02*
Y375119D01*
G01Y384516D02*
Y382993D01*
G01Y380579D02*
Y379056D01*
G01Y388453D02*
Y386930D01*
G01X-34607Y373045D02*
Y370841D01*
G01Y380919D02*
Y378715D01*
G01Y376982D02*
Y374778D01*
G01Y384856D02*
Y382652D01*
G01Y388793D02*
Y386589D01*
G01X-35357Y386944D02*
Y388439D01*
G01Y383007D02*
Y384502D01*
G01Y379070D02*
Y380565D01*
G01Y375133D02*
Y376628D01*
G01Y371196D02*
Y372691D01*
G01D02*
Y371196D01*
G01Y376628D02*
Y375133D01*
G01Y380565D02*
Y379070D01*
G01Y384502D02*
Y383007D01*
G01Y388439D02*
Y386944D01*
G01X-35545Y373124D02*
Y370762D01*
G01Y377061D02*
Y374699D01*
G01Y380998D02*
Y378636D01*
G01Y384935D02*
Y382573D01*
G01Y388872D02*
Y386510D01*
G01Y392809D02*
Y390447D01*
G01X-35594Y386967D02*
Y388416D01*
G01Y383030D02*
Y384478D01*
G01Y379093D02*
Y380541D01*
G01Y375156D02*
Y376604D01*
G01Y371219D02*
Y372667D01*
G01D02*
Y371219D01*
G01Y380541D02*
Y379093D01*
G01Y376604D02*
Y375156D01*
G01Y384478D02*
Y383030D01*
G01Y388416D02*
Y386967D01*
G01X-37870Y387186D02*
Y388197D01*
G01Y383249D02*
Y384260D01*
G01Y375375D02*
Y376386D01*
G01Y379312D02*
Y380323D01*
G01Y371438D02*
Y372449D01*
G01D02*
Y371438D01*
G01Y380323D02*
Y379312D01*
G01Y376386D02*
Y375375D01*
G01Y384260D02*
Y383249D01*
G01Y388197D02*
Y387186D01*
G01X-38108Y387209D02*
Y388174D01*
G01Y383272D02*
Y384237D01*
G01Y375398D02*
Y376363D01*
G01Y379335D02*
Y380300D01*
G01Y371461D02*
Y372426D01*
G01D02*
Y371461D01*
G01Y380300D02*
Y379335D01*
G01Y376363D02*
Y375398D01*
G01Y384237D02*
Y383272D01*
G01Y388174D02*
Y387209D01*
G01X-38425Y373124D02*
Y370762D01*
G01Y377061D02*
Y374699D01*
G01Y380998D02*
Y378636D01*
G01Y384935D02*
Y382573D01*
G01Y388872D02*
Y386510D01*
G01Y392809D02*
Y390447D01*
G01X-38108Y387209D02*
X-35350Y386943D01*
G01X-38108Y387209D02*
X-35350Y386943D01*
G01X-38108Y383272D02*
X-35350Y383006D01*
G01X-38108Y383272D02*
X-35350Y383006D01*
G01X-38108Y379335D02*
X-35350Y379069D01*
G01X-38108Y379335D02*
X-35350Y379069D01*
G01X-38108Y375398D02*
X-35350Y375132D01*
G01X-38108Y375398D02*
X-35350Y375132D01*
G01X-38108Y371461D02*
X-35350Y371195D01*
G01X-38108Y371461D02*
X-35350Y371195D01*
G01Y386943D02*
X-10630Y386667D01*
G01D02*
X-35350Y386943D01*
G01Y383006D02*
X-10630Y382730D01*
G01D02*
X-35350Y383006D01*
G01Y379069D02*
X-10630Y378793D01*
G01D02*
X-35350Y379069D01*
G01Y375132D02*
X-10630Y374856D01*
G01D02*
X-35350Y375132D01*
G01Y371195D02*
X-10630Y370919D01*
G01D02*
X-35350Y371195D01*
G01X-39607Y390447D02*
X-24508D01*
G01Y388872D02*
X-39607D01*
G01X-35545Y388793D02*
X0D01*
G01X-39607Y387041D02*
X-27992D01*
G01X-35545Y386589D02*
X0D01*
G01X-39607Y386510D02*
X-24508D01*
G01Y384935D02*
X-39607D01*
G01X-35545Y384856D02*
X0D01*
G01X-39607Y383892D02*
X-24843D01*
G01X-35545Y382652D02*
X0D01*
G01X-39607Y382573D02*
X-24508D01*
G01Y380998D02*
X-39607D01*
G01X-35545Y380919D02*
X0D01*
G01X-39607Y379916D02*
X-24843D01*
G01X-35545Y378715D02*
X0D01*
G01X-39607Y378636D02*
X-24508D01*
G01Y377061D02*
X-39607D01*
G01X-35545Y376982D02*
X0D01*
G01X-27992Y376766D02*
X-39607D01*
G01X-35545Y374778D02*
X0D01*
G01X-39607Y374699D02*
X-24508D01*
G01Y373124D02*
X-39607D01*
G01X-35545Y373045D02*
X0D01*
G01X-35545Y370841D02*
X0D01*
G01X-39607Y370762D02*
X-24508D01*
G01X-35350Y388439D02*
X-10630Y388715D01*
G01X-35350Y388439D02*
X-10630Y388715D01*
G01X-35350Y384502D02*
X-10630Y384778D01*
G01X-35350Y384502D02*
X-10630Y384778D01*
G01X-35350Y380565D02*
X-10630Y380841D01*
G01X-35350Y380565D02*
X-10630Y380841D01*
G01X-35350Y376628D02*
X-10630Y376904D01*
G01X-35350Y376628D02*
X-10630Y376904D01*
G01X-35350Y372691D02*
X-10630Y372967D01*
G01X-35350Y372691D02*
X-10630Y372967D01*
G01X-35350Y410565D02*
X-10630Y410290D01*
G01D02*
X-35350Y410565D01*
G01Y406628D02*
X-10630Y406353D01*
G01D02*
X-35350Y406628D01*
G01X-39607Y410664D02*
X-27992D01*
G01X-35545Y410211D02*
X0D01*
G01X-39607Y410132D02*
X-24508D01*
G01Y408557D02*
X-39607D01*
G01X-35545Y408478D02*
X0D01*
G01X-39607Y407514D02*
X-24843D01*
G01X-35545Y406274D02*
X0D01*
G01X-39607Y406195D02*
X-24508D01*
G01Y404620D02*
X-39607D01*
G01X-35545Y404541D02*
X0D01*
G01X-39607Y403538D02*
X-24843D01*
G01X-35545Y402337D02*
X0D01*
G01X-39607Y402258D02*
X-24508D01*
G01Y400683D02*
X-39607D01*
G01X-35545Y400604D02*
X0D01*
G01X-27992Y400388D02*
X-39607D01*
G01X-35545Y398400D02*
X0D01*
G01X-39607Y398321D02*
X-24508D01*
G01X-35350Y408124D02*
X-10630Y408400D01*
G01X-35350Y408124D02*
X-10630Y408400D01*
G01X-35350Y404187D02*
X-10630Y404463D01*
G01X-35350Y404187D02*
X-10630Y404463D01*
G01X-35350Y400250D02*
X-10630Y400526D01*
G01X-35350Y400250D02*
X-10630Y400526D01*
G01X-35350Y396313D02*
X-10630Y396589D01*
G01X-35350Y396313D02*
X-10630Y396589D01*
G01X-35350Y392376D02*
X-10630Y392652D01*
G01X-35350Y392376D02*
X-10630Y392652D01*
G01X-38108Y407859D02*
X-35350Y408124D01*
G01D02*
X-38108Y407859D01*
G01Y403922D02*
X-35350Y404187D01*
G01D02*
X-38108Y403922D01*
G01Y399985D02*
X-35350Y400250D01*
G01D02*
X-38108Y399985D01*
G01Y396048D02*
X-35350Y396313D01*
G01D02*
X-38108Y396048D01*
G01Y392111D02*
X-35350Y392376D01*
G01D02*
X-38108Y392111D01*
G01X-24121Y410440D02*
Y412186D01*
G01Y406503D02*
Y408249D01*
G01Y402566D02*
Y404312D01*
G01Y398629D02*
Y400375D01*
G01Y394692D02*
Y396438D01*
G01Y390755D02*
Y392501D01*
G01D02*
Y390755D01*
G01Y396438D02*
Y394692D01*
G01Y400375D02*
Y398629D01*
G01Y408249D02*
Y406503D01*
G01Y404312D02*
Y402566D01*
G01Y412186D02*
Y410440D01*
G01X-24508Y396746D02*
Y394384D01*
G01Y400683D02*
Y398321D01*
G01Y404620D02*
Y402258D01*
G01Y408557D02*
Y406195D01*
G01Y412494D02*
Y410132D01*
G01X-24843Y407514D02*
Y427160D01*
G01X-26565Y410467D02*
Y412159D01*
G01Y406530D02*
Y408222D01*
G01Y402593D02*
Y404285D01*
G01Y398656D02*
Y400348D01*
G01Y394719D02*
Y396411D01*
G01Y390782D02*
Y392474D01*
G01D02*
Y390782D01*
G01Y396411D02*
Y394719D01*
G01Y404285D02*
Y402593D01*
G01Y400348D02*
Y398656D01*
G01Y408222D02*
Y406530D01*
G01Y412159D02*
Y410467D01*
G01X-26942Y410471D02*
Y412155D01*
G01Y406534D02*
Y408218D01*
G01Y402597D02*
Y404281D01*
G01Y398660D02*
Y400344D01*
G01Y394723D02*
Y396407D01*
G01Y390786D02*
Y392470D01*
G01D02*
Y390786D01*
G01Y396407D02*
Y394723D01*
G01Y400344D02*
Y398660D01*
G01Y408218D02*
Y406534D01*
G01Y404281D02*
Y402597D01*
G01Y412155D02*
Y410471D01*
G01X-27264Y396746D02*
Y394384D01*
G01Y400683D02*
Y398321D01*
G01Y408557D02*
Y406195D01*
G01Y404620D02*
Y402258D01*
G01Y412494D02*
Y410132D01*
G01X-27992Y407514D02*
Y427160D01*
G01X-31941Y410527D02*
Y412099D01*
G01Y406590D02*
Y408162D01*
G01Y402653D02*
Y404225D01*
G01Y398716D02*
Y400288D01*
G01Y394779D02*
Y396351D01*
G01Y390842D02*
Y392414D01*
G01D02*
Y390842D01*
G01Y396351D02*
Y394779D01*
G01Y400288D02*
Y398716D01*
G01Y408162D02*
Y406590D01*
G01Y404225D02*
Y402653D01*
G01Y412099D02*
Y410527D01*
G01X-32318Y410531D02*
Y412095D01*
G01Y406594D02*
Y408158D01*
G01Y402657D02*
Y404221D01*
G01Y398720D02*
Y400284D01*
G01Y394783D02*
Y396347D01*
G01Y390846D02*
Y392410D01*
G01D02*
Y390846D01*
G01Y396347D02*
Y394783D01*
G01Y400284D02*
Y398720D01*
G01Y408158D02*
Y406594D01*
G01Y404221D02*
Y402657D01*
G01Y412095D02*
Y410531D01*
G01X-33153Y410541D02*
Y412086D01*
G01Y406604D02*
Y408149D01*
G01Y402667D02*
Y404212D01*
G01Y398730D02*
Y400275D01*
G01Y394793D02*
Y396338D01*
G01Y390856D02*
Y392401D01*
G01D02*
Y390856D01*
G01Y396338D02*
Y394793D01*
G01Y404212D02*
Y402667D01*
G01Y400275D02*
Y398730D01*
G01Y408149D02*
Y406604D01*
G01Y412086D02*
Y410541D01*
G01X-34136Y410552D02*
Y412075D01*
G01Y406615D02*
Y408138D01*
G01Y402678D02*
Y404201D01*
G01Y398741D02*
Y400264D01*
G01Y394804D02*
Y396327D01*
G01Y390867D02*
Y392390D01*
G01D02*
Y390867D01*
G01Y396327D02*
Y394804D01*
G01Y400264D02*
Y398741D01*
G01Y408138D02*
Y406615D01*
G01Y404201D02*
Y402678D01*
G01Y412075D02*
Y410552D01*
G01X-34607Y410211D02*
Y412416D01*
G01Y392730D02*
Y390526D01*
G01Y396667D02*
Y394463D01*
G01Y404541D02*
Y402337D01*
G01Y400604D02*
Y398400D01*
G01Y408478D02*
Y406274D01*
G01X-35357Y410566D02*
Y412061D01*
G01Y406629D02*
Y408124D01*
G01Y402692D02*
Y404187D01*
G01Y398755D02*
Y400250D01*
G01Y394818D02*
Y396313D01*
G01Y390881D02*
Y392376D01*
G01D02*
Y390881D01*
G01Y396313D02*
Y394818D01*
G01Y400250D02*
Y398755D01*
G01Y408124D02*
Y406629D01*
G01Y404187D02*
Y402692D01*
G01Y412061D02*
Y410566D01*
G01X-35545Y396746D02*
Y394384D01*
G01Y400683D02*
Y398321D01*
G01Y404620D02*
Y402258D01*
G01Y408557D02*
Y406195D01*
G01Y412494D02*
Y410132D01*
G01X-35594Y410589D02*
Y412038D01*
G01Y406652D02*
Y408101D01*
G01Y402715D02*
Y404164D01*
G01Y398778D02*
Y400227D01*
G01Y394841D02*
Y396290D01*
G01Y390904D02*
Y392353D01*
G01D02*
Y390904D01*
G01Y396290D02*
Y394841D01*
G01Y404164D02*
Y402715D01*
G01Y400227D02*
Y398778D01*
G01Y408101D02*
Y406652D01*
G01Y412038D02*
Y410589D01*
G01X-37870Y410808D02*
Y411819D01*
G01Y406871D02*
Y407882D01*
G01Y402934D02*
Y403945D01*
G01Y398997D02*
Y400008D01*
G01Y395060D02*
Y396071D01*
G01Y391123D02*
Y392134D01*
G01D02*
Y391123D01*
G01Y396071D02*
Y395060D01*
G01Y400008D02*
Y398997D01*
G01Y407882D02*
Y406871D01*
G01Y403945D02*
Y402934D01*
G01Y411819D02*
Y410808D01*
G01X-38108Y410831D02*
Y411796D01*
G01Y406894D02*
Y407859D01*
G01Y402957D02*
Y403922D01*
G01Y399020D02*
Y399985D01*
G01Y395083D02*
Y396048D01*
G01Y391146D02*
Y392111D01*
G01D02*
Y391146D01*
G01Y396048D02*
Y395083D01*
G01Y403922D02*
Y402957D01*
G01Y399985D02*
Y399020D01*
G01Y407859D02*
Y406894D01*
G01Y411796D02*
Y410831D01*
G01X-38425Y396746D02*
Y394384D01*
G01Y404620D02*
Y402258D01*
G01Y400683D02*
Y398321D01*
G01Y408557D02*
Y406195D01*
G01Y412494D02*
Y410132D01*
G01X-38108Y410831D02*
X-35350Y410565D01*
G01X-38108Y410831D02*
X-35350Y410565D01*
G01X-38108Y406894D02*
X-35350Y406628D01*
G01X-38108Y406894D02*
X-35350Y406628D01*
G01X-38108Y402957D02*
X-35350Y402691D01*
G01X-38108Y402957D02*
X-35350Y402691D01*
G01X-38108Y399020D02*
X-35350Y398754D01*
G01X-38108Y399020D02*
X-35350Y398754D01*
G01X-38108Y395083D02*
X-35350Y394817D01*
G01X-38108Y395083D02*
X-35350Y394817D01*
G01X-38108Y391146D02*
X-35350Y390880D01*
G01X-38108Y391146D02*
X-35350Y390880D01*
G01Y402691D02*
X-10630Y402416D01*
G01D02*
X-35350Y402691D01*
G01Y398754D02*
X-10630Y398478D01*
G01D02*
X-35350Y398754D01*
G01Y394817D02*
X-10630Y394541D01*
G01D02*
X-35350Y394817D01*
G01Y390880D02*
X-10630Y390604D01*
G01D02*
X-35350Y390880D01*
G01X-24508Y396746D02*
X-39607D01*
G01X-35545Y396667D02*
X0D01*
G01X-35545Y394463D02*
X0D01*
G01X-39607Y394384D02*
X-24508D01*
G01Y392809D02*
X-39607D01*
G01X-35545Y392730D02*
X0D01*
G01X-35545Y390526D02*
X0D01*
G01X-39019Y418432D02*
G03Y416174I790J-1129D01*
G01X-34844Y420723D02*
G03X-36560Y420182I0J-2992D01*
G01Y414453D02*
G03X-34844Y413912I1716J2451D01*
G01X-39019Y418460D02*
X-36560Y420182D01*
G01X-38108Y431481D02*
X-35350Y431746D01*
G01D02*
X-38108Y431481D01*
G01Y427544D02*
X-35350Y427809D01*
G01D02*
X-38108Y427544D01*
G01Y423607D02*
X-35350Y423872D01*
G01D02*
X-38108Y423607D01*
G01X-35350Y430250D02*
X-10630Y429975D01*
G01D02*
X-35350Y430250D01*
G01Y426313D02*
X-10630Y426038D01*
G01D02*
X-35350Y426313D01*
G01Y422376D02*
X-10630Y422101D01*
G01D02*
X-35350Y422376D01*
G01X-24508Y432179D02*
X-39607D01*
G01X-35545Y432101D02*
X0D01*
G01X-39607Y431136D02*
X-24843D01*
G01X-35545Y429896D02*
X0D01*
G01X-39607Y429817D02*
X-24508D01*
G01Y428242D02*
X-39607D01*
G01X-35545Y428164D02*
X0D01*
G01X-39607Y427160D02*
X-24843D01*
G01X-35545Y425959D02*
X0D01*
G01X-39607Y425880D02*
X-24508D01*
G01Y424305D02*
X-39607D01*
G01X-35545Y424227D02*
X0D01*
G01X-27992Y424010D02*
X-39607D01*
G01X-35545Y422022D02*
X0D01*
G01X-39607Y421943D02*
X-24508D01*
G01X-34844Y420723D02*
X-8898D01*
G01X0Y419719D02*
X-35433D01*
G01Y414719D02*
X0D01*
G01X-8898Y413912D02*
X-34844D01*
G01X-24508Y412494D02*
X-39607D01*
G01X-35545Y412416D02*
X0D01*
G01X-35350Y431746D02*
X-10630Y432022D01*
G01X-35350Y431746D02*
X-10630Y432022D01*
G01X-35350Y427809D02*
X-10630Y428085D01*
G01X-35350Y427809D02*
X-10630Y428085D01*
G01X-35350Y423872D02*
X-10630Y424148D01*
G01X-35350Y423872D02*
X-10630Y424148D01*
G01X-35350Y412061D02*
X-10630Y412337D01*
G01X-35350Y412061D02*
X-10630Y412337D01*
G01X-38108Y411796D02*
X-35350Y412061D01*
G01D02*
X-38108Y411796D01*
G01X-24121Y430125D02*
Y431871D01*
G01Y426188D02*
Y427934D01*
G01Y422251D02*
Y423997D01*
G01D02*
Y422251D01*
G01Y431871D02*
Y430125D01*
G01Y427934D02*
Y426188D01*
G01X-24508Y424305D02*
Y421943D01*
G01Y428242D02*
Y425880D01*
G01Y432179D02*
Y429817D01*
G01X-24843Y431136D02*
Y450782D01*
G01X-26565Y430152D02*
Y431844D01*
G01Y426215D02*
Y427907D01*
G01Y422278D02*
Y423970D01*
G01Y427907D02*
Y426215D01*
G01Y423970D02*
Y422278D01*
G01Y431844D02*
Y430152D01*
G01X-26942Y430156D02*
Y431840D01*
G01Y426219D02*
Y427903D01*
G01Y422282D02*
Y423966D01*
G01D02*
Y422282D01*
G01Y427903D02*
Y426219D01*
G01Y431840D02*
Y430156D01*
G01X-27264Y424305D02*
Y421943D01*
G01Y428242D02*
Y425880D01*
G01Y432179D02*
Y429817D01*
G01X-27992Y431136D02*
Y450782D01*
G01X-31941Y430212D02*
Y431784D01*
G01Y426275D02*
Y427847D01*
G01Y422338D02*
Y423910D01*
G01D02*
Y422338D01*
G01Y431784D02*
Y430212D01*
G01Y427847D02*
Y426275D01*
G01X-32318Y426279D02*
Y427843D01*
G01Y430216D02*
Y431780D01*
G01Y422342D02*
Y423906D01*
G01D02*
Y422342D01*
G01Y431780D02*
Y430216D01*
G01Y427843D02*
Y426279D01*
G01X-33153Y430226D02*
Y431771D01*
G01Y426289D02*
Y427834D01*
G01Y422352D02*
Y423897D01*
G01Y427834D02*
Y426289D01*
G01Y423897D02*
Y422352D01*
G01Y431771D02*
Y430226D01*
G01X-34136Y426300D02*
Y427823D01*
G01Y430237D02*
Y431760D01*
G01Y422363D02*
Y423886D01*
G01D02*
Y422363D01*
G01Y431760D02*
Y430237D01*
G01Y427823D02*
Y426300D01*
G01X-34607Y422022D02*
Y424227D01*
G01Y428164D02*
Y425959D01*
G01Y432101D02*
Y429896D01*
G01X-35357Y430251D02*
Y431746D01*
G01Y426314D02*
Y427809D01*
G01Y422377D02*
Y423872D01*
G01D02*
Y422377D01*
G01Y427809D02*
Y426314D01*
G01Y431746D02*
Y430251D01*
G01X-35433Y419719D02*
Y414719D01*
G01X-35545Y424305D02*
Y421943D01*
G01Y428242D02*
Y425880D01*
G01Y432179D02*
Y429817D01*
G01X-35594Y430274D02*
Y431723D01*
G01Y426337D02*
Y427786D01*
G01Y422400D02*
Y423849D01*
G01Y427786D02*
Y426337D01*
G01Y423849D02*
Y422400D01*
G01Y431723D02*
Y430274D01*
G01X-36811Y703664D02*
Y420006D01*
G01X-37870Y426556D02*
Y427567D01*
G01Y430493D02*
Y431504D01*
G01Y422619D02*
Y423630D01*
G01D02*
Y422619D01*
G01Y431504D02*
Y430493D01*
G01Y427567D02*
Y426556D01*
G01X-38108Y426579D02*
Y427544D01*
G01Y430516D02*
Y431481D01*
G01Y422642D02*
Y423607D01*
G01Y427544D02*
Y426579D01*
G01Y423607D02*
Y422642D01*
G01Y431481D02*
Y430516D01*
G01X-38425Y424305D02*
Y421943D01*
G01Y428242D02*
Y425880D01*
G01Y432179D02*
Y429817D01*
G01X-38108Y430516D02*
X-35350Y430250D01*
G01X-38108Y430516D02*
X-35350Y430250D01*
G01X-38108Y426579D02*
X-35350Y426313D01*
G01X-38108Y426579D02*
X-35350Y426313D01*
G01X-38108Y422642D02*
X-35350Y422376D01*
G01X-38108Y422642D02*
X-35350Y422376D01*
G01X-36560Y414453D02*
X-39019Y416174D01*
G01X-38108Y451166D02*
X-35350Y451431D01*
G01D02*
X-38108Y451166D01*
G01Y447229D02*
X-35350Y447494D01*
G01D02*
X-38108Y447229D01*
G01Y443292D02*
X-35350Y443557D01*
G01D02*
X-38108Y443292D01*
G01Y439355D02*
X-35350Y439620D01*
G01D02*
X-38108Y439355D01*
G01Y435418D02*
X-35350Y435683D01*
G01D02*
X-38108Y435418D01*
G01Y454138D02*
X-35350Y453872D01*
G01X-38108Y454138D02*
X-35350Y453872D01*
G01X-38108Y450201D02*
X-35350Y449935D01*
G01X-38108Y450201D02*
X-35350Y449935D01*
G01Y453872D02*
X-10630Y453597D01*
G01D02*
X-35350Y453872D01*
G01Y449935D02*
X-10630Y449660D01*
G01D02*
X-35350Y449935D01*
G01Y445998D02*
X-10630Y445723D01*
G01D02*
X-35350Y445998D01*
G01Y442061D02*
X-10630Y441786D01*
G01D02*
X-35350Y442061D01*
G01Y438124D02*
X-10630Y437849D01*
G01D02*
X-35350Y438124D01*
G01Y434187D02*
X-10630Y433912D01*
G01D02*
X-35350Y434187D01*
G01X-35545Y453518D02*
X0D01*
G01X-39607Y453439D02*
X-24508D01*
G01Y451864D02*
X-39607D01*
G01X-35545Y451786D02*
X0D01*
G01X-39607Y450782D02*
X-24843D01*
G01X-35545Y449581D02*
X0D01*
G01X-39607Y449502D02*
X-24508D01*
G01Y447927D02*
X-39607D01*
G01X-35545Y447849D02*
X0D01*
G01X-27992Y447632D02*
X-39607D01*
G01X-35545Y445644D02*
X0D01*
G01X-39607Y445565D02*
X-24508D01*
G01Y443990D02*
X-39607D01*
G01X-35545Y443912D02*
X0D01*
G01X-35545Y441707D02*
X0D01*
G01X-39607Y441628D02*
X-24508D01*
G01Y440053D02*
X-39607D01*
G01X-35545Y439975D02*
X0D01*
G01X-35545Y437770D02*
X0D01*
G01X-39607Y437691D02*
X-24508D01*
G01Y436116D02*
X-39607D01*
G01X-35545Y436038D02*
X0D01*
G01X-39607Y434286D02*
X-27992D01*
G01X-35545Y433833D02*
X0D01*
G01X-39607Y433754D02*
X-24508D01*
G01X-35350Y451431D02*
X-10630Y451707D01*
G01X-35350Y451431D02*
X-10630Y451707D01*
G01X-35350Y447494D02*
X-10630Y447770D01*
G01X-35350Y447494D02*
X-10630Y447770D01*
G01X-35350Y443557D02*
X-10630Y443833D01*
G01X-35350Y443557D02*
X-10630Y443833D01*
G01X-35350Y439620D02*
X-10630Y439896D01*
G01X-35350Y439620D02*
X-10630Y439896D01*
G01X-35350Y435683D02*
X-10630Y435959D01*
G01X-35350Y435683D02*
X-10630Y435959D01*
G01X-24121Y453747D02*
Y455493D01*
G01Y449810D02*
Y451556D01*
G01Y445873D02*
Y447619D01*
G01Y441936D02*
Y443682D01*
G01Y437999D02*
Y439745D01*
G01Y434062D02*
Y435808D01*
G01D02*
Y434062D01*
G01Y439745D02*
Y437999D01*
G01Y443682D02*
Y441936D01*
G01Y447619D02*
Y445873D01*
G01Y451556D02*
Y449810D01*
G01Y455493D02*
Y453747D01*
G01X-24508Y436116D02*
Y433754D01*
G01Y440053D02*
Y437691D01*
G01Y443990D02*
Y441628D01*
G01Y447927D02*
Y445565D01*
G01Y451864D02*
Y449502D01*
G01Y455801D02*
Y453439D01*
G01X-26565Y453774D02*
Y455466D01*
G01Y449837D02*
Y451529D01*
G01Y445900D02*
Y447592D01*
G01Y441963D02*
Y443655D01*
G01Y438026D02*
Y439718D01*
G01Y434089D02*
Y435781D01*
G01D02*
Y434089D01*
G01Y439718D02*
Y438026D01*
G01Y443655D02*
Y441963D01*
G01Y447592D02*
Y445900D01*
G01Y451529D02*
Y449837D01*
G01Y455466D02*
Y453774D01*
G01X-26942Y453778D02*
Y455462D01*
G01Y449841D02*
Y451525D01*
G01Y445904D02*
Y447588D01*
G01Y441967D02*
Y443651D01*
G01Y438030D02*
Y439714D01*
G01Y434093D02*
Y435777D01*
G01D02*
Y434093D01*
G01Y439714D02*
Y438030D01*
G01Y443651D02*
Y441967D01*
G01Y447588D02*
Y445904D01*
G01Y451525D02*
Y449841D01*
G01Y455462D02*
Y453778D01*
G01X-27264Y436116D02*
Y433754D01*
G01Y440053D02*
Y437691D01*
G01Y443990D02*
Y441628D01*
G01Y447927D02*
Y445565D01*
G01Y451864D02*
Y449502D01*
G01Y455801D02*
Y453439D01*
G01X-31941Y449897D02*
Y451469D01*
G01Y453834D02*
Y455406D01*
G01Y445960D02*
Y447532D01*
G01Y442023D02*
Y443595D01*
G01Y438086D02*
Y439658D01*
G01Y434149D02*
Y435721D01*
G01D02*
Y434149D01*
G01Y439658D02*
Y438086D01*
G01Y443595D02*
Y442023D01*
G01Y447532D02*
Y445960D01*
G01Y455406D02*
Y453834D01*
G01Y451469D02*
Y449897D01*
G01X-32318Y449901D02*
Y451465D01*
G01Y453838D02*
Y455402D01*
G01Y445964D02*
Y447528D01*
G01Y442027D02*
Y443591D01*
G01Y438090D02*
Y439654D01*
G01Y434153D02*
Y435717D01*
G01D02*
Y434153D01*
G01Y439654D02*
Y438090D01*
G01Y443591D02*
Y442027D01*
G01Y447528D02*
Y445964D01*
G01Y455402D02*
Y453838D01*
G01Y451465D02*
Y449901D01*
G01X-33153Y453848D02*
Y455393D01*
G01Y449911D02*
Y451456D01*
G01Y445974D02*
Y447519D01*
G01Y442037D02*
Y443582D01*
G01Y438100D02*
Y439645D01*
G01Y434163D02*
Y435708D01*
G01D02*
Y434163D01*
G01Y439645D02*
Y438100D01*
G01Y443582D02*
Y442037D01*
G01Y447519D02*
Y445974D01*
G01Y451456D02*
Y449911D01*
G01Y455393D02*
Y453848D01*
G01X-34136Y449922D02*
Y451445D01*
G01Y453859D02*
Y455382D01*
G01Y445985D02*
Y447508D01*
G01Y442048D02*
Y443571D01*
G01Y438111D02*
Y439634D01*
G01Y434174D02*
Y435697D01*
G01D02*
Y434174D01*
G01Y439634D02*
Y438111D01*
G01Y443571D02*
Y442048D01*
G01Y447508D02*
Y445985D01*
G01Y455382D02*
Y453859D01*
G01Y451445D02*
Y449922D01*
G01X-34607Y436038D02*
Y433833D01*
G01Y439975D02*
Y437770D01*
G01Y443912D02*
Y441707D01*
G01Y447849D02*
Y445644D01*
G01Y455723D02*
Y453518D01*
G01Y451786D02*
Y449581D01*
G01X-35357Y453873D02*
Y455368D01*
G01Y449936D02*
Y451431D01*
G01Y445999D02*
Y447494D01*
G01Y442062D02*
Y443557D01*
G01Y438125D02*
Y439620D01*
G01Y434188D02*
Y435683D01*
G01D02*
Y434188D01*
G01Y439620D02*
Y438125D01*
G01Y443557D02*
Y442062D01*
G01Y447494D02*
Y445999D01*
G01Y451431D02*
Y449936D01*
G01Y455368D02*
Y453873D01*
G01X-35545Y436116D02*
Y433754D01*
G01Y440053D02*
Y437691D01*
G01Y443990D02*
Y441628D01*
G01Y447927D02*
Y445565D01*
G01Y451864D02*
Y449502D01*
G01Y455801D02*
Y453439D01*
G01X-35594Y453896D02*
Y455345D01*
G01Y449959D02*
Y451408D01*
G01Y446022D02*
Y447471D01*
G01Y442085D02*
Y443534D01*
G01Y438148D02*
Y439597D01*
G01Y434211D02*
Y435660D01*
G01D02*
Y434211D01*
G01Y439597D02*
Y438148D01*
G01Y443534D02*
Y442085D01*
G01Y447471D02*
Y446022D01*
G01Y451408D02*
Y449959D01*
G01Y455345D02*
Y453896D01*
G01X-37870Y450178D02*
Y451189D01*
G01Y446241D02*
Y447252D01*
G01Y442304D02*
Y443315D01*
G01Y438367D02*
Y439378D01*
G01Y434430D02*
Y435441D01*
G01D02*
Y434430D01*
G01Y439378D02*
Y438367D01*
G01Y443315D02*
Y442304D01*
G01Y447252D02*
Y446241D01*
G01Y451189D02*
Y450178D01*
G01X-38108Y450201D02*
Y451166D01*
G01Y446264D02*
Y447229D01*
G01Y442327D02*
Y443292D01*
G01Y438390D02*
Y439355D01*
G01Y434453D02*
Y435418D01*
G01D02*
Y434453D01*
G01Y439355D02*
Y438390D01*
G01Y443292D02*
Y442327D01*
G01Y447229D02*
Y446264D01*
G01Y451166D02*
Y450201D01*
G01X-38425Y436116D02*
Y433754D01*
G01Y440053D02*
Y437691D01*
G01Y443990D02*
Y441628D01*
G01Y447927D02*
Y445565D01*
G01Y455801D02*
Y453439D01*
G01Y451864D02*
Y449502D01*
G01X-38108Y446264D02*
X-35350Y445998D01*
G01X-38108Y446264D02*
X-35350Y445998D01*
G01X-38108Y442327D02*
X-35350Y442061D01*
G01X-38108Y442327D02*
X-35350Y442061D01*
G01X-38108Y438390D02*
X-35350Y438124D01*
G01X-38108Y438390D02*
X-35350Y438124D01*
G01X-38108Y434453D02*
X-35350Y434187D01*
G01X-38108Y434453D02*
X-35350Y434187D01*
G01X-39607Y474404D02*
X-24843D01*
G01X-35545Y473203D02*
X0D01*
G01X-35350Y475053D02*
X-10630Y475329D01*
G01X-35350Y475053D02*
X-10630Y475329D01*
G01X-35350Y471116D02*
X-10630Y471392D01*
G01X-35350Y471116D02*
X-10630Y471392D01*
G01X-35350Y467179D02*
X-10630Y467455D01*
G01X-35350Y467179D02*
X-10630Y467455D01*
G01X-38108Y474788D02*
X-35350Y475053D01*
G01D02*
X-38108Y474788D01*
G01Y470851D02*
X-35350Y471116D01*
G01D02*
X-38108Y470851D01*
G01Y466914D02*
X-35350Y467179D01*
G01D02*
X-38108Y466914D01*
G01Y462977D02*
X-35350Y463242D01*
G01D02*
X-38108Y462977D01*
G01Y459040D02*
X-35350Y459305D01*
G01D02*
X-38108Y459040D01*
G01Y455103D02*
X-35350Y455368D01*
G01D02*
X-38108Y455103D01*
G01Y473823D02*
X-35350Y473557D01*
G01X-38108Y473823D02*
X-35350Y473557D01*
G01X-38108Y469886D02*
X-35350Y469620D01*
G01X-38108Y469886D02*
X-35350Y469620D01*
G01X-38108Y465949D02*
X-35350Y465683D01*
G01X-38108Y465949D02*
X-35350Y465683D01*
G01X-38108Y462012D02*
X-35350Y461746D01*
G01X-38108Y462012D02*
X-35350Y461746D01*
G01X-38108Y458075D02*
X-35350Y457809D01*
G01X-38108Y458075D02*
X-35350Y457809D01*
G01Y473557D02*
X-10630Y473282D01*
G01D02*
X-35350Y473557D01*
G01Y469620D02*
X-10630Y469345D01*
G01D02*
X-35350Y469620D01*
G01Y465683D02*
X-10630Y465408D01*
G01D02*
X-35350Y465683D01*
G01Y461746D02*
X-10630Y461471D01*
G01D02*
X-35350Y461746D01*
G01Y457809D02*
X-10630Y457534D01*
G01D02*
X-35350Y457809D01*
G01X-39607Y473124D02*
X-24508D01*
G01Y471549D02*
X-39607D01*
G01X-35545Y471471D02*
X0D01*
G01X-27992Y471254D02*
X-39607D01*
G01X-35545Y469266D02*
X0D01*
G01X-39607Y469187D02*
X-24508D01*
G01Y467612D02*
X-39607D01*
G01X-35545Y467534D02*
X0D01*
G01X-35545Y465329D02*
X0D01*
G01X-39607Y465250D02*
X-24508D01*
G01Y463675D02*
X-39607D01*
G01X-35545Y463597D02*
X0D01*
G01X-35545Y461392D02*
X0D01*
G01X-39607Y461313D02*
X-24508D01*
G01Y459738D02*
X-39607D01*
G01X-35545Y459660D02*
X0D01*
G01X-39607Y457908D02*
X-27992D01*
G01X-35545Y457455D02*
X0D01*
G01X-39607Y457376D02*
X-24508D01*
G01Y455801D02*
X-39607D01*
G01X-35545Y455723D02*
X0D01*
G01X-39607Y454758D02*
X-24843D01*
G01X-35350Y463242D02*
X-10630Y463518D01*
G01X-35350Y463242D02*
X-10630Y463518D01*
G01X-35350Y459305D02*
X-10630Y459581D01*
G01X-35350Y459305D02*
X-10630Y459581D01*
G01X-35350Y455368D02*
X-10630Y455644D01*
G01X-35350Y455368D02*
X-10630Y455644D01*
G01X-24121Y473432D02*
Y475178D01*
G01Y469495D02*
Y471241D01*
G01Y465558D02*
Y467304D01*
G01Y461621D02*
Y463367D01*
G01Y457684D02*
Y459430D01*
G01D02*
Y457684D01*
G01Y463367D02*
Y461621D01*
G01Y467304D02*
Y465558D01*
G01Y471241D02*
Y469495D01*
G01Y475178D02*
Y473432D01*
G01X-24508Y459738D02*
Y457376D01*
G01Y463675D02*
Y461313D01*
G01Y467612D02*
Y465250D01*
G01Y471549D02*
Y469187D01*
G01Y475486D02*
Y473124D01*
G01X-24843Y454758D02*
Y474404D01*
G01X-26565Y473459D02*
Y475151D01*
G01Y469522D02*
Y471214D01*
G01Y465585D02*
Y467277D01*
G01Y461648D02*
Y463340D01*
G01Y457711D02*
Y459403D01*
G01D02*
Y457711D01*
G01Y463340D02*
Y461648D01*
G01Y467277D02*
Y465585D01*
G01Y471214D02*
Y469522D01*
G01Y475151D02*
Y473459D01*
G01X-26942Y473464D02*
Y475147D01*
G01Y469527D02*
Y471210D01*
G01Y465590D02*
Y467273D01*
G01Y461653D02*
Y463336D01*
G01Y457716D02*
Y459399D01*
G01D02*
Y457716D01*
G01Y463336D02*
Y461653D01*
G01Y467273D02*
Y465590D01*
G01Y471210D02*
Y469527D01*
G01Y475147D02*
Y473464D01*
G01X-27264Y459738D02*
Y457376D01*
G01Y463675D02*
Y461313D01*
G01Y467612D02*
Y465250D01*
G01Y471549D02*
Y469187D01*
G01Y475486D02*
Y473124D01*
G01X-27992Y454758D02*
Y474404D01*
G01X-31941Y473519D02*
Y475091D01*
G01Y469582D02*
Y471154D01*
G01Y465645D02*
Y467217D01*
G01Y461708D02*
Y463280D01*
G01Y457771D02*
Y459343D01*
G01D02*
Y457771D01*
G01Y463280D02*
Y461708D01*
G01Y467217D02*
Y465645D01*
G01Y471154D02*
Y469582D01*
G01Y475091D02*
Y473519D01*
G01X-32318Y473523D02*
Y475087D01*
G01Y469586D02*
Y471150D01*
G01Y465649D02*
Y467213D01*
G01Y461712D02*
Y463276D01*
G01Y457775D02*
Y459339D01*
G01D02*
Y457775D01*
G01Y463276D02*
Y461712D01*
G01Y467213D02*
Y465649D01*
G01Y471150D02*
Y469586D01*
G01Y475087D02*
Y473523D01*
G01X-33153Y473533D02*
Y475078D01*
G01Y469596D02*
Y471141D01*
G01Y465659D02*
Y467204D01*
G01Y461722D02*
Y463267D01*
G01Y457785D02*
Y459330D01*
G01D02*
Y457785D01*
G01Y463267D02*
Y461722D01*
G01Y467204D02*
Y465659D01*
G01Y471141D02*
Y469596D01*
G01Y475078D02*
Y473533D01*
G01X-34136Y473544D02*
Y475067D01*
G01Y469607D02*
Y471130D01*
G01Y465670D02*
Y467193D01*
G01Y461733D02*
Y463256D01*
G01Y457796D02*
Y459319D01*
G01D02*
Y457796D01*
G01Y463256D02*
Y461733D01*
G01Y467193D02*
Y465670D01*
G01Y471130D02*
Y469607D01*
G01Y475067D02*
Y473544D01*
G01X-34607Y459660D02*
Y457455D01*
G01Y463597D02*
Y461392D01*
G01Y467534D02*
Y465329D01*
G01Y471471D02*
Y469266D01*
G01Y475408D02*
Y473203D01*
G01X-35357Y473558D02*
Y475053D01*
G01Y469621D02*
Y471116D01*
G01Y465684D02*
Y467179D01*
G01Y461747D02*
Y463242D01*
G01Y457810D02*
Y459305D01*
G01D02*
Y457810D01*
G01Y463242D02*
Y461747D01*
G01Y467179D02*
Y465684D01*
G01Y471116D02*
Y469621D01*
G01Y475053D02*
Y473558D01*
G01X-35545Y459738D02*
Y457376D01*
G01Y463675D02*
Y461313D01*
G01Y467612D02*
Y465250D01*
G01Y471549D02*
Y469187D01*
G01Y475486D02*
Y473124D01*
G01X-35594Y473581D02*
Y475030D01*
G01Y469644D02*
Y471093D01*
G01Y465707D02*
Y467156D01*
G01Y461770D02*
Y463219D01*
G01Y457833D02*
Y459282D01*
G01D02*
Y457833D01*
G01Y463219D02*
Y461770D01*
G01Y467156D02*
Y465707D01*
G01Y471093D02*
Y469644D01*
G01Y475030D02*
Y473581D01*
G01X-37870Y473800D02*
Y474811D01*
G01Y469863D02*
Y470874D01*
G01Y465926D02*
Y466937D01*
G01Y461989D02*
Y463000D01*
G01Y458052D02*
Y459063D01*
G01Y454115D02*
Y455126D01*
G01D02*
Y454115D01*
G01Y459063D02*
Y458052D01*
G01Y463000D02*
Y461989D01*
G01Y466937D02*
Y465926D01*
G01Y470874D02*
Y469863D01*
G01Y474811D02*
Y473800D01*
G01X-38108Y473823D02*
Y474788D01*
G01Y469886D02*
Y470851D01*
G01Y465949D02*
Y466914D01*
G01Y462012D02*
Y462977D01*
G01Y458075D02*
Y459040D01*
G01Y454138D02*
Y455103D01*
G01D02*
Y454138D01*
G01Y459040D02*
Y458075D01*
G01Y462977D02*
Y462012D01*
G01Y466914D02*
Y465949D01*
G01Y470851D02*
Y469886D01*
G01Y474788D02*
Y473823D01*
G01X-38425Y459738D02*
Y457376D01*
G01Y463675D02*
Y461313D01*
G01Y467612D02*
Y465250D01*
G01Y471549D02*
Y469187D01*
G01Y475486D02*
Y473124D01*
G01X-38108Y494473D02*
X-35350Y494738D01*
G01D02*
X-38108Y494473D01*
G01X-35350Y493242D02*
X-10630Y492967D01*
G01D02*
X-35350Y493242D01*
G01Y489305D02*
X-10630Y489030D01*
G01D02*
X-35350Y489305D01*
G01Y485368D02*
X-10630Y485093D01*
G01D02*
X-35350Y485368D01*
G01Y481431D02*
X-10630Y481156D01*
G01D02*
X-35350Y481431D01*
G01X-24508Y495171D02*
X-39607D01*
G01X-35545Y495093D02*
X0D01*
G01X-27992Y494876D02*
X-39607D01*
G01X-35545Y492888D02*
X0D01*
G01X-39607Y492809D02*
X-24508D01*
G01Y491234D02*
X-39607D01*
G01X-35545Y491156D02*
X0D01*
G01X-35545Y488951D02*
X0D01*
G01X-39607Y488872D02*
X-24508D01*
G01Y487297D02*
X-39607D01*
G01X-35545Y487219D02*
X0D01*
G01X-35545Y485014D02*
X0D01*
G01X-39607Y484935D02*
X-24508D01*
G01Y483360D02*
X-39607D01*
G01X-35545Y483282D02*
X0D01*
G01X-39607Y481530D02*
X-27992D01*
G01X-35545Y481077D02*
X0D01*
G01X-39607Y480998D02*
X-24508D01*
G01Y479423D02*
X-39607D01*
G01X-35545Y479345D02*
X0D01*
G01X-39607Y478380D02*
X-24843D01*
G01X-35545Y477140D02*
X0D01*
G01X-39607Y477061D02*
X-24508D01*
G01Y475486D02*
X-39607D01*
G01X-35545Y475408D02*
X0D01*
G01X-35350Y494738D02*
X-10630Y495014D01*
G01X-35350Y494738D02*
X-10630Y495014D01*
G01X-35350Y490801D02*
X-10630Y491077D01*
G01X-35350Y490801D02*
X-10630Y491077D01*
G01X-35350Y486864D02*
X-10630Y487140D01*
G01X-35350Y486864D02*
X-10630Y487140D01*
G01X-35350Y482927D02*
X-10630Y483203D01*
G01X-35350Y482927D02*
X-10630Y483203D01*
G01X-35350Y478990D02*
X-10630Y479266D01*
G01X-35350Y478990D02*
X-10630Y479266D01*
G01X-38108Y490536D02*
X-35350Y490801D01*
G01D02*
X-38108Y490536D01*
G01Y486599D02*
X-35350Y486864D01*
G01D02*
X-38108Y486599D01*
G01Y482662D02*
X-35350Y482927D01*
G01D02*
X-38108Y482662D01*
G01Y478725D02*
X-35350Y478990D01*
G01D02*
X-38108Y478725D01*
G01Y493508D02*
X-35350Y493242D01*
G01X-38108Y493508D02*
X-35350Y493242D01*
G01X-38108Y489571D02*
X-35350Y489305D01*
G01X-38108Y489571D02*
X-35350Y489305D01*
G01X-38108Y485634D02*
X-35350Y485368D01*
G01X-38108Y485634D02*
X-35350Y485368D01*
G01X-38108Y481697D02*
X-35350Y481431D01*
G01X-38108Y481697D02*
X-35350Y481431D01*
G01X-38108Y477760D02*
X-35350Y477494D01*
G01X-38108Y477760D02*
X-35350Y477494D01*
G01D02*
X-10630Y477219D01*
G01D02*
X-35350Y477494D01*
G01X-24121Y493117D02*
Y494864D01*
G01Y489180D02*
Y490927D01*
G01Y485243D02*
Y486990D01*
G01Y477369D02*
Y479116D01*
G01Y481306D02*
Y483053D01*
G01D02*
Y481306D01*
G01Y479116D02*
Y477369D01*
G01Y486990D02*
Y485243D01*
G01Y490927D02*
Y489180D01*
G01Y494864D02*
Y493117D01*
G01X-24508Y479423D02*
Y477061D01*
G01Y483360D02*
Y480998D01*
G01Y487297D02*
Y484935D01*
G01Y491234D02*
Y488872D01*
G01Y495171D02*
Y492809D01*
G01X-24843Y478380D02*
Y498026D01*
G01X-26565Y493144D02*
Y494836D01*
G01Y489207D02*
Y490899D01*
G01Y485270D02*
Y486962D01*
G01Y481333D02*
Y483025D01*
G01Y477396D02*
Y479088D01*
G01D02*
Y477396D01*
G01Y483025D02*
Y481333D01*
G01Y486962D02*
Y485270D01*
G01Y490899D02*
Y489207D01*
G01Y494836D02*
Y493144D01*
G01X-26942Y493149D02*
Y494832D01*
G01Y489212D02*
Y490895D01*
G01Y485275D02*
Y486958D01*
G01Y481338D02*
Y483021D01*
G01Y477401D02*
Y479084D01*
G01D02*
Y477401D01*
G01Y483021D02*
Y481338D01*
G01Y486958D02*
Y485275D01*
G01Y490895D02*
Y489212D01*
G01Y494832D02*
Y493149D01*
G01X-27264Y479423D02*
Y477061D01*
G01Y483360D02*
Y480998D01*
G01Y487297D02*
Y484935D01*
G01Y491234D02*
Y488872D01*
G01Y495171D02*
Y492809D01*
G01X-27992Y478380D02*
Y498026D01*
G01X-31941Y493204D02*
Y494777D01*
G01Y489267D02*
Y490840D01*
G01Y485330D02*
Y486903D01*
G01Y477456D02*
Y479028D01*
G01Y481393D02*
Y482966D01*
G01D02*
Y481393D01*
G01Y479028D02*
Y477456D01*
G01Y486903D02*
Y485330D01*
G01Y490840D02*
Y489267D01*
G01Y494777D02*
Y493204D01*
G01X-32318Y493208D02*
Y494772D01*
G01Y489271D02*
Y490835D01*
G01Y485334D02*
Y486898D01*
G01Y477460D02*
Y479024D01*
G01Y481397D02*
Y482961D01*
G01D02*
Y481397D01*
G01Y479024D02*
Y477460D01*
G01Y486898D02*
Y485334D01*
G01Y490835D02*
Y489271D01*
G01Y494772D02*
Y493208D01*
G01X-33153Y493218D02*
Y494763D01*
G01Y489281D02*
Y490826D01*
G01Y485344D02*
Y486889D01*
G01Y481407D02*
Y482952D01*
G01Y477470D02*
Y479015D01*
G01D02*
Y477470D01*
G01Y482952D02*
Y481407D01*
G01Y486889D02*
Y485344D01*
G01Y490826D02*
Y489281D01*
G01Y494763D02*
Y493218D01*
G01X-34136Y493229D02*
Y494752D01*
G01Y489292D02*
Y490815D01*
G01Y485355D02*
Y486878D01*
G01Y477481D02*
Y479004D01*
G01Y481418D02*
Y482941D01*
G01D02*
Y481418D01*
G01Y479004D02*
Y477481D01*
G01Y486878D02*
Y485355D01*
G01Y490815D02*
Y489292D01*
G01Y494752D02*
Y493229D01*
G01X-34607Y479345D02*
Y477140D01*
G01Y483282D02*
Y481077D01*
G01Y487219D02*
Y485014D01*
G01Y491156D02*
Y488951D01*
G01Y495093D02*
Y492888D01*
G01X-35357Y493243D02*
Y494738D01*
G01Y489306D02*
Y490801D01*
G01Y485369D02*
Y486864D01*
G01Y481432D02*
Y482927D01*
G01Y477495D02*
Y478990D01*
G01D02*
Y477495D01*
G01Y482927D02*
Y481432D01*
G01Y486864D02*
Y485369D01*
G01Y490801D02*
Y489306D01*
G01Y494738D02*
Y493243D01*
G01X-35545Y479423D02*
Y477061D01*
G01Y483360D02*
Y480998D01*
G01Y487297D02*
Y484935D01*
G01Y491234D02*
Y488872D01*
G01Y495171D02*
Y492809D01*
G01X-35594Y493266D02*
Y494715D01*
G01Y489329D02*
Y490778D01*
G01Y485392D02*
Y486841D01*
G01Y481455D02*
Y482904D01*
G01Y477518D02*
Y478967D01*
G01D02*
Y477518D01*
G01Y482904D02*
Y481455D01*
G01Y486841D02*
Y485392D01*
G01Y490778D02*
Y489329D01*
G01Y494715D02*
Y493266D01*
G01X-37870Y493485D02*
Y494496D01*
G01Y489548D02*
Y490559D01*
G01Y485611D02*
Y486622D01*
G01Y481674D02*
Y482685D01*
G01Y477737D02*
Y478748D01*
G01D02*
Y477737D01*
G01Y482685D02*
Y481674D01*
G01Y486622D02*
Y485611D01*
G01Y490559D02*
Y489548D01*
G01Y494496D02*
Y493485D01*
G01X-38108Y493508D02*
Y494473D01*
G01Y489571D02*
Y490536D01*
G01Y485634D02*
Y486599D01*
G01Y481697D02*
Y482662D01*
G01Y477760D02*
Y478725D01*
G01D02*
Y477760D01*
G01Y482662D02*
Y481697D01*
G01Y486599D02*
Y485634D01*
G01Y490536D02*
Y489571D01*
G01Y494473D02*
Y493508D01*
G01X-38425Y479423D02*
Y477061D01*
G01Y483360D02*
Y480998D01*
G01Y487297D02*
Y484935D01*
G01Y491234D02*
Y488872D01*
G01Y495171D02*
Y492809D01*
G01X-38108Y514158D02*
X-35350Y514423D01*
G01D02*
X-38108Y514158D01*
G01Y510221D02*
X-35350Y510486D01*
G01D02*
X-38108Y510221D01*
G01Y506284D02*
X-35350Y506549D01*
G01D02*
X-38108Y506284D01*
G01Y502347D02*
X-35350Y502612D01*
G01D02*
X-38108Y502347D01*
G01Y498410D02*
X-35350Y498675D01*
G01D02*
X-38108Y498410D01*
G01X-35350Y516864D02*
X-10630Y516589D01*
G01D02*
X-35350Y516864D01*
G01Y512927D02*
X-10630Y512652D01*
G01D02*
X-35350Y512927D01*
G01Y508990D02*
X-10630Y508715D01*
G01D02*
X-35350Y508990D01*
G01Y505053D02*
X-10630Y504778D01*
G01D02*
X-35350Y505053D01*
G01Y501116D02*
X-10630Y500841D01*
G01D02*
X-35350Y501116D01*
G01Y497179D02*
X-10630Y496904D01*
G01D02*
X-35350Y497179D01*
G01X-35545Y516510D02*
X0D01*
G01X-39607Y516431D02*
X-24508D01*
G01Y514856D02*
X-39607D01*
G01X-35545Y514778D02*
X0D01*
G01X-35545Y512573D02*
X0D01*
G01X-39607Y512494D02*
X-24508D01*
G01Y510919D02*
X-39607D01*
G01X-35545Y510841D02*
X0D01*
G01X-35545Y508636D02*
X0D01*
G01X-39607Y508557D02*
X-24508D01*
G01Y506982D02*
X-39607D01*
G01X-35545Y506904D02*
X0D01*
G01X-39607Y505152D02*
X-27992D01*
G01X-35545Y504699D02*
X0D01*
G01X-39607Y504620D02*
X-24508D01*
G01Y503045D02*
X-39607D01*
G01X-35545Y502967D02*
X0D01*
G01X-39607Y502002D02*
X-24843D01*
G01X-35545Y500762D02*
X0D01*
G01X-39607Y500683D02*
X-24508D01*
G01Y499108D02*
X-39607D01*
G01X-35545Y499030D02*
X0D01*
G01X-39607Y498026D02*
X-24843D01*
G01X-35545Y496825D02*
X0D01*
G01X-39607Y496746D02*
X-24508D01*
G01X-35350Y514423D02*
X-10630Y514699D01*
G01X-35350Y514423D02*
X-10630Y514699D01*
G01X-35350Y510486D02*
X-10630Y510762D01*
G01X-35350Y510486D02*
X-10630Y510762D01*
G01X-35350Y506549D02*
X-10630Y506825D01*
G01X-35350Y506549D02*
X-10630Y506825D01*
G01X-35350Y502612D02*
X-10630Y502888D01*
G01X-35350Y502612D02*
X-10630Y502888D01*
G01X-35350Y498675D02*
X-10630Y498951D01*
G01X-35350Y498675D02*
X-10630Y498951D01*
G01X-38108Y517130D02*
X-35350Y516864D01*
G01X-38108Y517130D02*
X-35350Y516864D01*
G01X-38108Y513193D02*
X-35350Y512927D01*
G01X-38108Y513193D02*
X-35350Y512927D01*
G01X-38108Y509256D02*
X-35350Y508990D01*
G01X-38108Y509256D02*
X-35350Y508990D01*
G01X-38108Y505319D02*
X-35350Y505053D01*
G01X-38108Y505319D02*
X-35350Y505053D01*
G01X-38108Y501382D02*
X-35350Y501116D01*
G01X-38108Y501382D02*
X-35350Y501116D01*
G01X-38108Y497445D02*
X-35350Y497179D01*
G01X-38108Y497445D02*
X-35350Y497179D01*
G01X-24121Y516739D02*
Y518486D01*
G01Y512802D02*
Y514549D01*
G01Y508865D02*
Y510612D01*
G01Y504928D02*
Y506675D01*
G01Y500991D02*
Y502738D01*
G01Y497054D02*
Y498801D01*
G01D02*
Y497054D01*
G01Y506675D02*
Y504928D01*
G01Y502738D02*
Y500991D01*
G01Y510612D02*
Y508865D01*
G01Y514549D02*
Y512802D01*
G01Y518486D02*
Y516739D01*
G01X-24508Y499108D02*
Y496746D01*
G01Y503045D02*
Y500683D01*
G01Y506982D02*
Y504620D01*
G01Y510919D02*
Y508557D01*
G01Y514856D02*
Y512494D01*
G01Y518793D02*
Y516431D01*
G01X-24843Y502002D02*
Y521648D01*
G01X-26565Y516766D02*
Y518458D01*
G01Y512829D02*
Y514521D01*
G01Y508892D02*
Y510584D01*
G01Y504955D02*
Y506647D01*
G01Y501018D02*
Y502710D01*
G01Y497081D02*
Y498773D01*
G01Y502710D02*
Y501018D01*
G01Y498773D02*
Y497081D01*
G01Y506647D02*
Y504955D01*
G01Y510584D02*
Y508892D01*
G01Y514521D02*
Y512829D01*
G01Y518458D02*
Y516766D01*
G01X-26942Y516771D02*
Y518454D01*
G01Y512834D02*
Y514517D01*
G01Y508897D02*
Y510580D01*
G01Y504960D02*
Y506643D01*
G01Y501023D02*
Y502706D01*
G01Y497086D02*
Y498769D01*
G01D02*
Y497086D01*
G01Y502706D02*
Y501023D01*
G01Y506643D02*
Y504960D01*
G01Y510580D02*
Y508897D01*
G01Y514517D02*
Y512834D01*
G01Y518454D02*
Y516771D01*
G01X-27264Y499108D02*
Y496746D01*
G01Y503045D02*
Y500683D01*
G01Y506982D02*
Y504620D01*
G01Y510919D02*
Y508557D01*
G01Y514856D02*
Y512494D01*
G01Y518793D02*
Y516431D01*
G01X-27992Y502002D02*
Y521648D01*
G01X-31941Y516827D02*
Y518399D01*
G01Y512890D02*
Y514462D01*
G01Y508953D02*
Y510525D01*
G01Y505016D02*
Y506588D01*
G01Y501078D02*
Y502651D01*
G01Y497141D02*
Y498714D01*
G01D02*
Y497141D01*
G01Y506588D02*
Y505016D01*
G01Y502651D02*
Y501078D01*
G01Y510525D02*
Y508953D01*
G01Y514462D02*
Y512890D01*
G01Y518399D02*
Y516827D01*
G01X-32318Y516830D02*
Y518394D01*
G01Y512893D02*
Y514457D01*
G01Y508956D02*
Y510520D01*
G01Y501082D02*
Y502646D01*
G01Y505019D02*
Y506583D01*
G01Y497145D02*
Y498709D01*
G01D02*
Y497145D01*
G01Y506583D02*
Y505019D01*
G01Y502646D02*
Y501082D01*
G01Y510520D02*
Y508956D01*
G01Y514457D02*
Y512893D01*
G01Y518394D02*
Y516830D01*
G01X-33153Y516840D02*
Y518385D01*
G01Y512903D02*
Y514448D01*
G01Y508966D02*
Y510511D01*
G01Y505029D02*
Y506574D01*
G01Y501092D02*
Y502637D01*
G01Y497155D02*
Y498700D01*
G01Y502637D02*
Y501092D01*
G01Y498700D02*
Y497155D01*
G01Y506574D02*
Y505029D01*
G01Y510511D02*
Y508966D01*
G01Y514448D02*
Y512903D01*
G01Y518385D02*
Y516840D01*
G01X-34136Y516851D02*
Y518374D01*
G01Y512914D02*
Y514437D01*
G01Y508977D02*
Y510500D01*
G01Y501103D02*
Y502626D01*
G01Y505040D02*
Y506563D01*
G01Y497166D02*
Y498689D01*
G01D02*
Y497166D01*
G01Y506563D02*
Y505040D01*
G01Y502626D02*
Y501103D01*
G01Y510500D02*
Y508977D01*
G01Y514437D02*
Y512914D01*
G01Y518374D02*
Y516851D01*
G01X-34607Y502967D02*
Y500762D01*
G01Y499030D02*
Y496825D01*
G01Y506904D02*
Y504699D01*
G01Y510841D02*
Y508636D01*
G01Y514778D02*
Y512573D01*
G01Y518715D02*
Y516510D01*
G01X-35357Y516865D02*
Y518360D01*
G01Y512928D02*
Y514423D01*
G01Y508991D02*
Y510486D01*
G01Y505054D02*
Y506549D01*
G01Y501117D02*
Y502612D01*
G01Y497180D02*
Y498675D01*
G01D02*
Y497180D01*
G01Y502612D02*
Y501117D01*
G01Y506549D02*
Y505054D01*
G01Y510486D02*
Y508991D01*
G01Y514423D02*
Y512928D01*
G01Y518360D02*
Y516865D01*
G01X-35545Y499108D02*
Y496746D01*
G01Y503045D02*
Y500683D01*
G01Y506982D02*
Y504620D01*
G01Y510919D02*
Y508557D01*
G01Y514856D02*
Y512494D01*
G01Y518793D02*
Y516431D01*
G01X-35594Y516888D02*
Y518337D01*
G01Y512951D02*
Y514400D01*
G01Y509014D02*
Y510463D01*
G01Y505077D02*
Y506526D01*
G01Y501140D02*
Y502589D01*
G01Y497203D02*
Y498652D01*
G01Y502589D02*
Y501140D01*
G01Y498652D02*
Y497203D01*
G01Y506526D02*
Y505077D01*
G01Y510463D02*
Y509014D01*
G01Y514400D02*
Y512951D01*
G01Y518337D02*
Y516888D01*
G01X-37870Y517107D02*
Y518118D01*
G01Y513170D02*
Y514181D01*
G01Y509233D02*
Y510244D01*
G01Y501359D02*
Y502370D01*
G01Y505296D02*
Y506307D01*
G01Y497422D02*
Y498433D01*
G01D02*
Y497422D01*
G01Y506307D02*
Y505296D01*
G01Y502370D02*
Y501359D01*
G01Y510244D02*
Y509233D01*
G01Y514181D02*
Y513170D01*
G01Y518118D02*
Y517107D01*
G01X-38108Y517130D02*
Y518095D01*
G01Y513193D02*
Y514158D01*
G01Y509256D02*
Y510221D01*
G01Y501382D02*
Y502347D01*
G01Y505319D02*
Y506284D01*
G01Y497445D02*
Y498410D01*
G01Y502347D02*
Y501382D01*
G01Y498410D02*
Y497445D01*
G01Y506284D02*
Y505319D01*
G01Y510221D02*
Y509256D01*
G01Y514158D02*
Y513193D01*
G01Y518095D02*
Y517130D01*
G01X-38425Y503045D02*
Y500683D01*
G01Y499108D02*
Y496746D01*
G01Y506982D02*
Y504620D01*
G01Y510919D02*
Y508557D01*
G01Y514856D02*
Y512494D01*
G01Y518793D02*
Y516431D01*
G01X-38108Y537780D02*
X-35350Y538045D01*
G01D02*
X-38108Y537780D01*
G01Y533843D02*
X-35350Y534108D01*
G01D02*
X-38108Y533843D01*
G01Y529906D02*
X-35350Y530171D01*
G01D02*
X-38108Y529906D01*
G01Y525969D02*
X-35350Y526234D01*
G01D02*
X-38108Y525969D01*
G01Y522032D02*
X-35350Y522297D01*
G01D02*
X-38108Y522032D01*
G01Y518095D02*
X-35350Y518360D01*
G01D02*
X-38108Y518095D01*
G01Y536815D02*
X-35350Y536549D01*
G01X-38108Y536815D02*
X-35350Y536549D01*
G01X-38108Y532878D02*
X-35350Y532612D01*
G01X-38108Y532878D02*
X-35350Y532612D01*
G01X-38108Y528941D02*
X-35350Y528675D01*
G01X-38108Y528941D02*
X-35350Y528675D01*
G01X-38108Y525004D02*
X-35350Y524738D01*
G01X-38108Y525004D02*
X-35350Y524738D01*
G01Y536549D02*
X-10630Y536274D01*
G01D02*
X-35350Y536549D01*
G01Y532612D02*
X-10630Y532337D01*
G01D02*
X-35350Y532612D01*
G01Y528675D02*
X-10630Y528400D01*
G01D02*
X-35350Y528675D01*
G01Y524738D02*
X-10630Y524463D01*
G01D02*
X-35350Y524738D01*
G01Y520801D02*
X-10630Y520526D01*
G01D02*
X-35350Y520801D01*
G01X-24508Y538478D02*
X-39607D01*
G01X-35545Y538400D02*
X0D01*
G01X-35545Y536195D02*
X0D01*
G01X-39607Y536116D02*
X-24508D01*
G01Y534541D02*
X-39607D01*
G01X-35545Y534463D02*
X0D01*
G01X-35545Y532258D02*
X0D01*
G01X-39607Y532179D02*
X-24508D01*
G01Y530604D02*
X-39607D01*
G01X-35545Y530526D02*
X0D01*
G01X-39607Y528774D02*
X-27992D01*
G01X-35545Y528321D02*
X0D01*
G01X-39607Y528242D02*
X-24508D01*
G01Y526667D02*
X-39607D01*
G01X-35545Y526589D02*
X0D01*
G01X-39607Y525624D02*
X-24843D01*
G01X-35545Y524384D02*
X0D01*
G01X-39607Y524305D02*
X-24508D01*
G01Y522730D02*
X-39607D01*
G01X-35545Y522652D02*
X0D01*
G01X-39607Y521648D02*
X-24843D01*
G01X-35545Y520447D02*
X0D01*
G01X-39607Y520368D02*
X-24508D01*
G01Y518793D02*
X-39607D01*
G01X-35545Y518715D02*
X0D01*
G01X-27992Y518498D02*
X-39607D01*
G01X-35350Y538045D02*
X-10630Y538321D01*
G01X-35350Y538045D02*
X-10630Y538321D01*
G01X-35350Y534108D02*
X-10630Y534384D01*
G01X-35350Y534108D02*
X-10630Y534384D01*
G01X-35350Y530171D02*
X-10630Y530447D01*
G01X-35350Y530171D02*
X-10630Y530447D01*
G01X-35350Y526234D02*
X-10630Y526510D01*
G01X-35350Y526234D02*
X-10630Y526510D01*
G01X-35350Y522297D02*
X-10630Y522573D01*
G01X-35350Y522297D02*
X-10630Y522573D01*
G01X-35350Y518360D02*
X-10630Y518636D01*
G01X-35350Y518360D02*
X-10630Y518636D01*
G01X-38108Y521067D02*
X-35350Y520801D01*
G01X-38108Y521067D02*
X-35350Y520801D01*
G01X-24121Y536424D02*
Y538171D01*
G01Y532487D02*
Y534234D01*
G01Y528550D02*
Y530297D01*
G01Y524613D02*
Y526360D01*
G01Y520676D02*
Y522423D01*
G01D02*
Y520676D01*
G01Y530297D02*
Y528550D01*
G01Y526360D02*
Y524613D01*
G01Y534234D02*
Y532487D01*
G01Y538171D02*
Y536424D01*
G01X-24508Y522730D02*
Y520368D01*
G01Y526667D02*
Y524305D01*
G01Y530604D02*
Y528242D01*
G01Y534541D02*
Y532179D01*
G01Y538478D02*
Y536116D01*
G01X-24843Y525624D02*
Y545270D01*
G01X-26565Y536451D02*
Y538143D01*
G01Y532514D02*
Y534206D01*
G01Y528577D02*
Y530269D01*
G01Y524640D02*
Y526332D01*
G01Y520703D02*
Y522395D01*
G01Y526332D02*
Y524640D01*
G01Y522395D02*
Y520703D01*
G01Y530269D02*
Y528577D01*
G01Y534206D02*
Y532514D01*
G01Y538143D02*
Y536451D01*
G01X-26942Y536456D02*
Y538139D01*
G01Y532519D02*
Y534202D01*
G01Y528582D02*
Y530265D01*
G01Y524645D02*
Y526328D01*
G01Y520708D02*
Y522391D01*
G01D02*
Y520708D01*
G01Y526328D02*
Y524645D01*
G01Y530265D02*
Y528582D01*
G01Y534202D02*
Y532519D01*
G01Y538139D02*
Y536456D01*
G01X-27264Y522730D02*
Y520368D01*
G01Y526667D02*
Y524305D01*
G01Y530604D02*
Y528242D01*
G01Y534541D02*
Y532179D01*
G01Y538478D02*
Y536116D01*
G01X-27992Y525624D02*
Y545270D01*
G01X-31941Y536512D02*
Y538084D01*
G01Y532575D02*
Y534147D01*
G01Y528638D02*
Y530210D01*
G01Y524701D02*
Y526273D01*
G01Y520764D02*
Y522336D01*
G01D02*
Y520764D01*
G01Y530210D02*
Y528638D01*
G01Y526273D02*
Y524701D01*
G01Y534147D02*
Y532575D01*
G01Y538084D02*
Y536512D01*
G01X-32318Y536516D02*
Y538079D01*
G01Y532578D02*
Y534142D01*
G01Y524704D02*
Y526268D01*
G01Y528641D02*
Y530205D01*
G01Y520767D02*
Y522331D01*
G01D02*
Y520767D01*
G01Y530205D02*
Y528641D01*
G01Y526268D02*
Y524704D01*
G01Y534142D02*
Y532578D01*
G01Y538079D02*
Y536516D01*
G01X-33153Y536525D02*
Y538070D01*
G01Y532588D02*
Y534133D01*
G01Y528651D02*
Y530196D01*
G01Y524714D02*
Y526259D01*
G01Y520777D02*
Y522322D01*
G01Y526259D02*
Y524714D01*
G01Y522322D02*
Y520777D01*
G01Y530196D02*
Y528651D01*
G01Y534133D02*
Y532588D01*
G01Y538070D02*
Y536525D01*
G01X-34136Y536536D02*
Y538059D01*
G01Y532599D02*
Y534122D01*
G01Y524725D02*
Y526248D01*
G01Y528662D02*
Y530185D01*
G01Y520788D02*
Y522311D01*
G01D02*
Y520788D01*
G01Y530185D02*
Y528662D01*
G01Y526248D02*
Y524725D01*
G01Y534122D02*
Y532599D01*
G01Y538059D02*
Y536536D01*
G01X-34607Y526589D02*
Y524384D01*
G01Y522652D02*
Y520447D01*
G01Y530526D02*
Y528321D01*
G01Y534463D02*
Y532258D01*
G01Y538400D02*
Y536195D01*
G01X-35357Y536550D02*
Y538045D01*
G01Y532613D02*
Y534108D01*
G01Y528676D02*
Y530171D01*
G01Y524739D02*
Y526234D01*
G01Y520802D02*
Y522297D01*
G01D02*
Y520802D01*
G01Y526234D02*
Y524739D01*
G01Y530171D02*
Y528676D01*
G01Y534108D02*
Y532613D01*
G01Y538045D02*
Y536550D01*
G01X-35545Y522730D02*
Y520368D01*
G01Y526667D02*
Y524305D01*
G01Y530604D02*
Y528242D01*
G01Y534541D02*
Y532179D01*
G01Y538478D02*
Y536116D01*
G01X-35594Y536573D02*
Y538022D01*
G01Y532636D02*
Y534085D01*
G01Y528699D02*
Y530148D01*
G01Y524762D02*
Y526211D01*
G01Y520825D02*
Y522274D01*
G01Y526211D02*
Y524762D01*
G01Y522274D02*
Y520825D01*
G01Y530148D02*
Y528699D01*
G01Y534085D02*
Y532636D01*
G01Y538022D02*
Y536573D01*
G01X-37870Y536792D02*
Y537803D01*
G01Y532855D02*
Y533866D01*
G01Y524981D02*
Y525992D01*
G01Y528918D02*
Y529929D01*
G01Y521044D02*
Y522055D01*
G01D02*
Y521044D01*
G01Y529929D02*
Y528918D01*
G01Y525992D02*
Y524981D01*
G01Y533866D02*
Y532855D01*
G01Y537803D02*
Y536792D01*
G01X-38108Y536815D02*
Y537780D01*
G01Y532878D02*
Y533843D01*
G01Y525004D02*
Y525969D01*
G01Y528941D02*
Y529906D01*
G01Y521067D02*
Y522032D01*
G01Y525969D02*
Y525004D01*
G01Y522032D02*
Y521067D01*
G01Y529906D02*
Y528941D01*
G01Y533843D02*
Y532878D01*
G01Y537780D02*
Y536815D01*
G01X-38425Y526667D02*
Y524305D01*
G01Y522730D02*
Y520368D01*
G01Y530604D02*
Y528242D01*
G01Y534541D02*
Y532179D01*
G01Y538478D02*
Y536116D01*
G01X-35350Y556234D02*
X-10630Y555959D01*
G01D02*
X-35350Y556234D01*
G01X-24508Y558164D02*
X-39607D01*
G01X-35545Y558085D02*
X0D01*
G01X-35545Y555880D02*
X0D01*
G01X-39607Y555801D02*
X-24508D01*
G01Y554227D02*
X-39607D01*
G01X-35545Y554148D02*
X0D01*
G01X-39607Y552396D02*
X-27992D01*
G01X-35545Y551943D02*
X0D01*
G01X-39607Y551864D02*
X-24508D01*
G01Y550290D02*
X-39607D01*
G01X-35545Y550211D02*
X0D01*
G01X-35350Y557730D02*
X-10630Y558006D01*
G01X-35350Y557730D02*
X-10630Y558006D01*
G01X-35350Y553793D02*
X-10630Y554069D01*
G01X-35350Y553793D02*
X-10630Y554069D01*
G01X-35350Y549856D02*
X-10630Y550132D01*
G01X-35350Y549856D02*
X-10630Y550132D01*
G01X-35350Y545919D02*
X-10630Y546195D01*
G01X-35350Y545919D02*
X-10630Y546195D01*
G01X-38108Y557465D02*
X-35350Y557730D01*
G01D02*
X-38108Y557465D01*
G01Y553528D02*
X-35350Y553793D01*
G01D02*
X-38108Y553528D01*
G01Y549591D02*
X-35350Y549856D01*
G01D02*
X-38108Y549591D01*
G01Y545654D02*
X-35350Y545919D01*
G01D02*
X-38108Y545654D01*
G01Y541717D02*
X-35350Y541982D01*
G01D02*
X-38108Y541717D01*
G01Y556500D02*
X-35350Y556234D01*
G01X-38108Y556500D02*
X-35350Y556234D01*
G01X-38108Y552563D02*
X-35350Y552297D01*
G01X-38108Y552563D02*
X-35350Y552297D01*
G01X-38108Y548626D02*
X-35350Y548360D01*
G01X-38108Y548626D02*
X-35350Y548360D01*
G01X-38108Y544689D02*
X-35350Y544423D01*
G01X-38108Y544689D02*
X-35350Y544423D01*
G01X-38108Y540752D02*
X-35350Y540486D01*
G01X-38108Y540752D02*
X-35350Y540486D01*
G01Y552297D02*
X-10630Y552022D01*
G01D02*
X-35350Y552297D01*
G01Y548360D02*
X-10630Y548085D01*
G01D02*
X-35350Y548360D01*
G01Y544423D02*
X-10630Y544148D01*
G01D02*
X-35350Y544423D01*
G01Y540486D02*
X-10630Y540211D01*
G01D02*
X-35350Y540486D01*
G01X-39607Y549246D02*
X-24843D01*
G01X-35545Y548006D02*
X0D01*
G01X-39607Y547927D02*
X-24508D01*
G01Y546353D02*
X-39607D01*
G01X-35545Y546274D02*
X0D01*
G01X-39607Y545270D02*
X-24843D01*
G01X-35545Y544069D02*
X0D01*
G01X-39607Y543990D02*
X-24508D01*
G01Y542416D02*
X-39607D01*
G01X-35545Y542337D02*
X0D01*
G01X-27992Y542120D02*
X-39607D01*
G01X-35545Y540132D02*
X0D01*
G01X-39607Y540053D02*
X-24508D01*
G01X-35350Y541982D02*
X-10630Y542258D01*
G01X-35350Y541982D02*
X-10630Y542258D01*
G01X-24121Y552172D02*
Y553919D01*
G01Y556109D02*
Y557856D01*
G01Y548235D02*
Y549982D01*
G01Y544298D02*
Y546045D01*
G01Y540361D02*
Y542108D01*
G01D02*
Y540361D01*
G01Y546045D02*
Y544298D01*
G01Y549982D02*
Y548235D01*
G01Y557856D02*
Y556109D01*
G01Y553919D02*
Y552172D01*
G01X-24508Y542416D02*
Y540053D01*
G01Y546353D02*
Y543990D01*
G01Y550290D02*
Y547927D01*
G01Y554227D02*
Y551864D01*
G01Y558164D02*
Y555801D01*
G01X-24843Y549246D02*
Y568892D01*
G01X-26565Y556136D02*
Y557828D01*
G01Y552199D02*
Y553891D01*
G01Y548262D02*
Y549954D01*
G01Y544325D02*
Y546017D01*
G01Y540388D02*
Y542080D01*
G01D02*
Y540388D01*
G01Y546017D02*
Y544325D01*
G01Y549954D02*
Y548262D01*
G01Y553891D02*
Y552199D01*
G01Y557828D02*
Y556136D01*
G01X-26942Y556141D02*
Y557824D01*
G01Y552204D02*
Y553887D01*
G01Y548267D02*
Y549950D01*
G01Y544330D02*
Y546013D01*
G01Y540393D02*
Y542076D01*
G01D02*
Y540393D01*
G01Y546013D02*
Y544330D01*
G01Y549950D02*
Y548267D01*
G01Y553887D02*
Y552204D01*
G01Y557824D02*
Y556141D01*
G01X-27264Y542416D02*
Y540053D01*
G01Y546353D02*
Y543990D01*
G01Y550290D02*
Y547927D01*
G01Y554227D02*
Y551864D01*
G01Y558164D02*
Y555801D01*
G01X-27992Y549246D02*
Y568892D01*
G01X-31941Y552260D02*
Y553832D01*
G01Y556197D02*
Y557769D01*
G01Y548323D02*
Y549895D01*
G01Y544386D02*
Y545958D01*
G01Y540449D02*
Y542021D01*
G01D02*
Y540449D01*
G01Y545958D02*
Y544386D01*
G01Y549895D02*
Y548323D01*
G01Y557769D02*
Y556197D01*
G01Y553832D02*
Y552260D01*
G01X-32318Y552264D02*
Y553827D01*
G01Y556201D02*
Y557764D01*
G01Y548327D02*
Y549890D01*
G01Y544390D02*
Y545953D01*
G01Y540453D02*
Y542016D01*
G01D02*
Y540453D01*
G01Y545953D02*
Y544390D01*
G01Y549890D02*
Y548327D01*
G01Y557764D02*
Y556201D01*
G01Y553827D02*
Y552264D01*
G01X-33153Y556210D02*
Y557755D01*
G01Y552273D02*
Y553818D01*
G01Y548336D02*
Y549881D01*
G01Y544399D02*
Y545944D01*
G01Y540462D02*
Y542007D01*
G01D02*
Y540462D01*
G01Y545944D02*
Y544399D01*
G01Y549881D02*
Y548336D01*
G01Y553818D02*
Y552273D01*
G01Y557755D02*
Y556210D01*
G01X-34136Y552284D02*
Y553807D01*
G01Y556221D02*
Y557744D01*
G01Y548347D02*
Y549870D01*
G01Y544410D02*
Y545933D01*
G01Y540473D02*
Y541996D01*
G01D02*
Y540473D01*
G01Y545933D02*
Y544410D01*
G01Y549870D02*
Y548347D01*
G01Y557744D02*
Y556221D01*
G01Y553807D02*
Y552284D01*
G01X-34607Y542337D02*
Y540132D01*
G01Y546274D02*
Y544069D01*
G01Y554148D02*
Y551943D01*
G01Y550211D02*
Y548006D01*
G01Y558085D02*
Y555880D01*
G01X-35357Y556235D02*
Y557730D01*
G01Y552298D02*
Y553793D01*
G01Y548361D02*
Y549856D01*
G01Y544424D02*
Y545919D01*
G01Y540487D02*
Y541982D01*
G01D02*
Y540487D01*
G01Y545919D02*
Y544424D01*
G01Y549856D02*
Y548361D01*
G01Y553793D02*
Y552298D01*
G01Y557730D02*
Y556235D01*
G01X-35545Y542416D02*
Y540053D01*
G01Y546353D02*
Y543990D01*
G01Y550290D02*
Y547927D01*
G01Y554227D02*
Y551864D01*
G01Y558164D02*
Y555801D01*
G01X-35594Y556258D02*
Y557707D01*
G01Y552321D02*
Y553770D01*
G01Y548384D02*
Y549833D01*
G01Y544447D02*
Y545896D01*
G01Y540510D02*
Y541959D01*
G01D02*
Y540510D01*
G01Y545896D02*
Y544447D01*
G01Y549833D02*
Y548384D01*
G01Y553770D02*
Y552321D01*
G01Y557707D02*
Y556258D01*
G01X-37870Y556477D02*
Y557488D01*
G01Y548603D02*
Y549614D01*
G01Y552540D02*
Y553551D01*
G01Y544666D02*
Y545677D01*
G01Y540729D02*
Y541740D01*
G01D02*
Y540729D01*
G01Y545677D02*
Y544666D01*
G01Y553551D02*
Y552540D01*
G01Y549614D02*
Y548603D01*
G01Y557488D02*
Y556477D01*
G01X-38108Y556500D02*
Y557465D01*
G01Y548626D02*
Y549591D01*
G01Y552563D02*
Y553528D01*
G01Y544689D02*
Y545654D01*
G01Y540752D02*
Y541717D01*
G01D02*
Y540752D01*
G01Y545654D02*
Y544689D01*
G01Y549591D02*
Y548626D01*
G01Y553528D02*
Y552563D01*
G01Y557465D02*
Y556500D01*
G01X-38425Y542416D02*
Y540053D01*
G01Y546353D02*
Y543990D01*
G01Y554227D02*
Y551864D01*
G01Y550290D02*
Y547927D01*
G01Y558164D02*
Y555801D01*
G01X-38108Y577150D02*
X-35350Y577416D01*
G01D02*
X-38108Y577150D01*
G01Y573213D02*
X-35350Y573478D01*
G01D02*
X-38108Y573213D01*
G01X-35350Y579856D02*
X-10630Y579581D01*
G01D02*
X-35350Y579856D01*
G01Y575919D02*
X-10630Y575644D01*
G01D02*
X-35350Y575919D01*
G01Y571982D02*
X-10630Y571707D01*
G01D02*
X-35350Y571982D01*
G01Y568045D02*
X-10630Y567770D01*
G01D02*
X-35350Y568045D01*
G01Y564108D02*
X-10630Y563833D01*
G01D02*
X-35350Y564108D01*
G01Y560171D02*
X-10630Y559896D01*
G01D02*
X-35350Y560171D01*
G01X-35545Y579502D02*
X0D01*
G01X-39607Y579423D02*
X-24508D01*
G01Y577849D02*
X-39607D01*
G01X-35545Y577770D02*
X0D01*
G01X-39607Y576018D02*
X-27992D01*
G01X-35545Y575565D02*
X0D01*
G01X-39607Y575486D02*
X-24508D01*
G01Y573912D02*
X-39607D01*
G01X-35545Y573833D02*
X0D01*
G01X-39607Y572868D02*
X-24843D01*
G01X-35545Y571628D02*
X0D01*
G01X-39607Y571549D02*
X-24508D01*
G01Y569975D02*
X-39607D01*
G01X-35545Y569896D02*
X0D01*
G01X-39607Y568892D02*
X-24843D01*
G01X-35545Y567691D02*
X0D01*
G01X-39607Y567612D02*
X-24508D01*
G01Y566038D02*
X-39607D01*
G01X-35545Y565959D02*
X0D01*
G01X-27992Y565742D02*
X-39607D01*
G01X-35545Y563754D02*
X0D01*
G01X-39607Y563675D02*
X-24508D01*
G01Y562101D02*
X-39607D01*
G01X-35545Y562022D02*
X0D01*
G01X-35545Y559817D02*
X0D01*
G01X-39607Y559738D02*
X-24508D01*
G01X-35350Y577416D02*
X-10630Y577691D01*
G01X-35350Y577416D02*
X-10630Y577691D01*
G01X-35350Y573478D02*
X-10630Y573754D01*
G01X-35350Y573478D02*
X-10630Y573754D01*
G01X-35350Y569541D02*
X-10630Y569817D01*
G01X-35350Y569541D02*
X-10630Y569817D01*
G01X-35350Y565604D02*
X-10630Y565880D01*
G01X-35350Y565604D02*
X-10630Y565880D01*
G01X-35350Y561667D02*
X-10630Y561943D01*
G01X-35350Y561667D02*
X-10630Y561943D01*
G01X-38108Y569276D02*
X-35350Y569541D01*
G01D02*
X-38108Y569276D01*
G01Y565339D02*
X-35350Y565604D01*
G01D02*
X-38108Y565339D01*
G01Y561402D02*
X-35350Y561667D01*
G01D02*
X-38108Y561402D01*
G01Y580122D02*
X-35350Y579856D01*
G01X-38108Y580122D02*
X-35350Y579856D01*
G01X-38108Y576185D02*
X-35350Y575919D01*
G01X-38108Y576185D02*
X-35350Y575919D01*
G01X-38108Y572248D02*
X-35350Y571982D01*
G01X-38108Y572248D02*
X-35350Y571982D01*
G01X-38108Y568311D02*
X-35350Y568045D01*
G01X-38108Y568311D02*
X-35350Y568045D01*
G01X-38108Y564374D02*
X-35350Y564108D01*
G01X-38108Y564374D02*
X-35350Y564108D01*
G01X-38108Y560437D02*
X-35350Y560171D01*
G01X-38108Y560437D02*
X-35350Y560171D01*
G01X-24121Y579731D02*
Y581478D01*
G01Y575794D02*
Y577541D01*
G01Y571857D02*
Y573604D01*
G01Y567920D02*
Y569667D01*
G01Y563983D02*
Y565730D01*
G01Y560046D02*
Y561793D01*
G01D02*
Y560046D01*
G01Y565730D02*
Y563983D01*
G01Y569667D02*
Y567920D01*
G01Y573604D02*
Y571857D01*
G01Y581478D02*
Y579731D01*
G01Y577541D02*
Y575794D01*
G01X-24508Y562101D02*
Y559738D01*
G01Y566038D02*
Y563675D01*
G01Y569975D02*
Y567612D01*
G01Y573912D02*
Y571549D01*
G01Y577849D02*
Y575486D01*
G01Y581786D02*
Y579423D01*
G01X-24843Y572868D02*
Y592514D01*
G01X-26565Y579758D02*
Y581451D01*
G01Y575821D02*
Y577514D01*
G01Y571884D02*
Y573577D01*
G01Y567947D02*
Y569640D01*
G01Y564010D02*
Y565703D01*
G01Y560073D02*
Y561766D01*
G01D02*
Y560073D01*
G01Y565703D02*
Y564010D01*
G01Y569640D02*
Y567947D01*
G01Y573577D02*
Y571884D01*
G01Y581451D02*
Y579758D01*
G01Y577514D02*
Y575821D01*
G01X-26942Y579763D02*
Y581446D01*
G01Y575826D02*
Y577509D01*
G01Y571889D02*
Y573572D01*
G01Y567952D02*
Y569635D01*
G01Y564015D02*
Y565698D01*
G01Y560078D02*
Y561761D01*
G01D02*
Y560078D01*
G01Y565698D02*
Y564015D01*
G01Y569635D02*
Y567952D01*
G01Y573572D02*
Y571889D01*
G01Y581446D02*
Y579763D01*
G01Y577509D02*
Y575826D01*
G01X-27264Y562101D02*
Y559738D01*
G01Y566038D02*
Y563675D01*
G01Y569975D02*
Y567612D01*
G01Y573912D02*
Y571549D01*
G01Y577849D02*
Y575486D01*
G01Y581786D02*
Y579423D01*
G01X-27992Y572868D02*
Y592514D01*
G01X-31941Y579819D02*
Y581391D01*
G01Y575882D02*
Y577454D01*
G01Y571945D02*
Y573517D01*
G01Y568008D02*
Y569580D01*
G01Y564071D02*
Y565643D01*
G01Y560134D02*
Y561706D01*
G01D02*
Y560134D01*
G01Y565643D02*
Y564071D01*
G01Y569580D02*
Y568008D01*
G01Y573517D02*
Y571945D01*
G01Y581391D02*
Y579819D01*
G01Y577454D02*
Y575882D01*
G01X-32318Y579823D02*
Y581386D01*
G01Y575886D02*
Y577449D01*
G01Y571949D02*
Y573512D01*
G01Y568012D02*
Y569575D01*
G01Y564075D02*
Y565638D01*
G01Y560138D02*
Y561701D01*
G01D02*
Y560138D01*
G01Y565638D02*
Y564075D01*
G01Y569575D02*
Y568012D01*
G01Y573512D02*
Y571949D01*
G01Y581386D02*
Y579823D01*
G01Y577449D02*
Y575886D01*
G01X-33153Y579832D02*
Y581377D01*
G01Y575895D02*
Y577440D01*
G01Y571958D02*
Y573503D01*
G01Y568021D02*
Y569566D01*
G01Y564084D02*
Y565629D01*
G01Y560147D02*
Y561692D01*
G01D02*
Y560147D01*
G01Y565629D02*
Y564084D01*
G01Y569566D02*
Y568021D01*
G01Y577440D02*
Y575895D01*
G01Y573503D02*
Y571958D01*
G01Y581377D02*
Y579832D01*
G01X-34136Y579843D02*
Y581366D01*
G01Y575906D02*
Y577429D01*
G01Y571969D02*
Y573492D01*
G01Y568032D02*
Y569555D01*
G01Y564095D02*
Y565618D01*
G01Y560158D02*
Y561681D01*
G01D02*
Y560158D01*
G01Y565618D02*
Y564095D01*
G01Y569555D02*
Y568032D01*
G01Y573492D02*
Y571969D01*
G01Y581366D02*
Y579843D01*
G01Y577429D02*
Y575906D01*
G01X-34607Y562022D02*
Y559817D01*
G01Y565959D02*
Y563754D01*
G01Y569896D02*
Y567691D01*
G01Y577770D02*
Y575565D01*
G01Y573833D02*
Y571628D01*
G01Y581707D02*
Y579502D01*
G01X-35357Y579857D02*
Y581352D01*
G01Y575920D02*
Y577415D01*
G01Y571983D02*
Y573478D01*
G01Y568046D02*
Y569541D01*
G01Y564109D02*
Y565604D01*
G01Y560172D02*
Y561667D01*
G01D02*
Y560172D01*
G01Y565604D02*
Y564109D01*
G01Y569541D02*
Y568046D01*
G01Y573478D02*
Y571983D01*
G01Y581352D02*
Y579857D01*
G01Y577415D02*
Y575920D01*
G01X-35545Y562101D02*
Y559738D01*
G01Y566038D02*
Y563675D01*
G01Y569975D02*
Y567612D01*
G01Y573912D02*
Y571549D01*
G01Y577849D02*
Y575486D01*
G01Y581786D02*
Y579423D01*
G01X-35594Y579880D02*
Y581329D01*
G01Y575943D02*
Y577392D01*
G01Y572006D02*
Y573455D01*
G01Y568069D02*
Y569518D01*
G01Y564132D02*
Y565581D01*
G01Y560195D02*
Y561644D01*
G01D02*
Y560195D01*
G01Y565581D02*
Y564132D01*
G01Y569518D02*
Y568069D01*
G01Y577392D02*
Y575943D01*
G01Y573455D02*
Y572006D01*
G01Y581329D02*
Y579880D01*
G01X-37870Y580099D02*
Y581110D01*
G01Y576162D02*
Y577173D01*
G01Y572225D02*
Y573236D01*
G01Y568288D02*
Y569299D01*
G01Y564351D02*
Y565362D01*
G01Y560414D02*
Y561425D01*
G01D02*
Y560414D01*
G01Y565362D02*
Y564351D01*
G01Y569299D02*
Y568288D01*
G01Y573236D02*
Y572225D01*
G01Y581110D02*
Y580099D01*
G01Y577173D02*
Y576162D01*
G01X-38108Y580122D02*
Y581087D01*
G01Y576185D02*
Y577150D01*
G01Y572248D02*
Y573213D01*
G01Y568311D02*
Y569276D01*
G01Y564374D02*
Y565339D01*
G01Y560437D02*
Y561402D01*
G01D02*
Y560437D01*
G01Y565339D02*
Y564374D01*
G01Y569276D02*
Y568311D01*
G01Y573213D02*
Y572248D01*
G01Y581087D02*
Y580122D01*
G01Y577150D02*
Y576185D01*
G01X-38425Y562101D02*
Y559738D01*
G01Y566038D02*
Y563675D01*
G01Y569975D02*
Y567612D01*
G01Y577849D02*
Y575486D01*
G01Y573912D02*
Y571549D01*
G01Y581786D02*
Y579423D01*
G01X-38108Y600772D02*
X-35350Y601038D01*
G01D02*
X-38108Y600772D01*
G01Y596835D02*
X-35350Y597101D01*
G01D02*
X-38108Y596835D01*
G01Y592898D02*
X-35350Y593164D01*
G01D02*
X-38108Y592898D01*
G01Y588961D02*
X-35350Y589227D01*
G01D02*
X-38108Y588961D01*
G01Y585024D02*
X-35350Y585290D01*
G01D02*
X-38108Y585024D01*
G01Y581087D02*
X-35350Y581353D01*
G01D02*
X-38108Y581087D01*
G01X-35350Y599541D02*
X-10630Y599266D01*
G01D02*
X-35350Y599541D01*
G01Y595604D02*
X-10630Y595329D01*
G01D02*
X-35350Y595604D01*
G01Y591667D02*
X-10630Y591392D01*
G01D02*
X-35350Y591667D01*
G01Y587730D02*
X-10630Y587455D01*
G01D02*
X-35350Y587730D01*
G01Y583793D02*
X-10630Y583518D01*
G01D02*
X-35350Y583793D01*
G01X-24508Y601471D02*
X-39607D01*
G01X-35545Y601392D02*
X0D01*
G01X-39607Y599640D02*
X-27992D01*
G01X-35545Y599187D02*
X0D01*
G01X-39607Y599108D02*
X-24508D01*
G01Y597534D02*
X-39607D01*
G01X-35545Y597455D02*
X0D01*
G01X-39607Y596490D02*
X-24843D01*
G01X-35545Y595250D02*
X0D01*
G01X-39607Y595171D02*
X-24508D01*
G01Y593597D02*
X-39607D01*
G01X-35545Y593518D02*
X0D01*
G01X-39607Y592514D02*
X-24843D01*
G01X-35545Y591313D02*
X0D01*
G01X-39607Y591234D02*
X-24508D01*
G01Y589660D02*
X-39607D01*
G01X-35545Y589581D02*
X0D01*
G01X-27992Y589364D02*
X-39607D01*
G01X-35545Y587376D02*
X0D01*
G01X-39607Y587297D02*
X-24508D01*
G01Y585723D02*
X-39607D01*
G01X-35545Y585644D02*
X0D01*
G01X-35545Y583439D02*
X0D01*
G01X-39607Y583360D02*
X-24508D01*
G01Y581786D02*
X-39607D01*
G01X-35545Y581707D02*
X0D01*
G01X-35350Y601038D02*
X-10630Y601313D01*
G01X-35350Y601038D02*
X-10630Y601313D01*
G01X-35350Y597101D02*
X-10630Y597376D01*
G01X-35350Y597101D02*
X-10630Y597376D01*
G01X-35350Y593164D02*
X-10630Y593439D01*
G01X-35350Y593164D02*
X-10630Y593439D01*
G01X-35350Y589227D02*
X-10630Y589502D01*
G01X-35350Y589227D02*
X-10630Y589502D01*
G01X-35350Y585290D02*
X-10630Y585565D01*
G01X-35350Y585290D02*
X-10630Y585565D01*
G01X-35350Y581353D02*
X-10630Y581628D01*
G01X-35350Y581353D02*
X-10630Y581628D01*
G01X-38108Y599807D02*
X-35350Y599541D01*
G01X-38108Y599807D02*
X-35350Y599541D01*
G01X-38108Y595870D02*
X-35350Y595604D01*
G01X-38108Y595870D02*
X-35350Y595604D01*
G01X-38108Y591933D02*
X-35350Y591667D01*
G01X-38108Y591933D02*
X-35350Y591667D01*
G01X-38108Y587996D02*
X-35350Y587730D01*
G01X-38108Y587996D02*
X-35350Y587730D01*
G01X-38108Y584059D02*
X-35350Y583793D01*
G01X-38108Y584059D02*
X-35350Y583793D01*
G01X-24121Y599416D02*
Y601163D01*
G01Y595479D02*
Y597226D01*
G01Y591542D02*
Y593289D01*
G01Y587605D02*
Y589352D01*
G01Y583668D02*
Y585415D01*
G01D02*
Y583668D01*
G01Y589352D02*
Y587605D01*
G01Y593289D02*
Y591542D01*
G01Y597226D02*
Y595479D01*
G01Y601163D02*
Y599416D01*
G01X-24508Y585723D02*
Y583360D01*
G01Y589660D02*
Y587297D01*
G01Y593597D02*
Y591234D01*
G01Y597534D02*
Y595171D01*
G01Y601471D02*
Y599108D01*
G01X-24843Y596490D02*
Y616136D01*
G01X-26565Y599443D02*
Y601136D01*
G01Y595506D02*
Y597199D01*
G01Y591569D02*
Y593262D01*
G01Y587632D02*
Y589325D01*
G01Y583695D02*
Y585388D01*
G01D02*
Y583695D01*
G01Y589325D02*
Y587632D01*
G01Y593262D02*
Y591569D01*
G01Y597199D02*
Y595506D01*
G01Y601136D02*
Y599443D01*
G01X-26942Y599448D02*
Y601131D01*
G01Y595511D02*
Y597194D01*
G01Y591574D02*
Y593257D01*
G01Y587637D02*
Y589320D01*
G01Y583700D02*
Y585383D01*
G01D02*
Y583700D01*
G01Y589320D02*
Y587637D01*
G01Y593257D02*
Y591574D01*
G01Y597194D02*
Y595511D01*
G01Y601131D02*
Y599448D01*
G01X-27264Y585723D02*
Y583360D01*
G01Y589660D02*
Y587297D01*
G01Y593597D02*
Y591234D01*
G01Y597534D02*
Y595171D01*
G01Y601471D02*
Y599108D01*
G01X-27992Y596490D02*
Y616136D01*
G01X-31941Y599504D02*
Y601076D01*
G01Y595567D02*
Y597139D01*
G01Y591630D02*
Y593202D01*
G01Y587693D02*
Y589265D01*
G01Y583756D02*
Y585328D01*
G01D02*
Y583756D01*
G01Y589265D02*
Y587693D01*
G01Y593202D02*
Y591630D01*
G01Y597139D02*
Y595567D01*
G01Y601076D02*
Y599504D01*
G01X-32318Y599508D02*
Y601071D01*
G01Y595571D02*
Y597134D01*
G01Y591634D02*
Y593197D01*
G01Y587697D02*
Y589260D01*
G01Y583760D02*
Y585323D01*
G01D02*
Y583760D01*
G01Y589260D02*
Y587697D01*
G01Y593197D02*
Y591634D01*
G01Y597134D02*
Y595571D01*
G01Y601071D02*
Y599508D01*
G01X-33153Y599517D02*
Y601062D01*
G01Y595580D02*
Y597125D01*
G01Y591643D02*
Y593188D01*
G01Y587706D02*
Y589251D01*
G01Y583769D02*
Y585314D01*
G01D02*
Y583769D01*
G01Y589251D02*
Y587706D01*
G01Y593188D02*
Y591643D01*
G01Y597125D02*
Y595580D01*
G01Y601062D02*
Y599517D01*
G01X-34136Y599528D02*
Y601051D01*
G01Y595591D02*
Y597114D01*
G01Y591654D02*
Y593177D01*
G01Y587717D02*
Y589240D01*
G01Y583780D02*
Y585303D01*
G01D02*
Y583780D01*
G01Y589240D02*
Y587717D01*
G01Y593177D02*
Y591654D01*
G01Y597114D02*
Y595591D01*
G01Y601051D02*
Y599528D01*
G01X-34607Y585644D02*
Y583439D01*
G01Y589581D02*
Y587376D01*
G01Y593518D02*
Y591313D01*
G01Y601392D02*
Y599187D01*
G01Y597455D02*
Y595250D01*
G01X-35357Y599542D02*
Y601037D01*
G01Y595605D02*
Y597100D01*
G01Y591668D02*
Y593163D01*
G01Y587731D02*
Y589226D01*
G01Y583794D02*
Y585289D01*
G01D02*
Y583794D01*
G01Y589226D02*
Y587731D01*
G01Y593163D02*
Y591668D01*
G01Y597100D02*
Y595605D01*
G01Y601037D02*
Y599542D01*
G01X-35545Y585723D02*
Y583360D01*
G01Y589660D02*
Y587297D01*
G01Y593597D02*
Y591234D01*
G01Y597534D02*
Y595171D01*
G01Y601471D02*
Y599108D01*
G01X-35594Y599565D02*
Y601014D01*
G01Y595628D02*
Y597077D01*
G01Y591691D02*
Y593140D01*
G01Y587754D02*
Y589203D01*
G01Y583817D02*
Y585266D01*
G01D02*
Y583817D01*
G01Y589203D02*
Y587754D01*
G01Y593140D02*
Y591691D01*
G01Y597077D02*
Y595628D01*
G01Y601014D02*
Y599565D01*
G01X-37870Y599784D02*
Y600795D01*
G01Y595847D02*
Y596858D01*
G01Y591910D02*
Y592921D01*
G01Y587973D02*
Y588984D01*
G01Y584036D02*
Y585047D01*
G01D02*
Y584036D01*
G01Y588984D02*
Y587973D01*
G01Y592921D02*
Y591910D01*
G01Y596858D02*
Y595847D01*
G01Y600795D02*
Y599784D01*
G01X-38108Y599807D02*
Y600772D01*
G01Y595870D02*
Y596835D01*
G01Y591933D02*
Y592898D01*
G01Y587996D02*
Y588961D01*
G01Y584059D02*
Y585024D01*
G01D02*
Y584059D01*
G01Y588961D02*
Y587996D01*
G01Y592898D02*
Y591933D01*
G01Y596835D02*
Y595870D01*
G01Y600772D02*
Y599807D01*
G01X-38425Y585723D02*
Y583360D01*
G01Y589660D02*
Y587297D01*
G01Y593597D02*
Y591234D01*
G01Y601471D02*
Y599108D01*
G01Y597534D02*
Y595171D01*
G01X-35350Y620723D02*
X-10630Y620998D01*
G01X-35350Y620723D02*
X-10630Y620998D01*
G01X-38108Y620457D02*
X-35350Y620723D01*
G01D02*
X-38108Y620457D01*
G01Y616520D02*
X-35350Y616786D01*
G01D02*
X-38108Y616520D01*
G01Y612583D02*
X-35350Y612849D01*
G01D02*
X-38108Y612583D01*
G01Y608646D02*
X-35350Y608912D01*
G01D02*
X-38108Y608646D01*
G01Y604709D02*
X-35350Y604975D01*
G01D02*
X-38108Y604709D01*
G01Y623429D02*
X-35350Y623164D01*
G01X-38108Y623429D02*
X-35350Y623164D01*
G01X-38108Y619492D02*
X-35350Y619227D01*
G01X-38108Y619492D02*
X-35350Y619227D01*
G01X-38108Y615555D02*
X-35350Y615290D01*
G01X-38108Y615555D02*
X-35350Y615290D01*
G01X-38108Y611618D02*
X-35350Y611353D01*
G01X-38108Y611618D02*
X-35350Y611353D01*
G01X-38108Y607681D02*
X-35350Y607416D01*
G01X-38108Y607681D02*
X-35350Y607416D01*
G01X-38108Y603744D02*
X-35350Y603478D01*
G01X-38108Y603744D02*
X-35350Y603478D01*
G01Y623164D02*
X-10630Y622888D01*
G01D02*
X-35350Y623164D01*
G01Y619227D02*
X-10630Y618951D01*
G01D02*
X-35350Y619227D01*
G01Y615290D02*
X-10630Y615014D01*
G01D02*
X-35350Y615290D01*
G01Y611353D02*
X-10630Y611077D01*
G01D02*
X-35350Y611353D01*
G01Y607416D02*
X-10630Y607140D01*
G01D02*
X-35350Y607416D01*
G01Y603478D02*
X-10630Y603203D01*
G01D02*
X-35350Y603478D01*
G01X-35545Y622809D02*
X0D01*
G01X-39607Y622730D02*
X-24508D01*
G01Y621156D02*
X-39607D01*
G01X-35545Y621077D02*
X0D01*
G01X-39607Y620112D02*
X-24843D01*
G01X-35545Y618872D02*
X0D01*
G01X-39607Y618793D02*
X-24508D01*
G01Y617219D02*
X-39607D01*
G01X-35545Y617140D02*
X0D01*
G01X-39607Y616136D02*
X-24843D01*
G01X-35545Y614935D02*
X0D01*
G01X-39607Y614856D02*
X-24508D01*
G01Y613282D02*
X-39607D01*
G01X-35545Y613203D02*
X0D01*
G01X-27992Y612986D02*
X-39607D01*
G01X-35545Y610998D02*
X0D01*
G01X-39607Y610919D02*
X-24508D01*
G01Y609345D02*
X-39607D01*
G01X-35545Y609266D02*
X0D01*
G01X-35545Y607061D02*
X0D01*
G01X-39607Y606982D02*
X-24508D01*
G01Y605408D02*
X-39607D01*
G01X-35545Y605329D02*
X0D01*
G01X-35545Y603124D02*
X0D01*
G01X-39607Y603045D02*
X-24508D01*
G01X-35350Y616786D02*
X-10630Y617061D01*
G01X-35350Y616786D02*
X-10630Y617061D01*
G01X-35350Y612849D02*
X-10630Y613124D01*
G01X-35350Y612849D02*
X-10630Y613124D01*
G01X-35350Y608912D02*
X-10630Y609187D01*
G01X-35350Y608912D02*
X-10630Y609187D01*
G01X-35350Y604975D02*
X-10630Y605250D01*
G01X-35350Y604975D02*
X-10630Y605250D01*
G01X-24121Y623038D02*
Y624785D01*
G01Y619101D02*
Y620848D01*
G01Y615164D02*
Y616911D01*
G01Y611227D02*
Y612974D01*
G01Y607290D02*
Y609037D01*
G01Y603353D02*
Y605100D01*
G01D02*
Y603353D01*
G01Y609037D02*
Y607290D01*
G01Y612974D02*
Y611227D01*
G01Y616911D02*
Y615164D01*
G01Y620848D02*
Y619101D01*
G01Y624785D02*
Y623038D01*
G01X-24508Y605408D02*
Y603045D01*
G01Y609345D02*
Y606982D01*
G01Y613282D02*
Y610919D01*
G01Y617219D02*
Y614856D01*
G01Y621156D02*
Y618793D01*
G01Y625093D02*
Y622730D01*
G01X-24843Y620112D02*
Y639758D01*
G01X-26565Y623066D02*
Y624758D01*
G01Y619128D02*
Y620821D01*
G01Y615191D02*
Y616884D01*
G01Y611254D02*
Y612947D01*
G01Y607317D02*
Y609010D01*
G01Y603380D02*
Y605073D01*
G01D02*
Y603380D01*
G01Y609010D02*
Y607317D01*
G01Y612947D02*
Y611254D01*
G01Y616884D02*
Y615191D01*
G01Y620821D02*
Y619128D01*
G01Y624758D02*
Y623066D01*
G01X-26942Y623070D02*
Y624753D01*
G01Y619133D02*
Y620816D01*
G01Y615196D02*
Y616879D01*
G01Y611259D02*
Y612942D01*
G01Y607322D02*
Y609005D01*
G01Y603385D02*
Y605068D01*
G01D02*
Y603385D01*
G01Y609005D02*
Y607322D01*
G01Y612942D02*
Y611259D01*
G01Y616879D02*
Y615196D01*
G01Y620816D02*
Y619133D01*
G01Y624753D02*
Y623070D01*
G01X-27264Y605408D02*
Y603045D01*
G01Y609345D02*
Y606982D01*
G01Y613282D02*
Y610919D01*
G01Y617219D02*
Y614856D01*
G01Y621156D02*
Y618793D01*
G01Y625093D02*
Y622730D01*
G01X-27992Y620112D02*
Y639758D01*
G01X-31941Y623126D02*
Y624698D01*
G01Y619189D02*
Y620761D01*
G01Y615252D02*
Y616824D01*
G01Y611315D02*
Y612887D01*
G01Y607378D02*
Y608950D01*
G01Y603441D02*
Y605013D01*
G01D02*
Y603441D01*
G01Y608950D02*
Y607378D01*
G01Y612887D02*
Y611315D01*
G01Y616824D02*
Y615252D01*
G01Y620761D02*
Y619189D01*
G01Y624698D02*
Y623126D01*
G01X-32318Y623130D02*
Y624693D01*
G01Y619193D02*
Y620756D01*
G01Y615256D02*
Y616819D01*
G01Y611319D02*
Y612882D01*
G01Y607382D02*
Y608945D01*
G01Y603445D02*
Y605008D01*
G01D02*
Y603445D01*
G01Y608945D02*
Y607382D01*
G01Y612882D02*
Y611319D01*
G01Y616819D02*
Y615256D01*
G01Y620756D02*
Y619193D01*
G01Y624693D02*
Y623130D01*
G01X-33153Y623139D02*
Y624684D01*
G01Y619202D02*
Y620747D01*
G01Y615265D02*
Y616810D01*
G01Y611328D02*
Y612873D01*
G01Y607391D02*
Y608936D01*
G01Y603454D02*
Y604999D01*
G01D02*
Y603454D01*
G01Y608936D02*
Y607391D01*
G01Y612873D02*
Y611328D01*
G01Y616810D02*
Y615265D01*
G01Y620747D02*
Y619202D01*
G01Y624684D02*
Y623139D01*
G01X-34136Y623150D02*
Y624673D01*
G01Y619213D02*
Y620736D01*
G01Y615276D02*
Y616799D01*
G01Y611339D02*
Y612862D01*
G01Y607402D02*
Y608925D01*
G01Y603465D02*
Y604988D01*
G01D02*
Y603465D01*
G01Y608925D02*
Y607402D01*
G01Y612862D02*
Y611339D01*
G01Y616799D02*
Y615276D01*
G01Y620736D02*
Y619213D01*
G01Y624673D02*
Y623150D01*
G01X-34607Y609266D02*
Y607061D01*
G01Y605329D02*
Y603124D01*
G01Y613203D02*
Y610998D01*
G01Y617140D02*
Y614935D01*
G01Y625014D02*
Y622809D01*
G01Y621077D02*
Y618872D01*
G01X-35357Y623164D02*
Y624659D01*
G01Y619227D02*
Y620722D01*
G01Y615290D02*
Y616785D01*
G01Y611353D02*
Y612848D01*
G01Y607416D02*
Y608911D01*
G01Y603479D02*
Y604974D01*
G01D02*
Y603479D01*
G01Y608911D02*
Y607416D01*
G01Y612848D02*
Y611353D01*
G01Y616785D02*
Y615290D01*
G01Y620722D02*
Y619227D01*
G01Y624659D02*
Y623164D01*
G01X-35545Y605408D02*
Y603045D01*
G01Y609345D02*
Y606982D01*
G01Y613282D02*
Y610919D01*
G01Y617219D02*
Y614856D01*
G01Y621156D02*
Y618793D01*
G01Y625093D02*
Y622730D01*
G01X-35594Y619250D02*
Y620699D01*
G01Y615313D02*
Y616762D01*
G01Y611376D02*
Y612825D01*
G01Y607439D02*
Y608888D01*
G01Y603502D02*
Y604951D01*
G01D02*
Y603502D01*
G01Y608888D02*
Y607439D01*
G01Y612825D02*
Y611376D01*
G01Y616762D02*
Y615313D01*
G01Y620699D02*
Y619250D01*
G01X-37870Y619469D02*
Y620480D01*
G01Y615532D02*
Y616543D01*
G01Y611595D02*
Y612606D01*
G01Y607658D02*
Y608669D01*
G01Y603721D02*
Y604732D01*
G01D02*
Y603721D01*
G01Y608669D02*
Y607658D01*
G01Y612606D02*
Y611595D01*
G01Y616543D02*
Y615532D01*
G01Y620480D02*
Y619469D01*
G01X-38108Y619492D02*
Y620457D01*
G01Y615555D02*
Y616520D01*
G01Y611618D02*
Y612583D01*
G01Y607681D02*
Y608646D01*
G01Y603744D02*
Y604709D01*
G01D02*
Y603744D01*
G01Y608646D02*
Y607681D01*
G01Y612583D02*
Y611618D01*
G01Y616520D02*
Y615555D01*
G01Y620457D02*
Y619492D01*
G01X-38425Y605408D02*
Y603045D01*
G01Y609345D02*
Y606982D01*
G01Y613282D02*
Y610919D01*
G01Y617219D02*
Y614856D01*
G01Y625093D02*
Y622730D01*
G01Y621156D02*
Y618793D01*
G01X-35350Y642849D02*
X-10630Y642573D01*
G01D02*
X-35350Y642849D01*
G01Y638912D02*
X-10630Y638636D01*
G01D02*
X-35350Y638912D01*
G01Y634975D02*
X-10630Y634699D01*
G01D02*
X-35350Y634975D01*
G01X-39607Y643734D02*
X-24843D01*
G01X-35545Y642494D02*
X0D01*
G01X-39607Y642416D02*
X-24508D01*
G01Y640841D02*
X-39607D01*
G01X-35545Y640762D02*
X0D01*
G01X-39607Y639758D02*
X-24843D01*
G01X-35545Y638557D02*
X0D01*
G01X-39607Y638478D02*
X-24508D01*
G01Y636904D02*
X-39607D01*
G01X-35545Y636825D02*
X0D01*
G01X-27992Y636608D02*
X-39607D01*
G01X-35545Y634620D02*
X0D01*
G01X-39607Y634541D02*
X-24508D01*
G01Y632967D02*
X-39607D01*
G01X-35545Y632888D02*
X0D01*
G01X-35545Y630683D02*
X0D01*
G01X-39607Y630604D02*
X-24508D01*
G01Y629030D02*
X-39607D01*
G01X-35545Y628951D02*
X0D01*
G01X-35545Y626746D02*
X0D01*
G01X-39607Y626667D02*
X-24508D01*
G01X-35350Y640408D02*
X-10630Y640683D01*
G01X-35350Y640408D02*
X-10630Y640683D01*
G01X-35350Y636471D02*
X-10630Y636746D01*
G01X-35350Y636471D02*
X-10630Y636746D01*
G01X-35350Y632534D02*
X-10630Y632809D01*
G01X-35350Y632534D02*
X-10630Y632809D01*
G01X-35350Y628597D02*
X-10630Y628872D01*
G01X-35350Y628597D02*
X-10630Y628872D01*
G01X-35350Y624660D02*
X-10630Y624935D01*
G01X-35350Y624660D02*
X-10630Y624935D01*
G01X-38108Y644079D02*
X-35350Y644345D01*
G01D02*
X-38108Y644079D01*
G01Y640142D02*
X-35350Y640408D01*
G01D02*
X-38108Y640142D01*
G01Y636205D02*
X-35350Y636471D01*
G01D02*
X-38108Y636205D01*
G01Y632268D02*
X-35350Y632534D01*
G01D02*
X-38108Y632268D01*
G01Y628331D02*
X-35350Y628597D01*
G01D02*
X-38108Y628331D01*
G01Y624394D02*
X-35350Y624660D01*
G01D02*
X-38108Y624394D01*
G01Y643114D02*
X-35350Y642849D01*
G01X-38108Y643114D02*
X-35350Y642849D01*
G01X-38108Y639177D02*
X-35350Y638912D01*
G01X-38108Y639177D02*
X-35350Y638912D01*
G01X-38108Y635240D02*
X-35350Y634975D01*
G01X-38108Y635240D02*
X-35350Y634975D01*
G01X-38108Y631303D02*
X-35350Y631038D01*
G01X-38108Y631303D02*
X-35350Y631038D01*
G01X-38108Y627366D02*
X-35350Y627101D01*
G01X-38108Y627366D02*
X-35350Y627101D01*
G01Y631038D02*
X-10630Y630762D01*
G01D02*
X-35350Y631038D01*
G01Y627101D02*
X-10630Y626825D01*
G01D02*
X-35350Y627101D01*
G01X-24508Y625093D02*
X-39607D01*
G01X-35545Y625014D02*
X0D01*
G01X-39607Y623262D02*
X-27992D01*
G01X-24121Y642723D02*
Y644470D01*
G01Y638786D02*
Y640533D01*
G01Y634849D02*
Y636596D01*
G01Y626975D02*
Y628722D01*
G01Y630912D02*
Y632659D01*
G01D02*
Y630912D01*
G01Y628722D02*
Y626975D01*
G01Y636596D02*
Y634849D01*
G01Y640533D02*
Y638786D01*
G01Y644470D02*
Y642723D01*
G01X-24508Y629030D02*
Y626667D01*
G01Y632967D02*
Y630604D01*
G01Y636904D02*
Y634541D01*
G01Y640841D02*
Y638478D01*
G01Y644778D02*
Y642416D01*
G01X-24843Y643734D02*
Y663380D01*
G01X-26565Y642751D02*
Y644443D01*
G01Y638814D02*
Y640506D01*
G01Y634877D02*
Y636569D01*
G01Y630940D02*
Y632632D01*
G01Y627003D02*
Y628695D01*
G01D02*
Y627003D01*
G01Y632632D02*
Y630940D01*
G01Y636569D02*
Y634877D01*
G01Y640506D02*
Y638814D01*
G01Y644443D02*
Y642751D01*
G01X-26942Y642755D02*
Y644438D01*
G01Y638818D02*
Y640501D01*
G01Y634881D02*
Y636564D01*
G01Y630944D02*
Y632627D01*
G01Y627007D02*
Y628690D01*
G01D02*
Y627007D01*
G01Y632627D02*
Y630944D01*
G01Y636564D02*
Y634881D01*
G01Y640501D02*
Y638818D01*
G01Y644438D02*
Y642755D01*
G01X-27264Y629030D02*
Y626667D01*
G01Y632967D02*
Y630604D01*
G01Y636904D02*
Y634541D01*
G01Y640841D02*
Y638478D01*
G01Y644778D02*
Y642416D01*
G01X-27992Y643734D02*
Y663380D01*
G01X-31941Y642811D02*
Y644383D01*
G01Y638874D02*
Y640446D01*
G01Y634937D02*
Y636509D01*
G01Y627063D02*
Y628635D01*
G01Y631000D02*
Y632572D01*
G01D02*
Y631000D01*
G01Y628635D02*
Y627063D01*
G01Y636509D02*
Y634937D01*
G01Y640446D02*
Y638874D01*
G01Y644383D02*
Y642811D01*
G01X-32318Y642815D02*
Y644378D01*
G01Y638878D02*
Y640441D01*
G01Y634941D02*
Y636504D01*
G01Y631004D02*
Y632567D01*
G01Y627067D02*
Y628630D01*
G01D02*
Y627067D01*
G01Y632567D02*
Y631004D01*
G01Y636504D02*
Y634941D01*
G01Y640441D02*
Y638878D01*
G01Y644378D02*
Y642815D01*
G01X-33153Y642824D02*
Y644369D01*
G01Y638887D02*
Y640432D01*
G01Y634950D02*
Y636495D01*
G01Y631013D02*
Y632558D01*
G01Y627076D02*
Y628621D01*
G01D02*
Y627076D01*
G01Y632558D02*
Y631013D01*
G01Y636495D02*
Y634950D01*
G01Y640432D02*
Y638887D01*
G01Y644369D02*
Y642824D01*
G01X-34136Y642835D02*
Y644358D01*
G01Y638898D02*
Y640421D01*
G01Y634961D02*
Y636484D01*
G01Y631024D02*
Y632547D01*
G01Y627087D02*
Y628610D01*
G01D02*
Y627087D01*
G01Y632547D02*
Y631024D01*
G01Y636484D02*
Y634961D01*
G01Y640421D02*
Y638898D01*
G01Y644358D02*
Y642835D01*
G01X-34607Y632888D02*
Y630683D01*
G01Y628951D02*
Y626746D01*
G01Y636825D02*
Y634620D01*
G01Y640762D02*
Y638557D01*
G01Y644699D02*
Y642494D01*
G01X-35357Y642849D02*
Y644344D01*
G01Y638912D02*
Y640407D01*
G01Y634975D02*
Y636470D01*
G01Y631038D02*
Y632533D01*
G01Y627101D02*
Y628596D01*
G01D02*
Y627101D01*
G01Y632533D02*
Y631038D01*
G01Y636470D02*
Y634975D01*
G01Y640407D02*
Y638912D01*
G01Y644344D02*
Y642849D01*
G01X-35545Y629030D02*
Y626667D01*
G01Y632967D02*
Y630604D01*
G01Y636904D02*
Y634541D01*
G01Y640841D02*
Y638478D01*
G01Y644778D02*
Y642416D01*
G01X-35594Y642872D02*
Y644321D01*
G01Y638935D02*
Y640384D01*
G01Y634998D02*
Y636447D01*
G01Y631061D02*
Y632510D01*
G01Y627124D02*
Y628573D01*
G01Y623187D02*
Y624636D01*
G01D02*
Y623187D01*
G01Y628573D02*
Y627124D01*
G01Y632510D02*
Y631061D01*
G01Y636447D02*
Y634998D01*
G01Y640384D02*
Y638935D01*
G01Y644321D02*
Y642872D01*
G01X-37870Y643091D02*
Y644102D01*
G01Y639154D02*
Y640165D01*
G01Y635217D02*
Y636228D01*
G01Y631280D02*
Y632291D01*
G01Y623406D02*
Y624417D01*
G01Y627343D02*
Y628354D01*
G01D02*
Y627343D01*
G01Y624417D02*
Y623406D01*
G01Y632291D02*
Y631280D01*
G01Y636228D02*
Y635217D01*
G01Y640165D02*
Y639154D01*
G01Y644102D02*
Y643091D01*
G01X-38108Y643114D02*
Y644079D01*
G01Y639177D02*
Y640142D01*
G01Y635240D02*
Y636205D01*
G01Y631303D02*
Y632268D01*
G01Y623429D02*
Y624394D01*
G01Y627366D02*
Y628331D01*
G01Y624394D02*
Y623429D01*
G01Y628331D02*
Y627366D01*
G01Y632268D02*
Y631303D01*
G01Y636205D02*
Y635240D01*
G01Y640142D02*
Y639177D01*
G01Y644079D02*
Y643114D01*
G01X-38425Y632967D02*
Y630604D01*
G01Y629030D02*
Y626667D01*
G01Y636904D02*
Y634541D01*
G01Y640841D02*
Y638478D01*
G01Y644778D02*
Y642416D01*
G01X-38108Y663764D02*
X-35350Y664030D01*
G01D02*
X-38108Y663764D01*
G01Y659827D02*
X-35350Y660093D01*
G01D02*
X-38108Y659827D01*
G01Y655890D02*
X-35350Y656156D01*
G01D02*
X-38108Y655890D01*
G01Y651953D02*
X-35350Y652219D01*
G01D02*
X-38108Y651953D01*
G01Y648016D02*
X-35350Y648282D01*
G01D02*
X-38108Y648016D01*
G01X-35350Y662534D02*
X-10630Y662258D01*
G01D02*
X-35350Y662534D01*
G01Y658597D02*
X-10630Y658321D01*
G01D02*
X-35350Y658597D01*
G01Y654660D02*
X-10630Y654384D01*
G01D02*
X-35350Y654660D01*
G01Y650723D02*
X-10630Y650447D01*
G01D02*
X-35350Y650723D01*
G01Y646786D02*
X-10630Y646510D01*
G01D02*
X-35350Y646786D01*
G01X-24508Y664463D02*
X-39607D01*
G01X-35545Y664384D02*
X0D01*
G01X-39607Y663380D02*
X-24843D01*
G01X-35545Y662179D02*
X0D01*
G01X-39607Y662101D02*
X-24508D01*
G01Y660526D02*
X-39607D01*
G01X-35545Y660447D02*
X0D01*
G01X-27992Y660230D02*
X-39607D01*
G01X-35545Y658242D02*
X0D01*
G01X-39607Y658164D02*
X-24508D01*
G01Y656589D02*
X-39607D01*
G01X-35545Y656510D02*
X0D01*
G01X-35545Y654305D02*
X0D01*
G01X-39607Y654227D02*
X-24508D01*
G01Y652652D02*
X-39607D01*
G01X-35545Y652573D02*
X0D01*
G01X-35545Y650368D02*
X0D01*
G01X-39607Y650290D02*
X-24508D01*
G01Y648715D02*
X-39607D01*
G01X-35545Y648636D02*
X0D01*
G01X-39607Y646884D02*
X-27992D01*
G01X-35545Y646431D02*
X0D01*
G01X-39607Y646353D02*
X-24508D01*
G01Y644778D02*
X-39607D01*
G01X-35545Y644699D02*
X0D01*
G01X-35350Y664030D02*
X-10630Y664305D01*
G01X-35350Y664030D02*
X-10630Y664305D01*
G01X-35350Y660093D02*
X-10630Y660368D01*
G01X-35350Y660093D02*
X-10630Y660368D01*
G01X-35350Y656156D02*
X-10630Y656431D01*
G01X-35350Y656156D02*
X-10630Y656431D01*
G01X-35350Y652219D02*
X-10630Y652494D01*
G01X-35350Y652219D02*
X-10630Y652494D01*
G01X-35350Y648282D02*
X-10630Y648557D01*
G01X-35350Y648282D02*
X-10630Y648557D01*
G01X-35350Y644345D02*
X-10630Y644620D01*
G01X-35350Y644345D02*
X-10630Y644620D01*
G01X-38108Y662799D02*
X-35350Y662534D01*
G01X-38108Y662799D02*
X-35350Y662534D01*
G01X-38108Y658862D02*
X-35350Y658597D01*
G01X-38108Y658862D02*
X-35350Y658597D01*
G01X-38108Y654925D02*
X-35350Y654660D01*
G01X-38108Y654925D02*
X-35350Y654660D01*
G01X-38108Y650988D02*
X-35350Y650723D01*
G01X-38108Y650988D02*
X-35350Y650723D01*
G01X-38108Y647051D02*
X-35350Y646786D01*
G01X-38108Y647051D02*
X-35350Y646786D01*
G01X-24121Y662408D02*
Y664155D01*
G01Y658471D02*
Y660218D01*
G01Y650597D02*
Y652344D01*
G01Y654534D02*
Y656281D01*
G01Y646660D02*
Y648407D01*
G01D02*
Y646660D01*
G01Y656281D02*
Y654534D01*
G01Y652344D02*
Y650597D01*
G01Y660218D02*
Y658471D01*
G01Y664155D02*
Y662408D01*
G01X-24508Y648715D02*
Y646353D01*
G01Y652652D02*
Y650290D01*
G01Y656589D02*
Y654227D01*
G01Y660526D02*
Y658164D01*
G01Y664463D02*
Y662101D01*
G01X-26565Y662436D02*
Y664128D01*
G01Y658499D02*
Y660191D01*
G01Y654562D02*
Y656254D01*
G01Y650625D02*
Y652317D01*
G01Y646688D02*
Y648380D01*
G01D02*
Y646688D01*
G01Y652317D02*
Y650625D01*
G01Y656254D02*
Y654562D01*
G01Y660191D02*
Y658499D01*
G01Y664128D02*
Y662436D01*
G01X-26942Y662440D02*
Y664123D01*
G01Y658503D02*
Y660186D01*
G01Y654566D02*
Y656249D01*
G01Y650629D02*
Y652312D01*
G01Y646692D02*
Y648375D01*
G01D02*
Y646692D01*
G01Y652312D02*
Y650629D01*
G01Y656249D02*
Y654566D01*
G01Y660186D02*
Y658503D01*
G01Y664123D02*
Y662440D01*
G01X-27264Y648715D02*
Y646353D01*
G01Y652652D02*
Y650290D01*
G01Y656589D02*
Y654227D01*
G01Y660526D02*
Y658164D01*
G01Y664463D02*
Y662101D01*
G01X-31941Y662496D02*
Y664068D01*
G01Y658559D02*
Y660131D01*
G01Y650685D02*
Y652257D01*
G01Y654622D02*
Y656194D01*
G01Y646748D02*
Y648320D01*
G01D02*
Y646748D01*
G01Y656194D02*
Y654622D01*
G01Y652257D02*
Y650685D01*
G01Y660131D02*
Y658559D01*
G01Y664068D02*
Y662496D01*
G01X-32318Y662500D02*
Y664064D01*
G01Y658563D02*
Y660127D01*
G01Y650689D02*
Y652253D01*
G01Y654626D02*
Y656190D01*
G01Y646752D02*
Y648316D01*
G01D02*
Y646752D01*
G01Y656190D02*
Y654626D01*
G01Y652253D02*
Y650689D01*
G01Y660127D02*
Y658563D01*
G01Y664064D02*
Y662500D01*
G01X-33153Y662509D02*
Y664054D01*
G01Y658572D02*
Y660117D01*
G01Y654635D02*
Y656180D01*
G01Y650698D02*
Y652243D01*
G01Y646761D02*
Y648306D01*
G01D02*
Y646761D01*
G01Y652243D02*
Y650698D01*
G01Y656180D02*
Y654635D01*
G01Y660117D02*
Y658572D01*
G01Y664054D02*
Y662509D01*
G01X-34136Y662520D02*
Y664043D01*
G01Y658583D02*
Y660106D01*
G01Y650709D02*
Y652232D01*
G01Y654646D02*
Y656169D01*
G01Y646772D02*
Y648295D01*
G01D02*
Y646772D01*
G01Y656169D02*
Y654646D01*
G01Y652232D02*
Y650709D01*
G01Y660106D02*
Y658583D01*
G01Y664043D02*
Y662520D01*
G01X-34607Y648636D02*
Y646431D01*
G01Y656510D02*
Y654305D01*
G01Y652573D02*
Y650368D01*
G01Y660447D02*
Y658242D01*
G01Y664384D02*
Y662179D01*
G01X-35357Y662534D02*
Y664029D01*
G01Y658597D02*
Y660092D01*
G01Y654660D02*
Y656155D01*
G01Y650723D02*
Y652218D01*
G01Y646786D02*
Y648281D01*
G01D02*
Y646786D01*
G01Y652218D02*
Y650723D01*
G01Y656155D02*
Y654660D01*
G01Y660092D02*
Y658597D01*
G01Y664029D02*
Y662534D01*
G01X-35545Y648715D02*
Y646353D01*
G01Y652652D02*
Y650290D01*
G01Y656589D02*
Y654227D01*
G01Y660526D02*
Y658164D01*
G01Y664463D02*
Y662101D01*
G01X-35594Y662557D02*
Y664006D01*
G01Y658620D02*
Y660069D01*
G01Y654683D02*
Y656132D01*
G01Y650746D02*
Y652195D01*
G01Y646809D02*
Y648258D01*
G01D02*
Y646809D01*
G01Y652195D02*
Y650746D01*
G01Y656132D02*
Y654683D01*
G01Y660069D02*
Y658620D01*
G01Y664006D02*
Y662557D01*
G01X-37870Y662777D02*
Y663787D01*
G01Y658840D02*
Y659850D01*
G01Y654903D02*
Y655913D01*
G01Y647028D02*
Y648039D01*
G01Y650966D02*
Y651976D01*
G01D02*
Y650966D01*
G01Y648039D02*
Y647028D01*
G01Y655913D02*
Y654903D01*
G01Y659850D02*
Y658840D01*
G01Y663787D02*
Y662777D01*
G01X-38108Y662799D02*
Y663764D01*
G01Y658862D02*
Y659827D01*
G01Y654925D02*
Y655890D01*
G01Y647051D02*
Y648016D01*
G01Y650988D02*
Y651953D01*
G01Y648016D02*
Y647051D01*
G01Y651953D02*
Y650988D01*
G01Y655890D02*
Y654925D01*
G01Y659827D02*
Y658862D01*
G01Y663764D02*
Y662799D01*
G01X-38425Y648715D02*
Y646353D01*
G01Y656589D02*
Y654227D01*
G01Y652652D02*
Y650290D01*
G01Y660526D02*
Y658164D01*
G01Y664463D02*
Y662101D01*
G01X-38108Y683449D02*
X-35350Y683715D01*
G01D02*
X-38108Y683449D01*
G01Y679512D02*
X-35350Y679778D01*
G01D02*
X-38108Y679512D01*
G01Y675575D02*
X-35350Y675841D01*
G01D02*
X-38108Y675575D01*
G01Y671638D02*
X-35350Y671904D01*
G01D02*
X-38108Y671638D01*
G01Y667701D02*
X-35350Y667967D01*
G01D02*
X-38108Y667701D01*
G01Y686421D02*
X-35350Y686156D01*
G01X-38108Y686421D02*
X-35350Y686156D01*
G01X-38108Y682484D02*
X-35350Y682219D01*
G01X-38108Y682484D02*
X-35350Y682219D01*
G01X-38108Y678547D02*
X-35350Y678282D01*
G01X-38108Y678547D02*
X-35350Y678282D01*
G01Y686156D02*
X-10630Y685880D01*
G01D02*
X-35350Y686156D01*
G01Y682219D02*
X-10630Y681943D01*
G01D02*
X-35350Y682219D01*
G01Y678282D02*
X-10630Y678006D01*
G01D02*
X-35350Y678282D01*
G01Y674345D02*
X-10630Y674069D01*
G01D02*
X-35350Y674345D01*
G01Y670408D02*
X-10630Y670132D01*
G01D02*
X-35350Y670408D01*
G01Y666471D02*
X-10630Y666195D01*
G01D02*
X-35350Y666471D01*
G01X-35545Y685801D02*
X0D01*
G01X-39607Y685723D02*
X-24508D01*
G01Y684148D02*
X-39607D01*
G01X-35545Y684069D02*
X0D01*
G01X-27992Y683853D02*
X-39607D01*
G01X-35545Y681864D02*
X0D01*
G01X-39607Y681786D02*
X-24508D01*
G01Y680211D02*
X-39607D01*
G01X-35545Y680132D02*
X0D01*
G01X-35545Y677927D02*
X0D01*
G01X-39607Y677849D02*
X-24508D01*
G01Y676274D02*
X-39607D01*
G01X-35545Y676195D02*
X0D01*
G01X-35545Y673990D02*
X0D01*
G01X-39607Y673912D02*
X-24508D01*
G01Y672337D02*
X-39607D01*
G01X-35545Y672258D02*
X0D01*
G01X-39607Y670506D02*
X-27992D01*
G01X-35545Y670053D02*
X0D01*
G01X-39607Y669975D02*
X-24508D01*
G01Y668400D02*
X-39607D01*
G01X-35545Y668321D02*
X0D01*
G01X-39607Y667356D02*
X-24843D01*
G01X-35545Y666116D02*
X0D01*
G01X-39607Y666038D02*
X-24508D01*
G01X-35350Y683715D02*
X-10630Y683990D01*
G01X-35350Y683715D02*
X-10630Y683990D01*
G01X-35350Y679778D02*
X-10630Y680053D01*
G01X-35350Y679778D02*
X-10630Y680053D01*
G01X-35350Y675841D02*
X-10630Y676116D01*
G01X-35350Y675841D02*
X-10630Y676116D01*
G01X-35350Y671904D02*
X-10630Y672179D01*
G01X-35350Y671904D02*
X-10630Y672179D01*
G01X-35350Y667967D02*
X-10630Y668242D01*
G01X-35350Y667967D02*
X-10630Y668242D01*
G01X-38108Y674610D02*
X-35350Y674345D01*
G01X-38108Y674610D02*
X-35350Y674345D01*
G01X-38108Y670673D02*
X-35350Y670408D01*
G01X-38108Y670673D02*
X-35350Y670408D01*
G01X-38108Y666736D02*
X-35350Y666471D01*
G01X-38108Y666736D02*
X-35350Y666471D01*
G01X-24121Y686030D02*
Y687777D01*
G01Y682093D02*
Y683840D01*
G01Y674219D02*
Y675966D01*
G01Y678156D02*
Y679903D01*
G01Y670282D02*
Y672029D01*
G01Y666345D02*
Y668092D01*
G01D02*
Y666345D01*
G01Y672029D02*
Y670282D01*
G01Y679903D02*
Y678156D01*
G01Y675966D02*
Y674219D01*
G01Y683840D02*
Y682093D01*
G01Y687777D02*
Y686030D01*
G01X-24508Y668400D02*
Y666038D01*
G01Y672337D02*
Y669975D01*
G01Y676274D02*
Y673912D01*
G01Y680211D02*
Y677849D01*
G01Y684148D02*
Y681786D01*
G01Y688085D02*
Y685723D01*
G01X-24843Y667356D02*
Y687002D01*
G01X-26565Y686058D02*
Y687750D01*
G01Y682121D02*
Y683813D01*
G01Y678184D02*
Y679876D01*
G01Y674247D02*
Y675939D01*
G01Y670310D02*
Y672002D01*
G01Y666373D02*
Y668065D01*
G01D02*
Y666373D01*
G01Y672002D02*
Y670310D01*
G01Y675939D02*
Y674247D01*
G01Y679876D02*
Y678184D01*
G01Y683813D02*
Y682121D01*
G01Y687750D02*
Y686058D01*
G01X-26942Y686062D02*
Y687745D01*
G01Y682125D02*
Y683808D01*
G01Y678188D02*
Y679871D01*
G01Y674251D02*
Y675934D01*
G01Y670314D02*
Y671997D01*
G01Y666377D02*
Y668060D01*
G01D02*
Y666377D01*
G01Y671997D02*
Y670314D01*
G01Y675934D02*
Y674251D01*
G01Y679871D02*
Y678188D01*
G01Y683808D02*
Y682125D01*
G01Y687745D02*
Y686062D01*
G01X-27264Y668400D02*
Y666038D01*
G01Y672337D02*
Y669975D01*
G01Y676274D02*
Y673912D01*
G01Y680211D02*
Y677849D01*
G01Y684148D02*
Y681786D01*
G01Y688085D02*
Y685723D01*
G01X-27992Y667356D02*
Y687002D01*
G01X-31941Y686118D02*
Y687690D01*
G01Y682181D02*
Y683753D01*
G01Y674307D02*
Y675879D01*
G01Y678244D02*
Y679816D01*
G01Y670370D02*
Y671942D01*
G01Y666433D02*
Y668005D01*
G01D02*
Y666433D01*
G01Y671942D02*
Y670370D01*
G01Y679816D02*
Y678244D01*
G01Y675879D02*
Y674307D01*
G01Y683753D02*
Y682181D01*
G01Y687690D02*
Y686118D01*
G01X-32318Y686122D02*
Y687686D01*
G01Y682185D02*
Y683749D01*
G01Y674311D02*
Y675875D01*
G01Y678248D02*
Y679812D01*
G01Y670374D02*
Y671938D01*
G01Y666437D02*
Y668001D01*
G01D02*
Y666437D01*
G01Y671938D02*
Y670374D01*
G01Y679812D02*
Y678248D01*
G01Y675875D02*
Y674311D01*
G01Y683749D02*
Y682185D01*
G01Y687686D02*
Y686122D01*
G01X-33153Y686131D02*
Y687676D01*
G01Y682194D02*
Y683739D01*
G01Y678257D02*
Y679802D01*
G01Y674320D02*
Y675865D01*
G01Y670383D02*
Y671928D01*
G01Y666446D02*
Y667991D01*
G01D02*
Y666446D01*
G01Y671928D02*
Y670383D01*
G01Y675865D02*
Y674320D01*
G01Y679802D02*
Y678257D01*
G01Y683739D02*
Y682194D01*
G01Y687676D02*
Y686131D01*
G01X-34136Y686142D02*
Y687666D01*
G01Y682205D02*
Y683728D01*
G01Y674331D02*
Y675854D01*
G01Y678268D02*
Y679791D01*
G01Y670394D02*
Y671917D01*
G01Y666457D02*
Y667980D01*
G01D02*
Y666457D01*
G01Y671917D02*
Y670394D01*
G01Y679791D02*
Y678268D01*
G01Y675854D02*
Y674331D01*
G01Y683728D02*
Y682205D01*
G01Y687666D02*
Y686142D01*
G01X-34607Y672258D02*
Y670053D01*
G01Y668321D02*
Y666116D01*
G01Y676195D02*
Y673990D01*
G01Y684069D02*
Y681864D01*
G01Y680132D02*
Y677927D01*
G01Y688006D02*
Y685801D01*
G01X-35357Y686156D02*
Y687651D01*
G01Y682219D02*
Y683714D01*
G01Y678282D02*
Y679777D01*
G01Y674345D02*
Y675840D01*
G01Y670408D02*
Y671903D01*
G01Y666471D02*
Y667966D01*
G01D02*
Y666471D01*
G01Y671903D02*
Y670408D01*
G01Y675840D02*
Y674345D01*
G01Y679777D02*
Y678282D01*
G01Y683714D02*
Y682219D01*
G01Y687651D02*
Y686156D01*
G01X-35545Y668400D02*
Y666038D01*
G01Y672337D02*
Y669975D01*
G01Y676274D02*
Y673912D01*
G01Y680211D02*
Y677849D01*
G01Y684148D02*
Y681786D01*
G01Y688085D02*
Y685723D01*
G01X-35594Y686179D02*
Y687628D01*
G01Y682242D02*
Y683691D01*
G01Y678305D02*
Y679754D01*
G01Y674368D02*
Y675817D01*
G01Y670431D02*
Y671880D01*
G01Y666494D02*
Y667943D01*
G01D02*
Y666494D01*
G01Y671880D02*
Y670431D01*
G01Y675817D02*
Y674368D01*
G01Y679754D02*
Y678305D01*
G01Y683691D02*
Y682242D01*
G01Y687628D02*
Y686179D01*
G01X-37870Y686399D02*
Y687409D01*
G01Y682462D02*
Y683472D01*
G01Y674588D02*
Y675598D01*
G01Y678525D02*
Y679535D01*
G01Y670651D02*
Y671661D01*
G01Y666714D02*
Y667724D01*
G01D02*
Y666714D01*
G01Y671661D02*
Y670651D01*
G01Y679535D02*
Y678525D01*
G01Y675598D02*
Y674588D01*
G01Y683472D02*
Y682462D01*
G01Y687409D02*
Y686399D01*
G01X-38108Y686421D02*
Y687386D01*
G01Y682484D02*
Y683449D01*
G01Y674610D02*
Y675575D01*
G01Y678547D02*
Y679512D01*
G01Y670673D02*
Y671638D01*
G01Y666736D02*
Y667701D01*
G01D02*
Y666736D01*
G01Y671638D02*
Y670673D01*
G01Y675575D02*
Y674610D01*
G01Y679512D02*
Y678547D01*
G01Y683449D02*
Y682484D01*
G01Y687386D02*
Y686421D01*
G01X-38425Y672337D02*
Y669975D01*
G01Y668400D02*
Y666038D01*
G01Y676274D02*
Y673912D01*
G01Y684148D02*
Y681786D01*
G01Y680211D02*
Y677849D01*
G01Y688085D02*
Y685723D01*
G01X-36560Y703488D02*
G03X-34844Y702947I1716J2451D01*
G01X-27992Y707475D02*
X-39607D01*
G01X-8898Y702947D02*
X-34844D01*
G01X-35350Y699463D02*
X-10630Y699738D01*
G01X-35350Y699463D02*
X-10630Y699738D01*
G01X-35350Y695526D02*
X-10630Y695801D01*
G01X-35350Y695526D02*
X-10630Y695801D01*
G01X-38108Y699197D02*
X-35350Y699463D01*
G01D02*
X-38108Y699197D01*
G01Y695260D02*
X-35350Y695526D01*
G01D02*
X-38108Y695260D01*
G01Y691323D02*
X-35350Y691589D01*
G01D02*
X-38108Y691323D01*
G01Y687386D02*
X-35350Y687652D01*
G01D02*
X-38108Y687386D01*
G01Y698232D02*
X-35350Y697967D01*
G01X-38108Y698232D02*
X-35350Y697967D01*
G01X-38108Y694295D02*
X-35350Y694030D01*
G01X-38108Y694295D02*
X-35350Y694030D01*
G01X-38108Y690358D02*
X-35350Y690093D01*
G01X-38108Y690358D02*
X-35350Y690093D01*
G01Y697967D02*
X-10630Y697691D01*
G01D02*
X-35350Y697967D01*
G01Y694030D02*
X-10630Y693754D01*
G01D02*
X-35350Y694030D01*
G01Y690093D02*
X-10630Y689817D01*
G01D02*
X-35350Y690093D01*
G01X-24508Y699896D02*
X-39607D01*
G01X-35545Y699817D02*
X0D01*
G01X-35545Y697612D02*
X0D01*
G01X-39607Y697534D02*
X-24508D01*
G01Y695959D02*
X-39607D01*
G01X-35545Y695880D02*
X0D01*
G01X-39607Y694128D02*
X-27992D01*
G01X-35545Y693675D02*
X0D01*
G01X-39607Y693597D02*
X-24508D01*
G01Y692022D02*
X-39607D01*
G01X-35545Y691943D02*
X0D01*
G01X-39607Y690978D02*
X-24843D01*
G01X-35545Y689738D02*
X0D01*
G01X-39607Y689660D02*
X-24508D01*
G01Y688085D02*
X-39607D01*
G01X-35545Y688006D02*
X0D01*
G01X-39607Y687002D02*
X-24843D01*
G01X-35350Y691589D02*
X-10630Y691864D01*
G01X-35350Y691589D02*
X-10630Y691864D01*
G01X-35350Y687652D02*
X-10630Y687927D01*
G01X-35350Y687652D02*
X-10630Y687927D01*
G01X-36560Y703488D02*
X-39607Y705621D01*
G01X-24121Y697841D02*
Y699588D01*
G01Y693904D02*
Y695651D01*
G01Y689967D02*
Y691714D01*
G01D02*
Y689967D01*
G01Y695651D02*
Y693904D01*
G01Y699588D02*
Y697841D01*
G01X-24508Y692022D02*
Y689660D01*
G01Y695959D02*
Y693597D01*
G01Y699896D02*
Y697534D01*
G01X-24843Y690978D02*
Y710624D01*
G01X-26565Y697869D02*
Y699561D01*
G01Y693932D02*
Y695624D01*
G01Y689995D02*
Y691687D01*
G01D02*
Y689995D01*
G01Y695624D02*
Y693932D01*
G01Y699561D02*
Y697869D01*
G01X-26942Y697873D02*
Y699556D01*
G01Y693936D02*
Y695619D01*
G01Y689999D02*
Y691682D01*
G01D02*
Y689999D01*
G01Y695619D02*
Y693936D01*
G01Y699556D02*
Y697873D01*
G01X-27264Y692022D02*
Y689660D01*
G01Y695959D02*
Y693597D01*
G01Y699896D02*
Y697534D01*
G01X-27992Y690978D02*
Y710624D01*
G01X-31941Y697929D02*
Y699501D01*
G01Y693992D02*
Y695564D01*
G01Y690055D02*
Y691627D01*
G01D02*
Y690055D01*
G01Y695564D02*
Y693992D01*
G01Y699501D02*
Y697929D01*
G01X-32318Y697933D02*
Y699497D01*
G01Y693996D02*
Y695560D01*
G01Y690059D02*
Y691623D01*
G01D02*
Y690059D01*
G01Y695560D02*
Y693996D01*
G01Y699497D02*
Y697933D01*
G01X-33153Y697942D02*
Y699487D01*
G01Y694005D02*
Y695550D01*
G01Y690068D02*
Y691613D01*
G01D02*
Y690068D01*
G01Y695550D02*
Y694005D01*
G01Y699487D02*
Y697942D01*
G01X-34136Y697953D02*
Y699477D01*
G01Y694016D02*
Y695540D01*
G01Y690079D02*
Y691603D01*
G01D02*
Y690079D01*
G01Y695540D02*
Y694016D01*
G01Y699477D02*
Y697953D01*
G01X-34607Y695880D02*
Y693675D01*
G01Y691943D02*
Y689738D01*
G01Y699817D02*
Y697612D01*
G01X-35357Y697967D02*
Y699462D01*
G01Y694030D02*
Y695525D01*
G01Y690093D02*
Y691588D01*
G01D02*
Y690093D01*
G01Y695525D02*
Y694030D01*
G01Y699462D02*
Y697967D01*
G01X-35545Y692022D02*
Y689660D01*
G01Y695959D02*
Y693597D01*
G01Y699896D02*
Y697534D01*
G01X-35594Y697990D02*
Y699439D01*
G01Y694053D02*
Y695502D01*
G01Y690116D02*
Y691565D01*
G01D02*
Y690116D01*
G01Y695502D02*
Y694053D01*
G01Y699439D02*
Y697990D01*
G01X-37870Y698210D02*
Y699220D01*
G01Y694273D02*
Y695283D01*
G01Y690336D02*
Y691346D01*
G01D02*
Y690336D01*
G01Y695283D02*
Y694273D01*
G01Y699220D02*
Y698210D01*
G01X-38108Y698232D02*
Y699197D01*
G01Y694295D02*
Y695260D01*
G01Y690358D02*
Y691323D01*
G01D02*
Y690358D01*
G01Y695260D02*
Y694295D01*
G01Y699197D02*
Y698232D01*
G01X-38425Y695959D02*
Y693597D01*
G01Y692022D02*
Y689660D01*
G01Y699896D02*
Y697534D01*
G01X-39607Y710624D02*
X0D01*
G01X-39607Y769693D02*
X0D01*
G01X-24843D02*
Y785441D01*
G01X-27992D02*
Y769693D01*
G01X-39607Y868118D02*
Y769693D01*
G01X-34602Y777567D02*
X-39607Y774063D01*
G01X-35350Y792453D02*
X-10630Y792178D01*
G01X-35350Y788516D02*
X-10630Y788241D01*
G01X-35350Y784579D02*
X-10630Y784304D01*
G01X-35545Y792114D02*
X0D01*
G01X-39607Y792036D02*
X-24508D01*
G01Y790461D02*
X-39607D01*
G01X-35545Y790382D02*
X0D01*
G01X-39607Y790166D02*
X-24843D01*
G01X-35545Y788177D02*
X0D01*
G01X-39607Y788099D02*
X-24508D01*
G01Y786524D02*
X-39607D01*
G01X-35545Y786445D02*
X0D01*
G01X-39607Y785441D02*
X-24843D01*
G01X-35545Y784240D02*
X0D01*
G01X-39607Y784162D02*
X-24508D01*
G01Y782587D02*
X-39607D01*
G01X-35545Y782508D02*
X0D01*
G01X-39607Y782291D02*
X-27992D01*
G01X-35545Y780303D02*
X0D01*
G01X-39607Y780225D02*
X-24508D01*
G01X-35350Y790012D02*
X-10630Y790288D01*
G01X-35350Y786075D02*
X-10630Y786351D01*
G01X-35350Y782138D02*
X-10630Y782414D01*
G01X-36191Y789931D02*
X-35340Y790014D01*
G01X-36191Y785994D02*
X-35340Y786077D01*
G01X-36191Y782057D02*
X-35340Y782140D01*
G01X-36191Y788597D02*
X-35350Y788516D01*
G01X-36191Y784660D02*
X-35350Y784579D01*
G01X-36191Y780723D02*
X-35350Y780642D01*
G01D02*
X-10630Y780367D01*
G01X-39607Y777567D02*
X-9607D01*
G01X-33701Y773630D02*
X-39607D01*
G01Y772843D02*
X-27992D01*
G01X-23997Y782265D02*
Y780516D01*
G01Y786202D02*
Y784453D01*
G01Y790139D02*
Y788390D01*
G01Y794076D02*
Y792327D01*
G01X-24508Y782587D02*
Y780225D01*
G01Y786524D02*
Y784162D01*
G01Y794398D02*
Y792036D01*
G01Y790461D02*
Y788099D01*
G01X-24843Y790166D02*
Y805914D01*
G01X-26241Y792352D02*
Y794051D01*
G01Y788415D02*
Y790114D01*
G01Y784478D02*
Y786177D01*
G01Y780541D02*
Y782240D01*
G01X-26511Y782237D02*
Y780544D01*
G01Y786174D02*
Y784481D01*
G01Y790111D02*
Y788418D01*
G01Y794048D02*
Y792355D01*
G01X-27264Y782587D02*
Y780225D01*
G01Y786524D02*
Y784162D01*
G01Y790461D02*
Y788099D01*
G01Y794398D02*
Y792036D01*
G01X-27992Y790166D02*
Y805914D01*
G01X-31725Y782179D02*
Y780602D01*
G01Y786116D02*
Y784539D01*
G01Y790053D02*
Y788476D01*
G01X-31994Y782176D02*
Y780605D01*
G01Y786113D02*
Y784542D01*
G01Y790050D02*
Y788479D01*
G01X-33153Y788492D02*
Y790037D01*
G01Y784555D02*
Y786100D01*
G01Y780618D02*
Y782163D01*
G01X-33701Y777567D02*
Y773630D01*
G01X-34136Y782152D02*
Y780629D01*
G01Y786089D02*
Y784566D01*
G01Y790026D02*
Y788503D01*
G01X-34607Y784240D02*
Y786445D01*
G01Y782508D02*
Y780303D01*
G01Y790382D02*
Y788177D01*
G01Y794319D02*
Y792114D01*
G01X-35331Y782140D02*
Y780642D01*
G01Y786077D02*
Y784579D01*
G01Y790014D02*
Y788516D01*
G01X-35545Y782587D02*
Y782119D01*
G01Y780661D02*
Y780225D01*
G01Y786524D02*
Y786056D01*
G01Y784598D02*
Y784162D01*
G01Y790461D02*
Y789993D01*
G01Y788535D02*
Y788099D01*
G01Y792472D02*
Y792036D01*
G01X-35594Y782115D02*
Y780666D01*
G01Y786052D02*
Y784603D01*
G01Y789989D02*
Y788540D01*
G01X-36191Y782057D02*
Y780723D01*
G01Y785994D02*
Y784660D01*
G01Y789931D02*
Y788597D01*
G01X-36811Y824091D02*
Y776021D01*
G01X-38425Y782587D02*
Y780225D01*
G01Y786524D02*
Y784162D01*
G01Y790461D02*
Y788099D01*
G01Y794398D02*
Y792036D01*
G01X-36191Y809616D02*
X-35340Y809699D01*
G01X-36191Y805679D02*
X-35340Y805762D01*
G01X-36191Y801742D02*
X-35340Y801825D01*
G01X-35350Y812138D02*
X-10630Y811863D01*
G01X-35350Y808201D02*
X-10630Y807926D01*
G01X-35350Y804264D02*
X-10630Y803989D01*
G01X-35350Y800327D02*
X-10630Y800052D01*
G01X-35350Y796390D02*
X-10630Y796115D01*
G01X-35545Y811799D02*
X0D01*
G01X-39607Y811721D02*
X-24508D01*
G01X-39607Y810638D02*
X-24843D01*
G01X-24508Y810146D02*
X-39607D01*
G01X-35545Y810067D02*
X0D01*
G01X-35545Y807862D02*
X0D01*
G01X-39607Y807784D02*
X-24508D01*
G01Y806209D02*
X-39607D01*
G01X-35545Y806130D02*
X0D01*
G01X-39607Y805914D02*
X-24843D01*
G01X-35545Y803925D02*
X0D01*
G01X-39607Y803847D02*
X-24508D01*
G01X-39607Y802764D02*
X-27992D01*
G01X-24508Y802272D02*
X-39607D01*
G01X-35545Y802193D02*
X0D01*
G01X-35545Y799988D02*
X0D01*
G01X-39607Y799910D02*
X-24508D01*
G01Y798335D02*
X-39607D01*
G01X-35545Y798256D02*
X0D01*
G01X-35545Y796051D02*
X0D01*
G01X-39607Y795973D02*
X-24508D01*
G01Y794398D02*
X-39607D01*
G01X-35545Y794319D02*
X0D01*
G01X-27992Y793315D02*
X-39607D01*
G01X-35350Y809697D02*
X-10630Y809973D01*
G01X-35350Y805760D02*
X-10630Y806036D01*
G01X-35350Y801823D02*
X-10630Y802099D01*
G01X-35350Y797886D02*
X-10630Y798162D01*
G01X-35350Y793949D02*
X-10630Y794225D01*
G01X-36191Y797805D02*
X-35340Y797888D01*
G01X-36191Y793868D02*
X-35340Y793951D01*
G01X-36191Y812219D02*
X-35350Y812138D01*
G01X-36191Y808282D02*
X-35350Y808201D01*
G01X-36191Y804345D02*
X-35350Y804264D01*
G01X-36191Y800408D02*
X-35350Y800327D01*
G01X-36191Y796471D02*
X-35350Y796390D01*
G01X-36191Y792534D02*
X-35350Y792453D01*
G01X-23997Y798013D02*
Y796264D01*
G01Y805887D02*
Y804138D01*
G01Y801950D02*
Y800201D01*
G01Y809824D02*
Y808075D01*
G01Y813761D02*
Y812012D01*
G01X-24508Y798335D02*
Y795973D01*
G01Y802272D02*
Y799910D01*
G01Y806209D02*
Y803847D01*
G01Y810146D02*
Y807784D01*
G01Y814083D02*
Y811721D01*
G01X-24843Y810638D02*
Y826386D01*
G01X-26241Y812037D02*
Y813736D01*
G01Y808100D02*
Y809799D01*
G01Y804163D02*
Y805862D01*
G01Y800226D02*
Y801925D01*
G01Y796289D02*
Y797988D01*
G01X-26511Y797985D02*
Y796292D01*
G01Y801922D02*
Y800229D01*
G01Y805859D02*
Y804166D01*
G01Y809796D02*
Y808103D01*
G01Y813733D02*
Y812040D01*
G01X-27264Y798335D02*
Y795973D01*
G01Y806209D02*
Y803847D01*
G01Y802272D02*
Y799910D01*
G01Y810146D02*
Y807784D01*
G01Y814083D02*
Y811721D01*
G01X-27992Y810638D02*
Y826386D01*
G01X-31725Y793990D02*
Y792413D01*
G01Y797927D02*
Y796350D01*
G01Y805801D02*
Y804224D01*
G01Y801864D02*
Y800287D01*
G01Y809738D02*
Y808161D01*
G01Y813675D02*
Y812098D01*
G01X-31994Y793987D02*
Y792416D01*
G01Y797924D02*
Y796353D01*
G01Y805798D02*
Y804227D01*
G01Y801861D02*
Y800290D01*
G01Y809735D02*
Y808164D01*
G01Y813672D02*
Y812101D01*
G01X-33153Y812114D02*
Y813659D01*
G01Y808177D02*
Y809722D01*
G01Y804240D02*
Y805785D01*
G01Y800303D02*
Y801848D01*
G01Y796366D02*
Y797911D01*
G01Y792429D02*
Y793974D01*
G01X-34136Y809711D02*
Y808188D01*
G01Y813648D02*
Y812125D01*
G01Y793963D02*
Y792440D01*
G01Y797900D02*
Y796377D01*
G01Y801837D02*
Y800314D01*
G01Y805774D02*
Y804251D01*
G01X-34607Y798256D02*
Y796051D01*
G01Y802193D02*
Y799988D01*
G01Y806130D02*
Y803925D01*
G01Y810067D02*
Y807862D01*
G01Y814004D02*
Y811799D01*
G01X-35331Y793951D02*
Y792453D01*
G01Y801825D02*
Y800327D01*
G01Y797888D02*
Y796390D01*
G01Y805762D02*
Y804264D01*
G01Y809699D02*
Y808201D01*
G01Y813636D02*
Y812138D01*
G01X-35545Y794398D02*
Y793930D01*
G01Y796409D02*
Y795973D01*
G01Y800346D02*
Y799910D01*
G01Y798335D02*
Y797867D01*
G01Y802272D02*
Y801804D01*
G01Y806209D02*
Y805741D01*
G01Y804283D02*
Y803847D01*
G01Y810146D02*
Y809678D01*
G01Y808220D02*
Y807784D01*
G01Y812157D02*
Y811721D01*
G01X-35594Y793926D02*
Y792477D01*
G01Y801800D02*
Y800351D01*
G01Y797863D02*
Y796414D01*
G01Y805737D02*
Y804288D01*
G01Y809674D02*
Y808225D01*
G01Y813611D02*
Y812162D01*
G01X-36191Y793868D02*
Y792534D01*
G01Y801742D02*
Y800408D01*
G01Y797805D02*
Y796471D01*
G01Y805679D02*
Y804345D01*
G01Y809616D02*
Y808282D01*
G01Y813553D02*
Y812219D01*
G01X-38425Y798335D02*
Y795973D01*
G01Y802272D02*
Y799910D01*
G01Y806209D02*
Y803847D01*
G01Y810146D02*
Y807784D01*
G01Y814083D02*
Y811721D01*
G01X-39607Y826766D02*
G03X-39019Y825637I1378J0D01*
G01Y827923D02*
G03X-39607Y826794I791J-1129D01*
G01X-36560Y823916D02*
G03X-34844Y823374I1717J2450D01*
G01Y830185D02*
G03X-36560Y829644I0J-2992D01*
G01X-36191Y833238D02*
X-35340Y833321D01*
G01X-36191Y821427D02*
X-35340Y821510D01*
G01X-36191Y817490D02*
X-35340Y817573D01*
G01X-36191Y813553D02*
X-35340Y813636D01*
G01X-36191Y831904D02*
X-35350Y831823D01*
G01D02*
X-10630Y831548D01*
G01X-35350Y820012D02*
X-10630Y819737D01*
G01X-35350Y816075D02*
X-10630Y815800D01*
G01X-27992Y834260D02*
X-39607D01*
G01X-24508Y833768D02*
X-39607D01*
G01X-35545Y833689D02*
X0D01*
G01X-35545Y831484D02*
X0D01*
G01X-39607Y831406D02*
X-24508D01*
G01X-39607Y831110D02*
X-24843D01*
G01X-34844Y830185D02*
X-9607D01*
G01X-35433Y829181D02*
X0D01*
G01X-39607Y826386D02*
X-24843D01*
G01X0Y824181D02*
X-35433D01*
G01X-9607Y823374D02*
X-34844D01*
G01X-39607Y823236D02*
X-27992D01*
G01X-24508Y821957D02*
X-39607D01*
G01X-35545Y821878D02*
X0D01*
G01X-35545Y819673D02*
X0D01*
G01X-39607Y819595D02*
X-24508D01*
G01Y818020D02*
X-39607D01*
G01X-35545Y817941D02*
X0D01*
G01X-35545Y815736D02*
X0D01*
G01X-39607Y815658D02*
X-24508D01*
G01Y814083D02*
X-39607D01*
G01X-35545Y814004D02*
X0D01*
G01X-27992Y813788D02*
X-39607D01*
G01X-35350Y833319D02*
X-10630Y833595D01*
G01X-35350Y821508D02*
X-10630Y821784D01*
G01X-35350Y817571D02*
X-10630Y817847D01*
G01X-35350Y813634D02*
X-10630Y813910D01*
G01X-39019Y827923D02*
X-36560Y829644D01*
G01X-36191Y820093D02*
X-35350Y820012D01*
G01X-36191Y816156D02*
X-35350Y816075D01*
G01X-36560Y823916D02*
X-39019Y825637D01*
G01X-23997Y817698D02*
Y815949D01*
G01Y821635D02*
Y819886D01*
G01Y833446D02*
Y831697D01*
G01X-24508Y818020D02*
Y815658D01*
G01Y821957D02*
Y819595D01*
G01Y833768D02*
Y831406D01*
G01X-24843Y831110D02*
Y846858D01*
G01X-26241Y831722D02*
Y833421D01*
G01Y819911D02*
Y821610D01*
G01Y815974D02*
Y817673D01*
G01X-26511Y817670D02*
Y815977D01*
G01Y821607D02*
Y819914D01*
G01Y833418D02*
Y831725D01*
G01X-27264Y818020D02*
Y815658D01*
G01Y821957D02*
Y819595D01*
G01Y833768D02*
Y831406D01*
G01X-27992Y831110D02*
Y846858D01*
G01X-31725Y817612D02*
Y816035D01*
G01Y821549D02*
Y819972D01*
G01Y833360D02*
Y831783D01*
G01X-31994Y817609D02*
Y816038D01*
G01Y821546D02*
Y819975D01*
G01Y833357D02*
Y831786D01*
G01X-33153Y831799D02*
Y833344D01*
G01Y819988D02*
Y821533D01*
G01Y816051D02*
Y817596D01*
G01X-34136Y817585D02*
Y816062D01*
G01Y821522D02*
Y819999D01*
G01Y833333D02*
Y831810D01*
G01X-34607Y831484D02*
Y833689D01*
G01Y817941D02*
Y815736D01*
G01Y821878D02*
Y819673D01*
G01X-35331Y817573D02*
Y816075D01*
G01Y821510D02*
Y820012D01*
G01Y833321D02*
Y831823D01*
G01X-35433Y824181D02*
Y829181D01*
G01X-35545Y816094D02*
Y815658D01*
G01Y814083D02*
Y813616D01*
G01Y818020D02*
Y817553D01*
G01Y820031D02*
Y819595D01*
G01Y821957D02*
Y821490D01*
G01Y833768D02*
Y833301D01*
G01Y831842D02*
Y831406D01*
G01X-35594Y817548D02*
Y816099D01*
G01Y821485D02*
Y820036D01*
G01Y833296D02*
Y831847D01*
G01X-36191Y817490D02*
Y816156D01*
G01Y821427D02*
Y820093D01*
G01Y833238D02*
Y831904D01*
G01X-36811Y861020D02*
Y829469D01*
G01X-38425Y818020D02*
Y815658D01*
G01Y821957D02*
Y819595D01*
G01Y833768D02*
Y831406D01*
G01X-35545Y855106D02*
X0D01*
G01X-39607Y855028D02*
X-24508D01*
G01X-27992Y854732D02*
X-39607D01*
G01X-35350Y853004D02*
X-10630Y853280D01*
G01X-35350Y849067D02*
X-10630Y849343D01*
G01X-36191Y852923D02*
X-35340Y853006D01*
G01X-36191Y848986D02*
X-35340Y849069D01*
G01X-36191Y845049D02*
X-35340Y845132D01*
G01X-36191Y841112D02*
X-35340Y841195D01*
G01X-36191Y837175D02*
X-35340Y837258D01*
G01X-36191Y855527D02*
X-35350Y855445D01*
G01X-36191Y851590D02*
X-35350Y851508D01*
G01X-36191Y847653D02*
X-35350Y847571D01*
G01X-36191Y843716D02*
X-35350Y843634D01*
G01X-36191Y839778D02*
X-35350Y839697D01*
G01X-36191Y835841D02*
X-35350Y835760D01*
G01Y855445D02*
X-10630Y855170D01*
G01X-35350Y851508D02*
X-10630Y851233D01*
G01X-35350Y847571D02*
X-10630Y847296D01*
G01X-35350Y843634D02*
X-10630Y843359D01*
G01X-35350Y839697D02*
X-10630Y839422D01*
G01X-35350Y835760D02*
X-10630Y835485D01*
G01X-24508Y853453D02*
X-39607D01*
G01X-35545Y853374D02*
X0D01*
G01X-39607Y851583D02*
X-24843D01*
G01X-35545Y851169D02*
X0D01*
G01X-39607Y851091D02*
X-24508D01*
G01Y849516D02*
X-39607D01*
G01X-35545Y849437D02*
X0D01*
G01X-35545Y847232D02*
X0D01*
G01X-39607Y847154D02*
X-24508D01*
G01X-39607Y846858D02*
X-24843D01*
G01X-24508Y845579D02*
X-39607D01*
G01X-35545Y845500D02*
X0D01*
G01X-39607Y843709D02*
X-27992D01*
G01X-35545Y843295D02*
X0D01*
G01X-39607Y843217D02*
X-24508D01*
G01Y841642D02*
X-39607D01*
G01X-35545Y841563D02*
X0D01*
G01X-35545Y839358D02*
X0D01*
G01X-39607Y839280D02*
X-24508D01*
G01Y837705D02*
X-39607D01*
G01X-35545Y837626D02*
X0D01*
G01X-35545Y835421D02*
X0D01*
G01X-39607Y835343D02*
X-24508D01*
G01X-35350Y845130D02*
X-10630Y845406D01*
G01X-35350Y841193D02*
X-10630Y841469D01*
G01X-35350Y837256D02*
X-10630Y837532D01*
G01X-23997Y837383D02*
Y835634D01*
G01Y841320D02*
Y839571D01*
G01Y845257D02*
Y843508D01*
G01Y849194D02*
Y847445D01*
G01Y853131D02*
Y851382D01*
G01Y857068D02*
Y855319D01*
G01X-24508Y837705D02*
Y835343D01*
G01Y841642D02*
Y839280D01*
G01Y845579D02*
Y843217D01*
G01Y849516D02*
Y847154D01*
G01Y853453D02*
Y851091D01*
G01Y857390D02*
Y855028D01*
G01X-24843Y851583D02*
Y868118D01*
G01X-26241Y855344D02*
Y857043D01*
G01Y847470D02*
Y849169D01*
G01Y851407D02*
Y853106D01*
G01Y843533D02*
Y845232D01*
G01Y839596D02*
Y841295D01*
G01Y835659D02*
Y837358D01*
G01X-26511Y853103D02*
Y851410D01*
G01Y849166D02*
Y847473D01*
G01Y857040D02*
Y855347D01*
G01Y837355D02*
Y835662D01*
G01Y841292D02*
Y839599D01*
G01Y845229D02*
Y843536D01*
G01X-27264Y837705D02*
Y835343D01*
G01Y841642D02*
Y839280D01*
G01Y845579D02*
Y843217D01*
G01Y849516D02*
Y847154D01*
G01Y853453D02*
Y851091D01*
G01Y857390D02*
Y855028D01*
G01X-27992Y851583D02*
Y868118D01*
G01X-31725Y837297D02*
Y835720D01*
G01Y841234D02*
Y839657D01*
G01Y845171D02*
Y843594D01*
G01Y849108D02*
Y847531D01*
G01Y853045D02*
Y851468D01*
G01Y856982D02*
Y855405D01*
G01X-31994Y837294D02*
Y835723D01*
G01Y841231D02*
Y839660D01*
G01Y845168D02*
Y843597D01*
G01Y849105D02*
Y847534D01*
G01Y853042D02*
Y851471D01*
G01Y856979D02*
Y855408D01*
G01X-33153Y855421D02*
Y856966D01*
G01Y847547D02*
Y849092D01*
G01Y851484D02*
Y853029D01*
G01Y843610D02*
Y845155D01*
G01Y839673D02*
Y841218D01*
G01Y835736D02*
Y837281D01*
G01X-34136Y837270D02*
Y835747D01*
G01Y841207D02*
Y839684D01*
G01Y845144D02*
Y843621D01*
G01Y853018D02*
Y851495D01*
G01Y849081D02*
Y847558D01*
G01Y856955D02*
Y855432D01*
G01X-34607Y837626D02*
Y835421D01*
G01Y845500D02*
Y843295D01*
G01Y841563D02*
Y839358D01*
G01Y849437D02*
Y847232D01*
G01Y853374D02*
Y851169D01*
G01Y857311D02*
Y855106D01*
G01X-35331Y837258D02*
Y835760D01*
G01Y841195D02*
Y839697D01*
G01Y845132D02*
Y843634D01*
G01Y849069D02*
Y847571D01*
G01Y853006D02*
Y851508D01*
G01Y856943D02*
Y855445D01*
G01X-35545Y837705D02*
Y837238D01*
G01Y835779D02*
Y835343D01*
G01Y841642D02*
Y841175D01*
G01Y839716D02*
Y839280D01*
G01Y843653D02*
Y843217D01*
G01Y847590D02*
Y847154D01*
G01Y845579D02*
Y845112D01*
G01Y851527D02*
Y851091D01*
G01Y849516D02*
Y849049D01*
G01Y855464D02*
Y855028D01*
G01Y853453D02*
Y852986D01*
G01X-35594Y837233D02*
Y835784D01*
G01Y841170D02*
Y839721D01*
G01Y845107D02*
Y843658D01*
G01Y852981D02*
Y851532D01*
G01Y849044D02*
Y847595D01*
G01Y856918D02*
Y855469D01*
G01X-36191Y837175D02*
Y835841D01*
G01Y841112D02*
Y839778D01*
G01Y845049D02*
Y843716D01*
G01Y852923D02*
Y851590D01*
G01Y848986D02*
Y847653D01*
G01Y856860D02*
Y855527D01*
G01X-38425Y837705D02*
Y835343D01*
G01Y841642D02*
Y839280D01*
G01Y845579D02*
Y843217D01*
G01Y853453D02*
Y851091D01*
G01Y849516D02*
Y847154D01*
G01Y857390D02*
Y855028D01*
G01X-36560Y860845D02*
G03X-34844Y860303I1717J2450D01*
G01X-39607Y868118D02*
X0D01*
G01X-27992Y864969D02*
X-39607D01*
G01X-9607Y860303D02*
X-34844D01*
G01X-24508Y857390D02*
X-39607D01*
G01X-35545Y857311D02*
X0D01*
G01X-35350Y856941D02*
X-10630Y857217D01*
G01X-36191Y856860D02*
X-35340Y856943D01*
G01X-39607Y862977D02*
X-36560Y860845D01*
G01X-35545Y857390D02*
Y856923D01*
G01X-32520Y1104776D02*
G03I-4291J0D01*
G01X-38108Y1360615D02*
X-35350Y1360880D01*
G01D02*
X-38108Y1360615D01*
G01Y1356678D02*
X-35350Y1356943D01*
G01D02*
X-38108Y1356678D01*
G01X-35350Y1363321D02*
X-10630Y1363045D01*
G01D02*
X-35350Y1363321D01*
G01Y1359384D02*
X-10630Y1359108D01*
G01D02*
X-35350Y1359384D01*
G01Y1355447D02*
X-10630Y1355171D01*
G01D02*
X-35350Y1355447D01*
G01X-35545Y1362967D02*
X0D01*
G01X-39607Y1362888D02*
X-24508D01*
G01Y1361313D02*
X-39607D01*
G01X-35545Y1361234D02*
X0D01*
G01X-27992Y1361018D02*
X-39607D01*
G01X-35545Y1359030D02*
X0D01*
G01X-39607Y1358951D02*
X-24508D01*
G01Y1357376D02*
X-39607D01*
G01X-35545Y1357297D02*
X0D01*
G01X-35545Y1355093D02*
X0D01*
G01X-39607Y1355014D02*
X-24508D01*
G01X-34602Y1352356D02*
X-8898D01*
G01X-39607Y1350388D02*
X-33701D01*
G01X-39607Y1347671D02*
X-27992D01*
G01X-33701Y1346451D02*
X-39607D01*
G01Y1344522D02*
X-24843D01*
G01Y1344482D02*
X-39607D01*
G01X0D02*
X-24843D01*
G01X-35350Y1360880D02*
X-10630Y1361156D01*
G01X-35350Y1360880D02*
X-10630Y1361156D01*
G01X-35350Y1356943D02*
X-10630Y1357219D01*
G01X-35350Y1356943D02*
X-10630Y1357219D01*
G01X-38108Y1363587D02*
X-35350Y1363321D01*
G01X-38108Y1363587D02*
X-35350Y1363321D01*
G01X-38108Y1359650D02*
X-35350Y1359384D01*
G01X-38108Y1359650D02*
X-35350Y1359384D01*
G01X-38108Y1355713D02*
X-35350Y1355447D01*
G01X-38108Y1355713D02*
X-35350Y1355447D01*
G01X-24121Y1363196D02*
Y1364942D01*
G01Y1359259D02*
Y1361005D01*
G01Y1355322D02*
Y1357068D01*
G01D02*
Y1355322D01*
G01Y1361005D02*
Y1359259D01*
G01Y1364942D02*
Y1363196D01*
G01X-24508Y1357376D02*
Y1355014D01*
G01Y1365250D02*
Y1362888D01*
G01Y1361313D02*
Y1358951D01*
G01X-24843Y1344522D02*
Y1364167D01*
G01X-26565Y1363223D02*
Y1364915D01*
G01Y1359286D02*
Y1360978D01*
G01Y1355349D02*
Y1357041D01*
G01D02*
Y1355349D01*
G01Y1360978D02*
Y1359286D01*
G01Y1364915D02*
Y1363223D01*
G01X-26942Y1363227D02*
Y1364911D01*
G01Y1359290D02*
Y1360974D01*
G01Y1355353D02*
Y1357037D01*
G01D02*
Y1355353D01*
G01Y1360974D02*
Y1359290D01*
G01Y1364911D02*
Y1363227D01*
G01X-27264Y1357376D02*
Y1355014D01*
G01Y1361313D02*
Y1358951D01*
G01Y1365250D02*
Y1362888D01*
G01X-27992Y1344522D02*
Y1364167D01*
G01X-31941Y1363283D02*
Y1364855D01*
G01Y1359346D02*
Y1360918D01*
G01Y1355409D02*
Y1356981D01*
G01D02*
Y1355409D01*
G01Y1360918D02*
Y1359346D01*
G01Y1364855D02*
Y1363283D01*
G01X-32318Y1363287D02*
Y1364851D01*
G01Y1359350D02*
Y1360914D01*
G01Y1355413D02*
Y1356977D01*
G01D02*
Y1355413D01*
G01Y1360914D02*
Y1359350D01*
G01Y1364851D02*
Y1363287D01*
G01X-33153Y1363297D02*
Y1364841D01*
G01Y1359360D02*
Y1360904D01*
G01Y1355423D02*
Y1356967D01*
G01D02*
Y1355423D01*
G01Y1360904D02*
Y1359360D01*
G01Y1364841D02*
Y1363297D01*
G01X-33701Y1350388D02*
Y1346451D01*
G01X-34136Y1363308D02*
Y1364831D01*
G01Y1359371D02*
Y1360894D01*
G01Y1355434D02*
Y1356957D01*
G01D02*
Y1355434D01*
G01Y1360894D02*
Y1359371D01*
G01Y1364831D02*
Y1363308D01*
G01X-34607Y1357297D02*
Y1355093D01*
G01Y1361234D02*
Y1359030D01*
G01Y1365171D02*
Y1362967D01*
G01X-35357Y1363322D02*
Y1364817D01*
G01Y1359385D02*
Y1360880D01*
G01Y1355448D02*
Y1356943D01*
G01D02*
Y1355448D01*
G01Y1360880D02*
Y1359385D01*
G01Y1364817D02*
Y1363322D01*
G01X-35545Y1357376D02*
Y1355014D01*
G01Y1365250D02*
Y1362888D01*
G01Y1361313D02*
Y1358951D01*
G01X-35594Y1363345D02*
Y1364793D01*
G01Y1359408D02*
Y1360856D01*
G01Y1355471D02*
Y1356919D01*
G01D02*
Y1355471D01*
G01Y1360856D02*
Y1359408D01*
G01Y1364793D02*
Y1363345D01*
G01X-36811Y1398880D02*
Y1350810D01*
G01X-37870Y1359627D02*
Y1360638D01*
G01Y1355690D02*
Y1356701D01*
G01D02*
Y1355690D01*
G01Y1360638D02*
Y1359627D01*
G01X-38108Y1359650D02*
Y1360615D01*
G01Y1355713D02*
Y1356678D01*
G01D02*
Y1355713D01*
G01Y1360615D02*
Y1359650D01*
G01X-38425Y1357376D02*
Y1355014D01*
G01Y1361313D02*
Y1358951D01*
G01Y1365250D02*
Y1362888D01*
G01X-39607Y1344522D02*
Y1694876D01*
G01Y1348853D02*
X-34602Y1352356D01*
G01X-35350Y1384502D02*
X-10630Y1384778D01*
G01X-35350Y1384502D02*
X-10630Y1384778D01*
G01X-38108Y1384237D02*
X-35350Y1384502D01*
G01D02*
X-38108Y1384237D01*
G01Y1380300D02*
X-35350Y1380565D01*
G01D02*
X-38108Y1380300D01*
G01Y1376363D02*
X-35350Y1376628D01*
G01D02*
X-38108Y1376363D01*
G01Y1372426D02*
X-35350Y1372691D01*
G01D02*
X-38108Y1372426D01*
G01Y1368489D02*
X-35350Y1368754D01*
G01D02*
X-38108Y1368489D01*
G01Y1364552D02*
X-35350Y1364817D01*
G01D02*
X-38108Y1364552D01*
G01Y1383272D02*
X-35350Y1383006D01*
G01X-38108Y1383272D02*
X-35350Y1383006D01*
G01X-38108Y1379335D02*
X-35350Y1379069D01*
G01X-38108Y1379335D02*
X-35350Y1379069D01*
G01X-38108Y1375398D02*
X-35350Y1375132D01*
G01X-38108Y1375398D02*
X-35350Y1375132D01*
G01X-38108Y1371461D02*
X-35350Y1371195D01*
G01X-38108Y1371461D02*
X-35350Y1371195D01*
G01X-38108Y1367524D02*
X-35350Y1367258D01*
G01X-38108Y1367524D02*
X-35350Y1367258D01*
G01Y1383006D02*
X-10630Y1382730D01*
G01D02*
X-35350Y1383006D01*
G01Y1379069D02*
X-10630Y1378793D01*
G01D02*
X-35350Y1379069D01*
G01Y1375132D02*
X-10630Y1374856D01*
G01D02*
X-35350Y1375132D01*
G01Y1371195D02*
X-10630Y1370919D01*
G01D02*
X-35350Y1371195D01*
G01Y1367258D02*
X-10630Y1366982D01*
G01D02*
X-35350Y1367258D01*
G01X-35545Y1382652D02*
X0D01*
G01X-39607Y1382573D02*
X-24508D01*
G01Y1380998D02*
X-39607D01*
G01X-35545Y1380919D02*
X0D01*
G01X-35545Y1378715D02*
X0D01*
G01X-39607Y1378636D02*
X-24508D01*
G01Y1377061D02*
X-39607D01*
G01X-35545Y1376982D02*
X0D01*
G01X-35545Y1374778D02*
X0D01*
G01X-39607Y1374699D02*
X-24508D01*
G01Y1373124D02*
X-39607D01*
G01X-35545Y1373045D02*
X0D01*
G01X-39607Y1371293D02*
X-27992D01*
G01X-35545Y1370841D02*
X0D01*
G01X-39607Y1370762D02*
X-24508D01*
G01Y1369187D02*
X-39607D01*
G01X-35545Y1369108D02*
X0D01*
G01X-39607Y1368144D02*
X-24843D01*
G01X-35545Y1366904D02*
X0D01*
G01X-39607Y1366825D02*
X-24508D01*
G01Y1365250D02*
X-39607D01*
G01X-35545Y1365171D02*
X0D01*
G01X-39607Y1364167D02*
X-24843D01*
G01X-35350Y1380565D02*
X-10630Y1380841D01*
G01X-35350Y1380565D02*
X-10630Y1380841D01*
G01X-35350Y1376628D02*
X-10630Y1376904D01*
G01X-35350Y1376628D02*
X-10630Y1376904D01*
G01X-35350Y1372691D02*
X-10630Y1372967D01*
G01X-35350Y1372691D02*
X-10630Y1372967D01*
G01X-35350Y1368754D02*
X-10630Y1369030D01*
G01X-35350Y1368754D02*
X-10630Y1369030D01*
G01X-35350Y1364817D02*
X-10630Y1365093D01*
G01X-35350Y1364817D02*
X-10630Y1365093D01*
G01X-24121Y1382881D02*
Y1384627D01*
G01Y1378944D02*
Y1380690D01*
G01Y1375007D02*
Y1376753D01*
G01Y1367133D02*
Y1368879D01*
G01Y1371070D02*
Y1372816D01*
G01D02*
Y1371070D01*
G01Y1368879D02*
Y1367133D01*
G01Y1376753D02*
Y1375007D01*
G01Y1380690D02*
Y1378944D01*
G01Y1384627D02*
Y1382881D01*
G01X-24508Y1369187D02*
Y1366825D01*
G01Y1373124D02*
Y1370762D01*
G01Y1377061D02*
Y1374699D01*
G01Y1380998D02*
Y1378636D01*
G01Y1384935D02*
Y1382573D01*
G01X-24843Y1368144D02*
Y1387790D01*
G01X-26565Y1382908D02*
Y1384600D01*
G01Y1378971D02*
Y1380663D01*
G01Y1375034D02*
Y1376726D01*
G01Y1371097D02*
Y1372789D01*
G01Y1367160D02*
Y1368852D01*
G01D02*
Y1367160D01*
G01Y1372789D02*
Y1371097D01*
G01Y1376726D02*
Y1375034D01*
G01Y1380663D02*
Y1378971D01*
G01Y1384600D02*
Y1382908D01*
G01X-26942Y1382912D02*
Y1384596D01*
G01Y1378975D02*
Y1380659D01*
G01Y1375038D02*
Y1376722D01*
G01Y1371101D02*
Y1372785D01*
G01Y1367164D02*
Y1368848D01*
G01D02*
Y1367164D01*
G01Y1372785D02*
Y1371101D01*
G01Y1376722D02*
Y1375038D01*
G01Y1380659D02*
Y1378975D01*
G01Y1384596D02*
Y1382912D01*
G01X-27264Y1369187D02*
Y1366825D01*
G01Y1377061D02*
Y1374699D01*
G01Y1373124D02*
Y1370762D01*
G01Y1380998D02*
Y1378636D01*
G01Y1384935D02*
Y1382573D01*
G01X-27992Y1368144D02*
Y1387790D01*
G01X-31941Y1382968D02*
Y1384540D01*
G01Y1379031D02*
Y1380603D01*
G01Y1375094D02*
Y1376666D01*
G01Y1367220D02*
Y1368792D01*
G01Y1371157D02*
Y1372729D01*
G01D02*
Y1371157D01*
G01Y1368792D02*
Y1367220D01*
G01Y1376666D02*
Y1375094D01*
G01Y1380603D02*
Y1379031D01*
G01Y1384540D02*
Y1382968D01*
G01X-32318Y1382972D02*
Y1384536D01*
G01Y1379035D02*
Y1380599D01*
G01Y1375098D02*
Y1376662D01*
G01Y1367224D02*
Y1368788D01*
G01Y1371161D02*
Y1372725D01*
G01D02*
Y1371161D01*
G01Y1368788D02*
Y1367224D01*
G01Y1376662D02*
Y1375098D01*
G01Y1380599D02*
Y1379035D01*
G01Y1384536D02*
Y1382972D01*
G01X-33153Y1382982D02*
Y1384527D01*
G01Y1379045D02*
Y1380590D01*
G01Y1375108D02*
Y1376653D01*
G01Y1371171D02*
Y1372716D01*
G01Y1367234D02*
Y1368778D01*
G01D02*
Y1367234D01*
G01Y1372716D02*
Y1371171D01*
G01Y1376653D02*
Y1375108D01*
G01Y1380590D02*
Y1379045D01*
G01Y1384527D02*
Y1382982D01*
G01X-34136Y1382993D02*
Y1384516D01*
G01Y1379056D02*
Y1380579D01*
G01Y1375119D02*
Y1376642D01*
G01Y1367245D02*
Y1368768D01*
G01Y1371182D02*
Y1372705D01*
G01D02*
Y1371182D01*
G01Y1368768D02*
Y1367245D01*
G01Y1376642D02*
Y1375119D01*
G01Y1380579D02*
Y1379056D01*
G01Y1384516D02*
Y1382993D01*
G01X-34607Y1369108D02*
Y1366904D01*
G01Y1373045D02*
Y1370841D01*
G01Y1376982D02*
Y1374778D01*
G01Y1380919D02*
Y1378715D01*
G01Y1384856D02*
Y1382652D01*
G01X-35357Y1383007D02*
Y1384502D01*
G01Y1379070D02*
Y1380565D01*
G01Y1375133D02*
Y1376628D01*
G01Y1371196D02*
Y1372691D01*
G01Y1367259D02*
Y1368754D01*
G01D02*
Y1367259D01*
G01Y1372691D02*
Y1371196D01*
G01Y1376628D02*
Y1375133D01*
G01Y1380565D02*
Y1379070D01*
G01Y1384502D02*
Y1383007D01*
G01X-35545Y1369187D02*
Y1366825D01*
G01Y1373124D02*
Y1370762D01*
G01Y1377061D02*
Y1374699D01*
G01Y1380998D02*
Y1378636D01*
G01Y1384935D02*
Y1382573D01*
G01X-35594Y1383030D02*
Y1384478D01*
G01Y1379093D02*
Y1380541D01*
G01Y1375156D02*
Y1376604D01*
G01Y1371219D02*
Y1372667D01*
G01Y1367282D02*
Y1368730D01*
G01D02*
Y1367282D01*
G01Y1372667D02*
Y1371219D01*
G01Y1376604D02*
Y1375156D01*
G01Y1380541D02*
Y1379093D01*
G01Y1384478D02*
Y1383030D01*
G01X-37870Y1383249D02*
Y1384260D01*
G01Y1379312D02*
Y1380323D01*
G01Y1375375D02*
Y1376386D01*
G01Y1367501D02*
Y1368512D01*
G01Y1371438D02*
Y1372449D01*
G01Y1363564D02*
Y1364575D01*
G01D02*
Y1363564D01*
G01Y1372449D02*
Y1371438D01*
G01Y1368512D02*
Y1367501D01*
G01Y1376386D02*
Y1375375D01*
G01Y1380323D02*
Y1379312D01*
G01Y1384260D02*
Y1383249D01*
G01X-38108Y1383272D02*
Y1384237D01*
G01Y1379335D02*
Y1380300D01*
G01Y1375398D02*
Y1376363D01*
G01Y1367524D02*
Y1368489D01*
G01Y1371461D02*
Y1372426D01*
G01Y1363587D02*
Y1364552D01*
G01D02*
Y1363587D01*
G01Y1368489D02*
Y1367524D01*
G01Y1372426D02*
Y1371461D01*
G01Y1376363D02*
Y1375398D01*
G01Y1380300D02*
Y1379335D01*
G01Y1384237D02*
Y1383272D01*
G01X-38425Y1369187D02*
Y1366825D01*
G01Y1373124D02*
Y1370762D01*
G01Y1377061D02*
Y1374699D01*
G01Y1380998D02*
Y1378636D01*
G01Y1384935D02*
Y1382573D01*
G01X-39019Y1402684D02*
G03Y1400426I790J-1129D01*
G01X-34844Y1404975D02*
G03X-36560Y1404434I0J-2992D01*
G01Y1398705D02*
G03X-34844Y1398164I1716J2451D01*
G01X-35350Y1394817D02*
X-10630Y1394541D01*
G01D02*
X-35350Y1394817D01*
G01X-34844Y1404975D02*
X-8898D01*
G01X0Y1403971D02*
X-35433D01*
G01Y1398971D02*
X0D01*
G01X-8898Y1398164D02*
X-34844D01*
G01X-24508Y1396746D02*
X-39607D01*
G01X-35545Y1396667D02*
X0D01*
G01X-39607Y1394916D02*
X-27992D01*
G01X-35545Y1394463D02*
X0D01*
G01X-39607Y1394384D02*
X-24508D01*
G01Y1392809D02*
X-39607D01*
G01X-35545Y1392730D02*
X0D01*
G01X-39607Y1391766D02*
X-24843D01*
G01X-35545Y1390526D02*
X0D01*
G01X-39607Y1390447D02*
X-24508D01*
G01Y1388872D02*
X-39607D01*
G01X-35545Y1388793D02*
X0D01*
G01X-39607Y1387790D02*
X-24843D01*
G01X-35350Y1396313D02*
X-10630Y1396589D01*
G01X-35350Y1396313D02*
X-10630Y1396589D01*
G01X-35350Y1392376D02*
X-10630Y1392652D01*
G01X-35350Y1392376D02*
X-10630Y1392652D01*
G01X-35350Y1388439D02*
X-10630Y1388715D01*
G01X-35350Y1388439D02*
X-10630Y1388715D01*
G01X-38108Y1396048D02*
X-35350Y1396313D01*
G01D02*
X-38108Y1396048D01*
G01Y1392111D02*
X-35350Y1392376D01*
G01D02*
X-38108Y1392111D01*
G01Y1388174D02*
X-35350Y1388439D01*
G01D02*
X-38108Y1388174D01*
G01Y1395083D02*
X-35350Y1394817D01*
G01X-38108Y1395083D02*
X-35350Y1394817D01*
G01X-38108Y1391146D02*
X-35350Y1390880D01*
G01X-38108Y1391146D02*
X-35350Y1390880D01*
G01X-38108Y1387209D02*
X-35350Y1386943D01*
G01X-38108Y1387209D02*
X-35350Y1386943D01*
G01Y1390880D02*
X-10630Y1390604D01*
G01D02*
X-35350Y1390880D01*
G01Y1386943D02*
X-10630Y1386667D01*
G01D02*
X-35350Y1386943D01*
G01X-35545Y1386589D02*
X0D01*
G01X-39607Y1386510D02*
X-24508D01*
G01Y1384935D02*
X-39607D01*
G01X-35545Y1384856D02*
X0D01*
G01X-27992Y1384640D02*
X-39607D01*
G01X-36560Y1398705D02*
X-39019Y1400426D01*
G01X-24121Y1394692D02*
Y1396438D01*
G01Y1390755D02*
Y1392501D01*
G01Y1386818D02*
Y1388564D01*
G01D02*
Y1386818D01*
G01Y1392501D02*
Y1390755D01*
G01Y1396438D02*
Y1394692D01*
G01X-24508Y1388872D02*
Y1386510D01*
G01Y1392809D02*
Y1390447D01*
G01Y1396746D02*
Y1394384D01*
G01X-24843Y1391766D02*
Y1411412D01*
G01X-26565Y1394719D02*
Y1396411D01*
G01Y1390782D02*
Y1392474D01*
G01Y1386845D02*
Y1388537D01*
G01D02*
Y1386845D01*
G01Y1392474D02*
Y1390782D01*
G01Y1396411D02*
Y1394719D01*
G01X-26942Y1394723D02*
Y1396407D01*
G01Y1390786D02*
Y1392470D01*
G01Y1386849D02*
Y1388533D01*
G01D02*
Y1386849D01*
G01Y1392470D02*
Y1390786D01*
G01Y1396407D02*
Y1394723D01*
G01X-27264Y1388872D02*
Y1386510D01*
G01Y1392809D02*
Y1390447D01*
G01Y1396746D02*
Y1394384D01*
G01X-27992Y1391766D02*
Y1411412D01*
G01X-31941Y1394779D02*
Y1396351D01*
G01Y1390842D02*
Y1392414D01*
G01Y1386905D02*
Y1388477D01*
G01D02*
Y1386905D01*
G01Y1392414D02*
Y1390842D01*
G01Y1396351D02*
Y1394779D01*
G01X-32318Y1394783D02*
Y1396347D01*
G01Y1390846D02*
Y1392410D01*
G01Y1386909D02*
Y1388473D01*
G01D02*
Y1386909D01*
G01Y1392410D02*
Y1390846D01*
G01Y1396347D02*
Y1394783D01*
G01X-33153Y1394793D02*
Y1396338D01*
G01Y1390856D02*
Y1392401D01*
G01Y1386919D02*
Y1388464D01*
G01D02*
Y1386919D01*
G01Y1392401D02*
Y1390856D01*
G01Y1396338D02*
Y1394793D01*
G01X-34136Y1390867D02*
Y1392390D01*
G01Y1394804D02*
Y1396327D01*
G01Y1386930D02*
Y1388453D01*
G01D02*
Y1386930D01*
G01Y1396327D02*
Y1394804D01*
G01Y1392390D02*
Y1390867D01*
G01X-34607Y1394463D02*
Y1396667D01*
G01Y1388793D02*
Y1386589D01*
G01Y1392730D02*
Y1390526D01*
G01X-35357Y1394818D02*
Y1396313D01*
G01Y1390881D02*
Y1392376D01*
G01Y1386944D02*
Y1388439D01*
G01D02*
Y1386944D01*
G01Y1392376D02*
Y1390881D01*
G01Y1396313D02*
Y1394818D01*
G01X-35433Y1403971D02*
Y1398971D01*
G01X-35545Y1388872D02*
Y1386510D01*
G01Y1392809D02*
Y1390447D01*
G01Y1396746D02*
Y1394384D01*
G01X-35594Y1394841D02*
Y1396290D01*
G01Y1390904D02*
Y1392353D01*
G01Y1386967D02*
Y1388416D01*
G01D02*
Y1386967D01*
G01Y1392353D02*
Y1390904D01*
G01Y1396290D02*
Y1394841D01*
G01X-36811Y1687916D02*
Y1404258D01*
G01X-37870Y1391123D02*
Y1392134D01*
G01Y1395060D02*
Y1396071D01*
G01Y1387186D02*
Y1388197D01*
G01D02*
Y1387186D01*
G01Y1396071D02*
Y1395060D01*
G01Y1392134D02*
Y1391123D01*
G01X-38108Y1391146D02*
Y1392111D01*
G01Y1395083D02*
Y1396048D01*
G01Y1387209D02*
Y1388174D01*
G01D02*
Y1387209D01*
G01Y1392111D02*
Y1391146D01*
G01Y1396048D02*
Y1395083D01*
G01X-38425Y1388872D02*
Y1386510D01*
G01Y1396746D02*
Y1394384D01*
G01Y1392809D02*
Y1390447D01*
G01X-39019Y1402712D02*
X-36560Y1404434D01*
G01X-38108Y1423607D02*
X-35350Y1423872D01*
G01D02*
X-38108Y1423607D01*
G01Y1419670D02*
X-35350Y1419935D01*
G01D02*
X-38108Y1419670D01*
G01Y1415733D02*
X-35350Y1415998D01*
G01D02*
X-38108Y1415733D01*
G01Y1411796D02*
X-35350Y1412061D01*
G01D02*
X-38108Y1411796D01*
G01X-35350Y1426313D02*
X-10630Y1426038D01*
G01D02*
X-35350Y1426313D01*
G01Y1422376D02*
X-10630Y1422101D01*
G01D02*
X-35350Y1422376D01*
G01Y1418439D02*
X-10630Y1418164D01*
G01D02*
X-35350Y1418439D01*
G01Y1414502D02*
X-10630Y1414227D01*
G01D02*
X-35350Y1414502D01*
G01Y1410565D02*
X-10630Y1410290D01*
G01D02*
X-35350Y1410565D01*
G01Y1406628D02*
X-10630Y1406353D01*
G01D02*
X-35350Y1406628D01*
G01X-35545Y1425959D02*
X0D01*
G01X-39607Y1425880D02*
X-24508D01*
G01Y1424305D02*
X-39607D01*
G01X-35545Y1424227D02*
X0D01*
G01X-35545Y1422022D02*
X0D01*
G01X-39607Y1421943D02*
X-24508D01*
G01Y1420368D02*
X-39607D01*
G01X-35545Y1420290D02*
X0D01*
G01X-39607Y1418538D02*
X-27992D01*
G01X-35545Y1418085D02*
X0D01*
G01X-39607Y1418006D02*
X-24508D01*
G01Y1416431D02*
X-39607D01*
G01X-35545Y1416353D02*
X0D01*
G01X-39607Y1415388D02*
X-24843D01*
G01X-35545Y1414148D02*
X0D01*
G01X-39607Y1414069D02*
X-24508D01*
G01Y1412494D02*
X-39607D01*
G01X-35545Y1412416D02*
X0D01*
G01X-39607Y1411412D02*
X-24843D01*
G01X-35545Y1410211D02*
X0D01*
G01X-39607Y1410132D02*
X-24508D01*
G01Y1408557D02*
X-39607D01*
G01X-35545Y1408478D02*
X0D01*
G01X-27992Y1408262D02*
X-39607D01*
G01X-35545Y1406274D02*
X0D01*
G01X-39607Y1406195D02*
X-24508D01*
G01X-35350Y1423872D02*
X-10630Y1424148D01*
G01X-35350Y1423872D02*
X-10630Y1424148D01*
G01X-35350Y1419935D02*
X-10630Y1420211D01*
G01X-35350Y1419935D02*
X-10630Y1420211D01*
G01X-35350Y1415998D02*
X-10630Y1416274D01*
G01X-35350Y1415998D02*
X-10630Y1416274D01*
G01X-35350Y1412061D02*
X-10630Y1412337D01*
G01X-35350Y1412061D02*
X-10630Y1412337D01*
G01X-35350Y1408124D02*
X-10630Y1408400D01*
G01X-35350Y1408124D02*
X-10630Y1408400D01*
G01X-38108Y1407859D02*
X-35350Y1408124D01*
G01D02*
X-38108Y1407859D01*
G01Y1426579D02*
X-35350Y1426313D01*
G01X-38108Y1426579D02*
X-35350Y1426313D01*
G01X-38108Y1422642D02*
X-35350Y1422376D01*
G01X-38108Y1422642D02*
X-35350Y1422376D01*
G01X-38108Y1418705D02*
X-35350Y1418439D01*
G01X-38108Y1418705D02*
X-35350Y1418439D01*
G01X-38108Y1414768D02*
X-35350Y1414502D01*
G01X-38108Y1414768D02*
X-35350Y1414502D01*
G01X-38108Y1410831D02*
X-35350Y1410565D01*
G01X-38108Y1410831D02*
X-35350Y1410565D01*
G01X-38108Y1406894D02*
X-35350Y1406628D01*
G01X-38108Y1406894D02*
X-35350Y1406628D01*
G01X-24121Y1426188D02*
Y1427934D01*
G01Y1418314D02*
Y1420060D01*
G01Y1422251D02*
Y1423997D01*
G01Y1414377D02*
Y1416123D01*
G01Y1410440D02*
Y1412186D01*
G01Y1406503D02*
Y1408249D01*
G01D02*
Y1406503D01*
G01Y1412186D02*
Y1410440D01*
G01Y1416123D02*
Y1414377D01*
G01Y1423997D02*
Y1422251D01*
G01Y1420060D02*
Y1418314D01*
G01Y1427934D02*
Y1426188D01*
G01X-24508Y1412494D02*
Y1410132D01*
G01Y1408557D02*
Y1406195D01*
G01Y1416431D02*
Y1414069D01*
G01Y1420368D02*
Y1418006D01*
G01Y1424305D02*
Y1421943D01*
G01Y1428242D02*
Y1425880D01*
G01X-24843Y1415388D02*
Y1435034D01*
G01X-26565Y1426215D02*
Y1427907D01*
G01Y1422278D02*
Y1423970D01*
G01Y1418341D02*
Y1420033D01*
G01Y1414404D02*
Y1416096D01*
G01Y1410467D02*
Y1412159D01*
G01Y1406530D02*
Y1408222D01*
G01D02*
Y1406530D01*
G01Y1412159D02*
Y1410467D01*
G01Y1416096D02*
Y1414404D01*
G01Y1420033D02*
Y1418341D01*
G01Y1423970D02*
Y1422278D01*
G01Y1427907D02*
Y1426215D01*
G01X-26942Y1426219D02*
Y1427903D01*
G01Y1422282D02*
Y1423966D01*
G01Y1418345D02*
Y1420029D01*
G01Y1414408D02*
Y1416092D01*
G01Y1410471D02*
Y1412155D01*
G01Y1406534D02*
Y1408218D01*
G01D02*
Y1406534D01*
G01Y1412155D02*
Y1410471D01*
G01Y1416092D02*
Y1414408D01*
G01Y1420029D02*
Y1418345D01*
G01Y1423966D02*
Y1422282D01*
G01Y1427903D02*
Y1426219D01*
G01X-27264Y1408557D02*
Y1406195D01*
G01Y1412494D02*
Y1410132D01*
G01Y1416431D02*
Y1414069D01*
G01Y1420368D02*
Y1418006D01*
G01Y1424305D02*
Y1421943D01*
G01Y1428242D02*
Y1425880D01*
G01X-27992Y1415388D02*
Y1435034D01*
G01X-31941Y1426275D02*
Y1427847D01*
G01Y1418401D02*
Y1419973D01*
G01Y1422338D02*
Y1423910D01*
G01Y1414464D02*
Y1416036D01*
G01Y1410527D02*
Y1412099D01*
G01Y1406590D02*
Y1408162D01*
G01D02*
Y1406590D01*
G01Y1412099D02*
Y1410527D01*
G01Y1416036D02*
Y1414464D01*
G01Y1423910D02*
Y1422338D01*
G01Y1419973D02*
Y1418401D01*
G01Y1427847D02*
Y1426275D01*
G01X-32318Y1426279D02*
Y1427843D01*
G01Y1418405D02*
Y1419969D01*
G01Y1422342D02*
Y1423906D01*
G01Y1414468D02*
Y1416032D01*
G01Y1410531D02*
Y1412095D01*
G01Y1406594D02*
Y1408158D01*
G01D02*
Y1406594D01*
G01Y1412095D02*
Y1410531D01*
G01Y1416032D02*
Y1414468D01*
G01Y1423906D02*
Y1422342D01*
G01Y1419969D02*
Y1418405D01*
G01Y1427843D02*
Y1426279D01*
G01X-33153Y1426289D02*
Y1427834D01*
G01Y1422352D02*
Y1423897D01*
G01Y1418415D02*
Y1419960D01*
G01Y1414478D02*
Y1416023D01*
G01Y1410541D02*
Y1412086D01*
G01Y1406604D02*
Y1408149D01*
G01D02*
Y1406604D01*
G01Y1412086D02*
Y1410541D01*
G01Y1416023D02*
Y1414478D01*
G01Y1419960D02*
Y1418415D01*
G01Y1423897D02*
Y1422352D01*
G01Y1427834D02*
Y1426289D01*
G01X-34136Y1426300D02*
Y1427823D01*
G01Y1418426D02*
Y1419949D01*
G01Y1422363D02*
Y1423886D01*
G01Y1414489D02*
Y1416012D01*
G01Y1410552D02*
Y1412075D01*
G01Y1406615D02*
Y1408138D01*
G01D02*
Y1406615D01*
G01Y1412075D02*
Y1410552D01*
G01Y1416012D02*
Y1414489D01*
G01Y1423886D02*
Y1422363D01*
G01Y1419949D02*
Y1418426D01*
G01Y1427823D02*
Y1426300D01*
G01X-34607Y1406274D02*
Y1408478D01*
G01Y1412416D02*
Y1410211D01*
G01Y1420290D02*
Y1418085D01*
G01Y1416353D02*
Y1414148D01*
G01Y1424227D02*
Y1422022D01*
G01Y1428164D02*
Y1425959D01*
G01X-35357Y1426314D02*
Y1427809D01*
G01Y1422377D02*
Y1423872D01*
G01Y1418440D02*
Y1419935D01*
G01Y1414503D02*
Y1415998D01*
G01Y1410566D02*
Y1412061D01*
G01Y1406629D02*
Y1408124D01*
G01D02*
Y1406629D01*
G01Y1412061D02*
Y1410566D01*
G01Y1415998D02*
Y1414503D01*
G01Y1419935D02*
Y1418440D01*
G01Y1423872D02*
Y1422377D01*
G01Y1427809D02*
Y1426314D01*
G01X-35545Y1412494D02*
Y1410132D01*
G01Y1408557D02*
Y1406195D01*
G01Y1416431D02*
Y1414069D01*
G01Y1420368D02*
Y1418006D01*
G01Y1424305D02*
Y1421943D01*
G01Y1428242D02*
Y1425880D01*
G01X-35594Y1426337D02*
Y1427786D01*
G01Y1422400D02*
Y1423849D01*
G01Y1418463D02*
Y1419912D01*
G01Y1414526D02*
Y1415975D01*
G01Y1410589D02*
Y1412038D01*
G01Y1406652D02*
Y1408101D01*
G01D02*
Y1406652D01*
G01Y1412038D02*
Y1410589D01*
G01Y1415975D02*
Y1414526D01*
G01Y1419912D02*
Y1418463D01*
G01Y1423849D02*
Y1422400D01*
G01Y1427786D02*
Y1426337D01*
G01X-37870Y1426556D02*
Y1427567D01*
G01Y1422619D02*
Y1423630D01*
G01Y1414745D02*
Y1415756D01*
G01Y1418682D02*
Y1419693D01*
G01Y1410808D02*
Y1411819D01*
G01Y1406871D02*
Y1407882D01*
G01D02*
Y1406871D01*
G01Y1411819D02*
Y1410808D01*
G01Y1419693D02*
Y1418682D01*
G01Y1415756D02*
Y1414745D01*
G01Y1423630D02*
Y1422619D01*
G01Y1427567D02*
Y1426556D01*
G01X-38108Y1426579D02*
Y1427544D01*
G01Y1422642D02*
Y1423607D01*
G01Y1414768D02*
Y1415733D01*
G01Y1418705D02*
Y1419670D01*
G01Y1410831D02*
Y1411796D01*
G01Y1406894D02*
Y1407859D01*
G01D02*
Y1406894D01*
G01Y1411796D02*
Y1410831D01*
G01Y1415733D02*
Y1414768D01*
G01Y1419670D02*
Y1418705D01*
G01Y1423607D02*
Y1422642D01*
G01Y1427544D02*
Y1426579D01*
G01X-38425Y1408557D02*
Y1406195D01*
G01Y1412494D02*
Y1410132D01*
G01Y1420368D02*
Y1418006D01*
G01Y1416431D02*
Y1414069D01*
G01Y1424305D02*
Y1421943D01*
G01Y1428242D02*
Y1425880D01*
G01X-38108Y1447229D02*
X-35350Y1447494D01*
G01D02*
X-38108Y1447229D01*
G01Y1443292D02*
X-35350Y1443557D01*
G01D02*
X-38108Y1443292D01*
G01Y1439355D02*
X-35350Y1439620D01*
G01D02*
X-38108Y1439355D01*
G01Y1435418D02*
X-35350Y1435683D01*
G01D02*
X-38108Y1435418D01*
G01Y1431481D02*
X-35350Y1431746D01*
G01D02*
X-38108Y1431481D01*
G01Y1427544D02*
X-35350Y1427809D01*
G01D02*
X-38108Y1427544D01*
G01Y1446264D02*
X-35350Y1445998D01*
G01X-38108Y1446264D02*
X-35350Y1445998D01*
G01D02*
X-10630Y1445723D01*
G01D02*
X-35350Y1445998D01*
G01Y1442061D02*
X-10630Y1441786D01*
G01D02*
X-35350Y1442061D01*
G01Y1438124D02*
X-10630Y1437849D01*
G01D02*
X-35350Y1438124D01*
G01Y1434187D02*
X-10630Y1433912D01*
G01D02*
X-35350Y1434187D01*
G01Y1430250D02*
X-10630Y1429975D01*
G01D02*
X-35350Y1430250D01*
G01X-24508Y1447927D02*
X-39607D01*
G01X-35545Y1447849D02*
X0D01*
G01X-35545Y1445644D02*
X0D01*
G01X-39607Y1445565D02*
X-24508D01*
G01Y1443990D02*
X-39607D01*
G01X-35545Y1443912D02*
X0D01*
G01X-39607Y1442160D02*
X-27992D01*
G01X-35545Y1441707D02*
X0D01*
G01X-39607Y1441628D02*
X-24508D01*
G01Y1440053D02*
X-39607D01*
G01X-35545Y1439975D02*
X0D01*
G01X-39607Y1439010D02*
X-24843D01*
G01X-35545Y1437770D02*
X0D01*
G01X-39607Y1437691D02*
X-24508D01*
G01Y1436116D02*
X-39607D01*
G01X-35545Y1436038D02*
X0D01*
G01X-39607Y1435034D02*
X-24843D01*
G01X-35545Y1433833D02*
X0D01*
G01X-39607Y1433754D02*
X-24508D01*
G01Y1432179D02*
X-39607D01*
G01X-35545Y1432101D02*
X0D01*
G01X-27992Y1431884D02*
X-39607D01*
G01X-35545Y1429896D02*
X0D01*
G01X-39607Y1429817D02*
X-24508D01*
G01Y1428242D02*
X-39607D01*
G01X-35545Y1428164D02*
X0D01*
G01X-35350Y1447494D02*
X-10630Y1447770D01*
G01X-35350Y1447494D02*
X-10630Y1447770D01*
G01X-35350Y1443557D02*
X-10630Y1443833D01*
G01X-35350Y1443557D02*
X-10630Y1443833D01*
G01X-35350Y1439620D02*
X-10630Y1439896D01*
G01X-35350Y1439620D02*
X-10630Y1439896D01*
G01X-35350Y1435683D02*
X-10630Y1435959D01*
G01X-35350Y1435683D02*
X-10630Y1435959D01*
G01X-35350Y1431746D02*
X-10630Y1432022D01*
G01X-35350Y1431746D02*
X-10630Y1432022D01*
G01X-35350Y1427809D02*
X-10630Y1428085D01*
G01X-35350Y1427809D02*
X-10630Y1428085D01*
G01X-38108Y1442327D02*
X-35350Y1442061D01*
G01X-38108Y1442327D02*
X-35350Y1442061D01*
G01X-38108Y1438390D02*
X-35350Y1438124D01*
G01X-38108Y1438390D02*
X-35350Y1438124D01*
G01X-38108Y1434453D02*
X-35350Y1434187D01*
G01X-38108Y1434453D02*
X-35350Y1434187D01*
G01X-38108Y1430516D02*
X-35350Y1430250D01*
G01X-38108Y1430516D02*
X-35350Y1430250D01*
G01X-24121Y1445873D02*
Y1447619D01*
G01Y1441936D02*
Y1443682D01*
G01Y1437999D02*
Y1439745D01*
G01Y1434062D02*
Y1435808D01*
G01Y1430125D02*
Y1431871D01*
G01D02*
Y1430125D01*
G01Y1435808D02*
Y1434062D01*
G01Y1439745D02*
Y1437999D01*
G01Y1447619D02*
Y1445873D01*
G01Y1443682D02*
Y1441936D01*
G01X-24508Y1432179D02*
Y1429817D01*
G01Y1436116D02*
Y1433754D01*
G01Y1440053D02*
Y1437691D01*
G01Y1443990D02*
Y1441628D01*
G01Y1447927D02*
Y1445565D01*
G01X-24843Y1439010D02*
Y1458656D01*
G01X-26565Y1445900D02*
Y1447592D01*
G01Y1441963D02*
Y1443655D01*
G01Y1438026D02*
Y1439718D01*
G01Y1434089D02*
Y1435781D01*
G01Y1430152D02*
Y1431844D01*
G01D02*
Y1430152D01*
G01Y1435781D02*
Y1434089D01*
G01Y1439718D02*
Y1438026D01*
G01Y1447592D02*
Y1445900D01*
G01Y1443655D02*
Y1441963D01*
G01X-26942Y1445904D02*
Y1447588D01*
G01Y1441967D02*
Y1443651D01*
G01Y1438030D02*
Y1439714D01*
G01Y1434093D02*
Y1435777D01*
G01Y1430156D02*
Y1431840D01*
G01D02*
Y1430156D01*
G01Y1435777D02*
Y1434093D01*
G01Y1439714D02*
Y1438030D01*
G01Y1443651D02*
Y1441967D01*
G01Y1447588D02*
Y1445904D01*
G01X-27264Y1432179D02*
Y1429817D01*
G01Y1436116D02*
Y1433754D01*
G01Y1440053D02*
Y1437691D01*
G01Y1443990D02*
Y1441628D01*
G01Y1447927D02*
Y1445565D01*
G01X-27992Y1439010D02*
Y1458656D01*
G01X-31941Y1445960D02*
Y1447532D01*
G01Y1442023D02*
Y1443595D01*
G01Y1438086D02*
Y1439658D01*
G01Y1434149D02*
Y1435721D01*
G01Y1430212D02*
Y1431784D01*
G01D02*
Y1430212D01*
G01Y1435721D02*
Y1434149D01*
G01Y1439658D02*
Y1438086D01*
G01Y1447532D02*
Y1445960D01*
G01Y1443595D02*
Y1442023D01*
G01X-32318Y1442027D02*
Y1443591D01*
G01Y1445964D02*
Y1447528D01*
G01Y1438090D02*
Y1439654D01*
G01Y1434153D02*
Y1435717D01*
G01Y1430216D02*
Y1431780D01*
G01D02*
Y1430216D01*
G01Y1435717D02*
Y1434153D01*
G01Y1439654D02*
Y1438090D01*
G01Y1447528D02*
Y1445964D01*
G01Y1443591D02*
Y1442027D01*
G01X-33153Y1445974D02*
Y1447519D01*
G01Y1442037D02*
Y1443582D01*
G01Y1438100D02*
Y1439645D01*
G01Y1434163D02*
Y1435708D01*
G01Y1430226D02*
Y1431771D01*
G01D02*
Y1430226D01*
G01Y1435708D02*
Y1434163D01*
G01Y1443582D02*
Y1442037D01*
G01Y1439645D02*
Y1438100D01*
G01Y1447519D02*
Y1445974D01*
G01X-34136Y1442048D02*
Y1443571D01*
G01Y1445985D02*
Y1447508D01*
G01Y1438111D02*
Y1439634D01*
G01Y1434174D02*
Y1435697D01*
G01Y1430237D02*
Y1431760D01*
G01D02*
Y1430237D01*
G01Y1435697D02*
Y1434174D01*
G01Y1439634D02*
Y1438111D01*
G01Y1447508D02*
Y1445985D01*
G01Y1443571D02*
Y1442048D01*
G01X-34607Y1432101D02*
Y1429896D01*
G01Y1436038D02*
Y1433833D01*
G01Y1443912D02*
Y1441707D01*
G01Y1439975D02*
Y1437770D01*
G01Y1447849D02*
Y1445644D01*
G01X-35357Y1445999D02*
Y1447494D01*
G01Y1442062D02*
Y1443557D01*
G01Y1438125D02*
Y1439620D01*
G01Y1434188D02*
Y1435683D01*
G01Y1430251D02*
Y1431746D01*
G01D02*
Y1430251D01*
G01Y1435683D02*
Y1434188D01*
G01Y1439620D02*
Y1438125D01*
G01Y1443557D02*
Y1442062D01*
G01Y1447494D02*
Y1445999D01*
G01X-35545Y1432179D02*
Y1429817D01*
G01Y1436116D02*
Y1433754D01*
G01Y1440053D02*
Y1437691D01*
G01Y1443990D02*
Y1441628D01*
G01Y1447927D02*
Y1445565D01*
G01X-35594Y1446022D02*
Y1447471D01*
G01Y1442085D02*
Y1443534D01*
G01Y1438148D02*
Y1439597D01*
G01Y1434211D02*
Y1435660D01*
G01Y1430274D02*
Y1431723D01*
G01D02*
Y1430274D01*
G01Y1435660D02*
Y1434211D01*
G01Y1443534D02*
Y1442085D01*
G01Y1439597D02*
Y1438148D01*
G01Y1447471D02*
Y1446022D01*
G01X-37870Y1442304D02*
Y1443315D01*
G01Y1446241D02*
Y1447252D01*
G01Y1438367D02*
Y1439378D01*
G01Y1434430D02*
Y1435441D01*
G01Y1430493D02*
Y1431504D01*
G01D02*
Y1430493D01*
G01Y1435441D02*
Y1434430D01*
G01Y1439378D02*
Y1438367D01*
G01Y1447252D02*
Y1446241D01*
G01Y1443315D02*
Y1442304D01*
G01X-38108Y1442327D02*
Y1443292D01*
G01Y1446264D02*
Y1447229D01*
G01Y1438390D02*
Y1439355D01*
G01Y1434453D02*
Y1435418D01*
G01Y1430516D02*
Y1431481D01*
G01D02*
Y1430516D01*
G01Y1435418D02*
Y1434453D01*
G01Y1439355D02*
Y1438390D01*
G01Y1447229D02*
Y1446264D01*
G01Y1443292D02*
Y1442327D01*
G01X-38425Y1432179D02*
Y1429817D01*
G01Y1436116D02*
Y1433754D01*
G01Y1443990D02*
Y1441628D01*
G01Y1440053D02*
Y1437691D01*
G01Y1447927D02*
Y1445565D01*
G01X-39607Y1469187D02*
X-24508D01*
G01Y1467612D02*
X-39607D01*
G01X-35545Y1467534D02*
X0D01*
G01X-39607Y1465782D02*
X-27992D01*
G01X-35545Y1465329D02*
X0D01*
G01X-39607Y1465250D02*
X-24508D01*
G01Y1463675D02*
X-39607D01*
G01X-35545Y1463597D02*
X0D01*
G01X-35350Y1467179D02*
X-10630Y1467455D01*
G01X-35350Y1467179D02*
X-10630Y1467455D01*
G01X-35350Y1463242D02*
X-10630Y1463518D01*
G01X-35350Y1463242D02*
X-10630Y1463518D01*
G01X-35350Y1459305D02*
X-10630Y1459581D01*
G01X-35350Y1459305D02*
X-10630Y1459581D01*
G01X-38108Y1466914D02*
X-35350Y1467179D01*
G01D02*
X-38108Y1466914D01*
G01Y1462977D02*
X-35350Y1463242D01*
G01D02*
X-38108Y1462977D01*
G01Y1459040D02*
X-35350Y1459305D01*
G01D02*
X-38108Y1459040D01*
G01Y1455103D02*
X-35350Y1455368D01*
G01D02*
X-38108Y1455103D01*
G01Y1451166D02*
X-35350Y1451431D01*
G01D02*
X-38108Y1451166D01*
G01Y1465949D02*
X-35350Y1465683D01*
G01X-38108Y1465949D02*
X-35350Y1465683D01*
G01X-38108Y1462012D02*
X-35350Y1461746D01*
G01X-38108Y1462012D02*
X-35350Y1461746D01*
G01X-38108Y1458075D02*
X-35350Y1457809D01*
G01X-38108Y1458075D02*
X-35350Y1457809D01*
G01X-38108Y1454138D02*
X-35350Y1453872D01*
G01X-38108Y1454138D02*
X-35350Y1453872D01*
G01X-38108Y1450201D02*
X-35350Y1449935D01*
G01X-38108Y1450201D02*
X-35350Y1449935D01*
G01Y1465683D02*
X-10630Y1465408D01*
G01D02*
X-35350Y1465683D01*
G01Y1461746D02*
X-10630Y1461471D01*
G01D02*
X-35350Y1461746D01*
G01Y1457809D02*
X-10630Y1457534D01*
G01D02*
X-35350Y1457809D01*
G01Y1453872D02*
X-10630Y1453597D01*
G01D02*
X-35350Y1453872D01*
G01Y1449935D02*
X-10630Y1449660D01*
G01D02*
X-35350Y1449935D01*
G01X-39607Y1462632D02*
X-24843D01*
G01X-35545Y1461392D02*
X0D01*
G01X-39607Y1461313D02*
X-24508D01*
G01Y1459738D02*
X-39607D01*
G01X-35545Y1459660D02*
X0D01*
G01X-39607Y1458656D02*
X-24843D01*
G01X-35545Y1457455D02*
X0D01*
G01X-39607Y1457376D02*
X-24508D01*
G01Y1455801D02*
X-39607D01*
G01X-35545Y1455723D02*
X0D01*
G01X-27992Y1455506D02*
X-39607D01*
G01X-35545Y1453518D02*
X0D01*
G01X-39607Y1453439D02*
X-24508D01*
G01Y1451864D02*
X-39607D01*
G01X-35545Y1451786D02*
X0D01*
G01X-35545Y1449581D02*
X0D01*
G01X-39607Y1449502D02*
X-24508D01*
G01X-35350Y1455368D02*
X-10630Y1455644D01*
G01X-35350Y1455368D02*
X-10630Y1455644D01*
G01X-35350Y1451431D02*
X-10630Y1451707D01*
G01X-35350Y1451431D02*
X-10630Y1451707D01*
G01X-24121Y1465558D02*
Y1467304D01*
G01Y1461621D02*
Y1463367D01*
G01Y1457684D02*
Y1459430D01*
G01Y1453747D02*
Y1455493D01*
G01Y1449810D02*
Y1451556D01*
G01D02*
Y1449810D01*
G01Y1455493D02*
Y1453747D01*
G01Y1459430D02*
Y1457684D01*
G01Y1463367D02*
Y1461621D01*
G01Y1467304D02*
Y1465558D01*
G01X-24508Y1451864D02*
Y1449502D01*
G01Y1455801D02*
Y1453439D01*
G01Y1459738D02*
Y1457376D01*
G01Y1463675D02*
Y1461313D01*
G01Y1467612D02*
Y1465250D01*
G01Y1471549D02*
Y1469187D01*
G01X-24843Y1462632D02*
Y1482278D01*
G01X-26565Y1465585D02*
Y1467277D01*
G01Y1461648D02*
Y1463340D01*
G01Y1457711D02*
Y1459403D01*
G01Y1453774D02*
Y1455466D01*
G01Y1449837D02*
Y1451529D01*
G01D02*
Y1449837D01*
G01Y1455466D02*
Y1453774D01*
G01Y1459403D02*
Y1457711D01*
G01Y1463340D02*
Y1461648D01*
G01Y1467277D02*
Y1465585D01*
G01X-26942Y1465590D02*
Y1467273D01*
G01Y1461653D02*
Y1463336D01*
G01Y1457716D02*
Y1459399D01*
G01Y1453778D02*
Y1455462D01*
G01Y1449841D02*
Y1451525D01*
G01D02*
Y1449841D01*
G01Y1455462D02*
Y1453778D01*
G01Y1459399D02*
Y1457716D01*
G01Y1463336D02*
Y1461653D01*
G01Y1467273D02*
Y1465590D01*
G01X-27264Y1451864D02*
Y1449502D01*
G01Y1455801D02*
Y1453439D01*
G01Y1459738D02*
Y1457376D01*
G01Y1463675D02*
Y1461313D01*
G01Y1467612D02*
Y1465250D01*
G01Y1471549D02*
Y1469187D01*
G01X-27992Y1462632D02*
Y1482278D01*
G01X-31941Y1465645D02*
Y1467217D01*
G01Y1461708D02*
Y1463280D01*
G01Y1457771D02*
Y1459343D01*
G01Y1453834D02*
Y1455406D01*
G01Y1449897D02*
Y1451469D01*
G01D02*
Y1449897D01*
G01Y1455406D02*
Y1453834D01*
G01Y1459343D02*
Y1457771D01*
G01Y1463280D02*
Y1461708D01*
G01Y1467217D02*
Y1465645D01*
G01X-32318Y1465649D02*
Y1467213D01*
G01Y1461712D02*
Y1463276D01*
G01Y1457775D02*
Y1459339D01*
G01Y1453838D02*
Y1455402D01*
G01Y1449901D02*
Y1451465D01*
G01D02*
Y1449901D01*
G01Y1455402D02*
Y1453838D01*
G01Y1459339D02*
Y1457775D01*
G01Y1463276D02*
Y1461712D01*
G01Y1467213D02*
Y1465649D01*
G01X-33153Y1465659D02*
Y1467204D01*
G01Y1461722D02*
Y1463267D01*
G01Y1457785D02*
Y1459330D01*
G01Y1453848D02*
Y1455393D01*
G01Y1449911D02*
Y1451456D01*
G01D02*
Y1449911D01*
G01Y1455393D02*
Y1453848D01*
G01Y1459330D02*
Y1457785D01*
G01Y1463267D02*
Y1461722D01*
G01Y1467204D02*
Y1465659D01*
G01X-34136Y1465670D02*
Y1467193D01*
G01Y1461733D02*
Y1463256D01*
G01Y1457796D02*
Y1459319D01*
G01Y1453859D02*
Y1455382D01*
G01Y1449922D02*
Y1451445D01*
G01D02*
Y1449922D01*
G01Y1455382D02*
Y1453859D01*
G01Y1459319D02*
Y1457796D01*
G01Y1463256D02*
Y1461733D01*
G01Y1467193D02*
Y1465670D01*
G01X-34607Y1451786D02*
Y1449581D01*
G01Y1455723D02*
Y1453518D01*
G01Y1459660D02*
Y1457455D01*
G01Y1467534D02*
Y1465329D01*
G01Y1463597D02*
Y1461392D01*
G01X-35357Y1465684D02*
Y1467179D01*
G01Y1461747D02*
Y1463242D01*
G01Y1457810D02*
Y1459305D01*
G01Y1453873D02*
Y1455368D01*
G01Y1449936D02*
Y1451431D01*
G01D02*
Y1449936D01*
G01Y1455368D02*
Y1453873D01*
G01Y1459305D02*
Y1457810D01*
G01Y1463242D02*
Y1461747D01*
G01Y1467179D02*
Y1465684D01*
G01X-35545Y1451864D02*
Y1449502D01*
G01Y1455801D02*
Y1453439D01*
G01Y1459738D02*
Y1457376D01*
G01Y1463675D02*
Y1461313D01*
G01Y1467612D02*
Y1465250D01*
G01Y1471549D02*
Y1469187D01*
G01X-35594Y1465707D02*
Y1467156D01*
G01Y1461770D02*
Y1463219D01*
G01Y1457833D02*
Y1459282D01*
G01Y1453896D02*
Y1455345D01*
G01Y1449959D02*
Y1451408D01*
G01D02*
Y1449959D01*
G01Y1455345D02*
Y1453896D01*
G01Y1459282D02*
Y1457833D01*
G01Y1463219D02*
Y1461770D01*
G01Y1467156D02*
Y1465707D01*
G01X-37870Y1465926D02*
Y1466937D01*
G01Y1461989D02*
Y1463000D01*
G01Y1458052D02*
Y1459063D01*
G01Y1454115D02*
Y1455126D01*
G01Y1450178D02*
Y1451189D01*
G01D02*
Y1450178D01*
G01Y1455126D02*
Y1454115D01*
G01Y1459063D02*
Y1458052D01*
G01Y1463000D02*
Y1461989D01*
G01Y1466937D02*
Y1465926D01*
G01X-38108Y1465949D02*
Y1466914D01*
G01Y1462012D02*
Y1462977D01*
G01Y1458075D02*
Y1459040D01*
G01Y1454138D02*
Y1455103D01*
G01Y1450201D02*
Y1451166D01*
G01D02*
Y1450201D01*
G01Y1455103D02*
Y1454138D01*
G01Y1459040D02*
Y1458075D01*
G01Y1462977D02*
Y1462012D01*
G01Y1466914D02*
Y1465949D01*
G01X-38425Y1451864D02*
Y1449502D01*
G01Y1455801D02*
Y1453439D01*
G01Y1459738D02*
Y1457376D01*
G01Y1467612D02*
Y1465250D01*
G01Y1463675D02*
Y1461313D01*
G01Y1471549D02*
Y1469187D01*
G01X-35350Y1489305D02*
X-10630Y1489030D01*
G01D02*
X-35350Y1489305D01*
G01Y1485368D02*
X-10630Y1485093D01*
G01D02*
X-35350Y1485368D01*
G01Y1481431D02*
X-10630Y1481156D01*
G01D02*
X-35350Y1481431D01*
G01Y1477494D02*
X-10630Y1477219D01*
G01D02*
X-35350Y1477494D01*
G01Y1473557D02*
X-10630Y1473282D01*
G01D02*
X-35350Y1473557D01*
G01Y1469620D02*
X-10630Y1469345D01*
G01D02*
X-35350Y1469620D01*
G01X-39607Y1489404D02*
X-27992D01*
G01X-35545Y1488951D02*
X0D01*
G01X-39607Y1488872D02*
X-24508D01*
G01Y1487297D02*
X-39607D01*
G01X-35545Y1487219D02*
X0D01*
G01X-39607Y1486254D02*
X-24843D01*
G01X-35545Y1485014D02*
X0D01*
G01X-39607Y1484935D02*
X-24508D01*
G01Y1483360D02*
X-39607D01*
G01X-35545Y1483282D02*
X0D01*
G01X-39607Y1482278D02*
X-24843D01*
G01X-35545Y1481077D02*
X0D01*
G01X-39607Y1480998D02*
X-24508D01*
G01Y1479423D02*
X-39607D01*
G01X-35545Y1479345D02*
X0D01*
G01X-27992Y1479128D02*
X-39607D01*
G01X-35545Y1477140D02*
X0D01*
G01X-39607Y1477061D02*
X-24508D01*
G01Y1475486D02*
X-39607D01*
G01X-35545Y1475408D02*
X0D01*
G01X-35545Y1473203D02*
X0D01*
G01X-39607Y1473124D02*
X-24508D01*
G01Y1471549D02*
X-39607D01*
G01X-35545Y1471471D02*
X0D01*
G01X-35545Y1469266D02*
X0D01*
G01X-35350Y1486864D02*
X-10630Y1487140D01*
G01X-35350Y1486864D02*
X-10630Y1487140D01*
G01X-35350Y1482927D02*
X-10630Y1483203D01*
G01X-35350Y1482927D02*
X-10630Y1483203D01*
G01X-35350Y1478990D02*
X-10630Y1479266D01*
G01X-35350Y1478990D02*
X-10630Y1479266D01*
G01X-35350Y1475053D02*
X-10630Y1475329D01*
G01X-35350Y1475053D02*
X-10630Y1475329D01*
G01X-35350Y1471116D02*
X-10630Y1471392D01*
G01X-35350Y1471116D02*
X-10630Y1471392D01*
G01X-38108Y1486599D02*
X-35350Y1486864D01*
G01D02*
X-38108Y1486599D01*
G01Y1482662D02*
X-35350Y1482927D01*
G01D02*
X-38108Y1482662D01*
G01Y1478725D02*
X-35350Y1478990D01*
G01D02*
X-38108Y1478725D01*
G01Y1474788D02*
X-35350Y1475053D01*
G01D02*
X-38108Y1474788D01*
G01Y1470851D02*
X-35350Y1471116D01*
G01D02*
X-38108Y1470851D01*
G01Y1489571D02*
X-35350Y1489305D01*
G01X-38108Y1489571D02*
X-35350Y1489305D01*
G01X-38108Y1485634D02*
X-35350Y1485368D01*
G01X-38108Y1485634D02*
X-35350Y1485368D01*
G01X-38108Y1481697D02*
X-35350Y1481431D01*
G01X-38108Y1481697D02*
X-35350Y1481431D01*
G01X-38108Y1477760D02*
X-35350Y1477494D01*
G01X-38108Y1477760D02*
X-35350Y1477494D01*
G01X-38108Y1473823D02*
X-35350Y1473557D01*
G01X-38108Y1473823D02*
X-35350Y1473557D01*
G01X-38108Y1469886D02*
X-35350Y1469620D01*
G01X-38108Y1469886D02*
X-35350Y1469620D01*
G01X-24121Y1489180D02*
Y1490927D01*
G01Y1485243D02*
Y1486990D01*
G01Y1481306D02*
Y1483053D01*
G01Y1477369D02*
Y1479116D01*
G01Y1469495D02*
Y1471241D01*
G01Y1473432D02*
Y1475178D01*
G01D02*
Y1473432D01*
G01Y1471241D02*
Y1469495D01*
G01Y1479116D02*
Y1477369D01*
G01Y1483053D02*
Y1481306D01*
G01Y1486990D02*
Y1485243D01*
G01Y1490927D02*
Y1489180D01*
G01X-24508Y1475486D02*
Y1473124D01*
G01Y1479423D02*
Y1477061D01*
G01Y1483360D02*
Y1480998D01*
G01Y1487297D02*
Y1484935D01*
G01Y1491234D02*
Y1488872D01*
G01X-24843Y1486254D02*
Y1505900D01*
G01X-26565Y1489207D02*
Y1490899D01*
G01Y1485270D02*
Y1486962D01*
G01Y1481333D02*
Y1483025D01*
G01Y1477396D02*
Y1479088D01*
G01Y1473459D02*
Y1475151D01*
G01Y1469522D02*
Y1471214D01*
G01D02*
Y1469522D01*
G01Y1475151D02*
Y1473459D01*
G01Y1479088D02*
Y1477396D01*
G01Y1483025D02*
Y1481333D01*
G01Y1486962D02*
Y1485270D01*
G01Y1490899D02*
Y1489207D01*
G01X-26942Y1489212D02*
Y1490895D01*
G01Y1485275D02*
Y1486958D01*
G01Y1481338D02*
Y1483021D01*
G01Y1477401D02*
Y1479084D01*
G01Y1473464D02*
Y1475147D01*
G01Y1469527D02*
Y1471210D01*
G01D02*
Y1469527D01*
G01Y1475147D02*
Y1473464D01*
G01Y1479084D02*
Y1477401D01*
G01Y1483021D02*
Y1481338D01*
G01Y1486958D02*
Y1485275D01*
G01Y1490895D02*
Y1489212D01*
G01X-27264Y1475486D02*
Y1473124D01*
G01Y1479423D02*
Y1477061D01*
G01Y1483360D02*
Y1480998D01*
G01Y1487297D02*
Y1484935D01*
G01Y1491234D02*
Y1488872D01*
G01X-27992Y1486254D02*
Y1505900D01*
G01X-31941Y1489267D02*
Y1490840D01*
G01Y1485330D02*
Y1486903D01*
G01Y1481393D02*
Y1482966D01*
G01Y1477456D02*
Y1479028D01*
G01Y1473519D02*
Y1475091D01*
G01Y1469582D02*
Y1471154D01*
G01D02*
Y1469582D01*
G01Y1475091D02*
Y1473519D01*
G01Y1479028D02*
Y1477456D01*
G01Y1482966D02*
Y1481393D01*
G01Y1486903D02*
Y1485330D01*
G01Y1490840D02*
Y1489267D01*
G01X-32318Y1489271D02*
Y1490835D01*
G01Y1485334D02*
Y1486898D01*
G01Y1481397D02*
Y1482961D01*
G01Y1477460D02*
Y1479024D01*
G01Y1473523D02*
Y1475087D01*
G01Y1469586D02*
Y1471150D01*
G01D02*
Y1469586D01*
G01Y1475087D02*
Y1473523D01*
G01Y1479024D02*
Y1477460D01*
G01Y1482961D02*
Y1481397D01*
G01Y1486898D02*
Y1485334D01*
G01Y1490835D02*
Y1489271D01*
G01X-33153Y1489281D02*
Y1490826D01*
G01Y1485344D02*
Y1486889D01*
G01Y1481407D02*
Y1482952D01*
G01Y1477470D02*
Y1479015D01*
G01Y1473533D02*
Y1475078D01*
G01Y1469596D02*
Y1471141D01*
G01D02*
Y1469596D01*
G01Y1475078D02*
Y1473533D01*
G01Y1479015D02*
Y1477470D01*
G01Y1482952D02*
Y1481407D01*
G01Y1486889D02*
Y1485344D01*
G01Y1490826D02*
Y1489281D01*
G01X-34136Y1489292D02*
Y1490815D01*
G01Y1485355D02*
Y1486878D01*
G01Y1481418D02*
Y1482941D01*
G01Y1477481D02*
Y1479004D01*
G01Y1473544D02*
Y1475067D01*
G01Y1469607D02*
Y1471130D01*
G01D02*
Y1469607D01*
G01Y1475067D02*
Y1473544D01*
G01Y1479004D02*
Y1477481D01*
G01Y1482941D02*
Y1481418D01*
G01Y1486878D02*
Y1485355D01*
G01Y1490815D02*
Y1489292D01*
G01X-34607Y1475408D02*
Y1473203D01*
G01Y1471471D02*
Y1469266D01*
G01Y1479345D02*
Y1477140D01*
G01Y1483282D02*
Y1481077D01*
G01Y1491156D02*
Y1488951D01*
G01Y1487219D02*
Y1485014D01*
G01X-35357Y1489306D02*
Y1490801D01*
G01Y1485369D02*
Y1486864D01*
G01Y1481432D02*
Y1482927D01*
G01Y1477495D02*
Y1478990D01*
G01Y1473558D02*
Y1475053D01*
G01Y1469621D02*
Y1471116D01*
G01D02*
Y1469621D01*
G01Y1475053D02*
Y1473558D01*
G01Y1478990D02*
Y1477495D01*
G01Y1482927D02*
Y1481432D01*
G01Y1486864D02*
Y1485369D01*
G01Y1490801D02*
Y1489306D01*
G01X-35545Y1475486D02*
Y1473124D01*
G01Y1479423D02*
Y1477061D01*
G01Y1483360D02*
Y1480998D01*
G01Y1487297D02*
Y1484935D01*
G01Y1491234D02*
Y1488872D01*
G01X-35594Y1489329D02*
Y1490778D01*
G01Y1485392D02*
Y1486841D01*
G01Y1481455D02*
Y1482904D01*
G01Y1477518D02*
Y1478967D01*
G01Y1473581D02*
Y1475030D01*
G01Y1469644D02*
Y1471093D01*
G01D02*
Y1469644D01*
G01Y1475030D02*
Y1473581D01*
G01Y1478967D02*
Y1477518D01*
G01Y1482904D02*
Y1481455D01*
G01Y1486841D02*
Y1485392D01*
G01Y1490778D02*
Y1489329D01*
G01X-37870Y1489548D02*
Y1490559D01*
G01Y1485611D02*
Y1486622D01*
G01Y1481674D02*
Y1482685D01*
G01Y1477737D02*
Y1478748D01*
G01Y1473800D02*
Y1474811D01*
G01Y1469863D02*
Y1470874D01*
G01D02*
Y1469863D01*
G01Y1474811D02*
Y1473800D01*
G01Y1478748D02*
Y1477737D01*
G01Y1482685D02*
Y1481674D01*
G01Y1486622D02*
Y1485611D01*
G01Y1490559D02*
Y1489548D01*
G01X-38108Y1489571D02*
Y1490536D01*
G01Y1485634D02*
Y1486599D01*
G01Y1481697D02*
Y1482662D01*
G01Y1477760D02*
Y1478725D01*
G01Y1473823D02*
Y1474788D01*
G01Y1469886D02*
Y1470851D01*
G01D02*
Y1469886D01*
G01Y1474788D02*
Y1473823D01*
G01Y1478725D02*
Y1477760D01*
G01Y1482662D02*
Y1481697D01*
G01Y1486599D02*
Y1485634D01*
G01Y1490536D02*
Y1489571D01*
G01X-38425Y1475486D02*
Y1473124D01*
G01Y1479423D02*
Y1477061D01*
G01Y1483360D02*
Y1480998D01*
G01Y1487297D02*
Y1484935D01*
G01Y1491234D02*
Y1488872D01*
G01X-38108Y1510221D02*
X-35350Y1510486D01*
G01D02*
X-38108Y1510221D01*
G01Y1506284D02*
X-35350Y1506549D01*
G01D02*
X-38108Y1506284D01*
G01Y1502347D02*
X-35350Y1502612D01*
G01D02*
X-38108Y1502347D01*
G01Y1498410D02*
X-35350Y1498675D01*
G01D02*
X-38108Y1498410D01*
G01Y1494473D02*
X-35350Y1494738D01*
G01D02*
X-38108Y1494473D01*
G01Y1490536D02*
X-35350Y1490801D01*
G01D02*
X-38108Y1490536D01*
G01X-35350Y1508990D02*
X-10630Y1508715D01*
G01D02*
X-35350Y1508990D01*
G01Y1505053D02*
X-10630Y1504778D01*
G01D02*
X-35350Y1505053D01*
G01Y1501116D02*
X-10630Y1500841D01*
G01D02*
X-35350Y1501116D01*
G01Y1497179D02*
X-10630Y1496904D01*
G01D02*
X-35350Y1497179D01*
G01Y1493242D02*
X-10630Y1492967D01*
G01D02*
X-35350Y1493242D01*
G01X-24508Y1510919D02*
X-39607D01*
G01X-35545Y1510841D02*
X0D01*
G01X-39607Y1509876D02*
X-24843D01*
G01X-35545Y1508636D02*
X0D01*
G01X-39607Y1508557D02*
X-24508D01*
G01Y1506982D02*
X-39607D01*
G01X-35545Y1506904D02*
X0D01*
G01X-39607Y1505900D02*
X-24843D01*
G01X-35545Y1504699D02*
X0D01*
G01X-39607Y1504620D02*
X-24508D01*
G01Y1503045D02*
X-39607D01*
G01X-35545Y1502967D02*
X0D01*
G01X-27992Y1502750D02*
X-39607D01*
G01X-35545Y1500762D02*
X0D01*
G01X-39607Y1500683D02*
X-24508D01*
G01Y1499108D02*
X-39607D01*
G01X-35545Y1499030D02*
X0D01*
G01X-35545Y1496825D02*
X0D01*
G01X-39607Y1496746D02*
X-24508D01*
G01Y1495171D02*
X-39607D01*
G01X-35545Y1495093D02*
X0D01*
G01X-35545Y1492888D02*
X0D01*
G01X-39607Y1492809D02*
X-24508D01*
G01Y1491234D02*
X-39607D01*
G01X-35545Y1491156D02*
X0D01*
G01X-35350Y1510486D02*
X-10630Y1510762D01*
G01X-35350Y1510486D02*
X-10630Y1510762D01*
G01X-35350Y1506549D02*
X-10630Y1506825D01*
G01X-35350Y1506549D02*
X-10630Y1506825D01*
G01X-35350Y1502612D02*
X-10630Y1502888D01*
G01X-35350Y1502612D02*
X-10630Y1502888D01*
G01X-35350Y1498675D02*
X-10630Y1498951D01*
G01X-35350Y1498675D02*
X-10630Y1498951D01*
G01X-35350Y1494738D02*
X-10630Y1495014D01*
G01X-35350Y1494738D02*
X-10630Y1495014D01*
G01X-35350Y1490801D02*
X-10630Y1491077D01*
G01X-35350Y1490801D02*
X-10630Y1491077D01*
G01X-38108Y1509256D02*
X-35350Y1508990D01*
G01X-38108Y1509256D02*
X-35350Y1508990D01*
G01X-38108Y1505319D02*
X-35350Y1505053D01*
G01X-38108Y1505319D02*
X-35350Y1505053D01*
G01X-38108Y1501382D02*
X-35350Y1501116D01*
G01X-38108Y1501382D02*
X-35350Y1501116D01*
G01X-38108Y1497445D02*
X-35350Y1497179D01*
G01X-38108Y1497445D02*
X-35350Y1497179D01*
G01X-38108Y1493508D02*
X-35350Y1493242D01*
G01X-38108Y1493508D02*
X-35350Y1493242D01*
G01X-24121Y1508865D02*
Y1510612D01*
G01Y1504928D02*
Y1506675D01*
G01Y1500991D02*
Y1502738D01*
G01Y1493117D02*
Y1494864D01*
G01Y1497054D02*
Y1498801D01*
G01D02*
Y1497054D01*
G01Y1494864D02*
Y1493117D01*
G01Y1502738D02*
Y1500991D01*
G01Y1506675D02*
Y1504928D01*
G01Y1510612D02*
Y1508865D01*
G01X-24508Y1495171D02*
Y1492809D01*
G01Y1499108D02*
Y1496746D01*
G01Y1503045D02*
Y1500683D01*
G01Y1506982D02*
Y1504620D01*
G01Y1510919D02*
Y1508557D01*
G01X-24843Y1509876D02*
Y1529522D01*
G01X-26565Y1508892D02*
Y1510584D01*
G01Y1504955D02*
Y1506647D01*
G01Y1501018D02*
Y1502710D01*
G01Y1497081D02*
Y1498773D01*
G01Y1493144D02*
Y1494836D01*
G01D02*
Y1493144D01*
G01Y1498773D02*
Y1497081D01*
G01Y1502710D02*
Y1501018D01*
G01Y1506647D02*
Y1504955D01*
G01Y1510584D02*
Y1508892D01*
G01X-26942Y1508897D02*
Y1510580D01*
G01Y1504960D02*
Y1506643D01*
G01Y1501023D02*
Y1502706D01*
G01Y1497086D02*
Y1498769D01*
G01Y1493149D02*
Y1494832D01*
G01D02*
Y1493149D01*
G01Y1498769D02*
Y1497086D01*
G01Y1502706D02*
Y1501023D01*
G01Y1506643D02*
Y1504960D01*
G01Y1510580D02*
Y1508897D01*
G01X-27264Y1495171D02*
Y1492809D01*
G01Y1499108D02*
Y1496746D01*
G01Y1503045D02*
Y1500683D01*
G01Y1506982D02*
Y1504620D01*
G01Y1510919D02*
Y1508557D01*
G01X-27992Y1509876D02*
Y1529522D01*
G01X-31941Y1508953D02*
Y1510525D01*
G01Y1505016D02*
Y1506588D01*
G01Y1501078D02*
Y1502651D01*
G01Y1493204D02*
Y1494777D01*
G01Y1497141D02*
Y1498714D01*
G01D02*
Y1497141D01*
G01Y1494777D02*
Y1493204D01*
G01Y1502651D02*
Y1501078D01*
G01Y1506588D02*
Y1505016D01*
G01Y1510525D02*
Y1508953D01*
G01X-32318Y1508956D02*
Y1510520D01*
G01Y1505019D02*
Y1506583D01*
G01Y1501082D02*
Y1502646D01*
G01Y1493208D02*
Y1494772D01*
G01Y1497145D02*
Y1498709D01*
G01D02*
Y1497145D01*
G01Y1494772D02*
Y1493208D01*
G01Y1502646D02*
Y1501082D01*
G01Y1506583D02*
Y1505019D01*
G01Y1510520D02*
Y1508956D01*
G01X-33153Y1508966D02*
Y1510511D01*
G01Y1505029D02*
Y1506574D01*
G01Y1501092D02*
Y1502637D01*
G01Y1497155D02*
Y1498700D01*
G01Y1493218D02*
Y1494763D01*
G01D02*
Y1493218D01*
G01Y1498700D02*
Y1497155D01*
G01Y1502637D02*
Y1501092D01*
G01Y1506574D02*
Y1505029D01*
G01Y1510511D02*
Y1508966D01*
G01X-34136Y1508977D02*
Y1510500D01*
G01Y1505040D02*
Y1506563D01*
G01Y1501103D02*
Y1502626D01*
G01Y1493229D02*
Y1494752D01*
G01Y1497166D02*
Y1498689D01*
G01D02*
Y1497166D01*
G01Y1494752D02*
Y1493229D01*
G01Y1502626D02*
Y1501103D01*
G01Y1506563D02*
Y1505040D01*
G01Y1510500D02*
Y1508977D01*
G01X-34607Y1499030D02*
Y1496825D01*
G01Y1495093D02*
Y1492888D01*
G01Y1502967D02*
Y1500762D01*
G01Y1506904D02*
Y1504699D01*
G01Y1510841D02*
Y1508636D01*
G01X-35357Y1508991D02*
Y1510486D01*
G01Y1505054D02*
Y1506549D01*
G01Y1501117D02*
Y1502612D01*
G01Y1497180D02*
Y1498675D01*
G01Y1493243D02*
Y1494738D01*
G01D02*
Y1493243D01*
G01Y1498675D02*
Y1497180D01*
G01Y1502612D02*
Y1501117D01*
G01Y1506549D02*
Y1505054D01*
G01Y1510486D02*
Y1508991D01*
G01X-35545Y1495171D02*
Y1492809D01*
G01Y1499108D02*
Y1496746D01*
G01Y1503045D02*
Y1500683D01*
G01Y1506982D02*
Y1504620D01*
G01Y1510919D02*
Y1508557D01*
G01X-35594Y1509014D02*
Y1510463D01*
G01Y1505077D02*
Y1506526D01*
G01Y1501140D02*
Y1502589D01*
G01Y1497203D02*
Y1498652D01*
G01Y1493266D02*
Y1494715D01*
G01D02*
Y1493266D01*
G01Y1498652D02*
Y1497203D01*
G01Y1502589D02*
Y1501140D01*
G01Y1506526D02*
Y1505077D01*
G01Y1510463D02*
Y1509014D01*
G01X-37870Y1509233D02*
Y1510244D01*
G01Y1505296D02*
Y1506307D01*
G01Y1501359D02*
Y1502370D01*
G01Y1497422D02*
Y1498433D01*
G01Y1493485D02*
Y1494496D01*
G01D02*
Y1493485D01*
G01Y1498433D02*
Y1497422D01*
G01Y1502370D02*
Y1501359D01*
G01Y1506307D02*
Y1505296D01*
G01Y1510244D02*
Y1509233D01*
G01X-38108Y1509256D02*
Y1510221D01*
G01Y1505319D02*
Y1506284D01*
G01Y1501382D02*
Y1502347D01*
G01Y1497445D02*
Y1498410D01*
G01Y1493508D02*
Y1494473D01*
G01D02*
Y1493508D01*
G01Y1498410D02*
Y1497445D01*
G01Y1502347D02*
Y1501382D01*
G01Y1506284D02*
Y1505319D01*
G01Y1510221D02*
Y1509256D01*
G01X-38425Y1499108D02*
Y1496746D01*
G01Y1495171D02*
Y1492809D01*
G01Y1503045D02*
Y1500683D01*
G01Y1506982D02*
Y1504620D01*
G01Y1510919D02*
Y1508557D01*
G01X-38108Y1529906D02*
X-35350Y1530171D01*
G01D02*
X-38108Y1529906D01*
G01Y1525969D02*
X-35350Y1526234D01*
G01D02*
X-38108Y1525969D01*
G01Y1522032D02*
X-35350Y1522297D01*
G01D02*
X-38108Y1522032D01*
G01Y1518095D02*
X-35350Y1518360D01*
G01D02*
X-38108Y1518095D01*
G01Y1514158D02*
X-35350Y1514423D01*
G01D02*
X-38108Y1514158D01*
G01Y1532878D02*
X-35350Y1532612D01*
G01X-38108Y1532878D02*
X-35350Y1532612D01*
G01X-38108Y1528941D02*
X-35350Y1528675D01*
G01X-38108Y1528941D02*
X-35350Y1528675D01*
G01X-38108Y1525004D02*
X-35350Y1524738D01*
G01X-38108Y1525004D02*
X-35350Y1524738D01*
G01X-38108Y1521067D02*
X-35350Y1520801D01*
G01X-38108Y1521067D02*
X-35350Y1520801D01*
G01Y1532612D02*
X-10630Y1532337D01*
G01D02*
X-35350Y1532612D01*
G01Y1528675D02*
X-10630Y1528400D01*
G01D02*
X-35350Y1528675D01*
G01Y1524738D02*
X-10630Y1524463D01*
G01D02*
X-35350Y1524738D01*
G01Y1520801D02*
X-10630Y1520526D01*
G01D02*
X-35350Y1520801D01*
G01Y1516864D02*
X-10630Y1516589D01*
G01D02*
X-35350Y1516864D01*
G01Y1512927D02*
X-10630Y1512652D01*
G01D02*
X-35350Y1512927D01*
G01X-35545Y1532258D02*
X0D01*
G01X-39607Y1532179D02*
X-24508D01*
G01Y1530604D02*
X-39607D01*
G01X-35545Y1530526D02*
X0D01*
G01X-39607Y1529522D02*
X-24843D01*
G01X-35545Y1528321D02*
X0D01*
G01X-39607Y1528242D02*
X-24508D01*
G01Y1526667D02*
X-39607D01*
G01X-35545Y1526589D02*
X0D01*
G01X-27992Y1526372D02*
X-39607D01*
G01X-35545Y1524384D02*
X0D01*
G01X-39607Y1524305D02*
X-24508D01*
G01Y1522730D02*
X-39607D01*
G01X-35545Y1522652D02*
X0D01*
G01X-35545Y1520447D02*
X0D01*
G01X-39607Y1520368D02*
X-24508D01*
G01Y1518793D02*
X-39607D01*
G01X-35545Y1518715D02*
X0D01*
G01X-35545Y1516510D02*
X0D01*
G01X-39607Y1516431D02*
X-24508D01*
G01Y1514856D02*
X-39607D01*
G01X-35545Y1514778D02*
X0D01*
G01X-39607Y1513026D02*
X-27992D01*
G01X-35545Y1512573D02*
X0D01*
G01X-39607Y1512494D02*
X-24508D01*
G01X-35350Y1530171D02*
X-10630Y1530447D01*
G01X-35350Y1530171D02*
X-10630Y1530447D01*
G01X-35350Y1526234D02*
X-10630Y1526510D01*
G01X-35350Y1526234D02*
X-10630Y1526510D01*
G01X-35350Y1522297D02*
X-10630Y1522573D01*
G01X-35350Y1522297D02*
X-10630Y1522573D01*
G01X-35350Y1518360D02*
X-10630Y1518636D01*
G01X-35350Y1518360D02*
X-10630Y1518636D01*
G01X-35350Y1514423D02*
X-10630Y1514699D01*
G01X-35350Y1514423D02*
X-10630Y1514699D01*
G01X-38108Y1517130D02*
X-35350Y1516864D01*
G01X-38108Y1517130D02*
X-35350Y1516864D01*
G01X-38108Y1513193D02*
X-35350Y1512927D01*
G01X-38108Y1513193D02*
X-35350Y1512927D01*
G01X-24121Y1532487D02*
Y1534234D01*
G01Y1528550D02*
Y1530297D01*
G01Y1524613D02*
Y1526360D01*
G01Y1516739D02*
Y1518486D01*
G01Y1520676D02*
Y1522423D01*
G01Y1512802D02*
Y1514549D01*
G01D02*
Y1512802D01*
G01Y1522423D02*
Y1520676D01*
G01Y1518486D02*
Y1516739D01*
G01Y1526360D02*
Y1524613D01*
G01Y1530297D02*
Y1528550D01*
G01Y1534234D02*
Y1532487D01*
G01X-24508Y1514856D02*
Y1512494D01*
G01Y1518793D02*
Y1516431D01*
G01Y1522730D02*
Y1520368D01*
G01Y1526667D02*
Y1524305D01*
G01Y1530604D02*
Y1528242D01*
G01Y1534541D02*
Y1532179D01*
G01X-26565Y1532514D02*
Y1534206D01*
G01Y1528577D02*
Y1530269D01*
G01Y1524640D02*
Y1526332D01*
G01Y1520703D02*
Y1522395D01*
G01Y1516766D02*
Y1518458D01*
G01Y1512829D02*
Y1514521D01*
G01D02*
Y1512829D01*
G01Y1518458D02*
Y1516766D01*
G01Y1522395D02*
Y1520703D01*
G01Y1526332D02*
Y1524640D01*
G01Y1530269D02*
Y1528577D01*
G01Y1534206D02*
Y1532514D01*
G01X-26942Y1532519D02*
Y1534202D01*
G01Y1528582D02*
Y1530265D01*
G01Y1524645D02*
Y1526328D01*
G01Y1520708D02*
Y1522391D01*
G01Y1516771D02*
Y1518454D01*
G01Y1512834D02*
Y1514517D01*
G01D02*
Y1512834D01*
G01Y1518454D02*
Y1516771D01*
G01Y1522391D02*
Y1520708D01*
G01Y1526328D02*
Y1524645D01*
G01Y1530265D02*
Y1528582D01*
G01Y1534202D02*
Y1532519D01*
G01X-27264Y1514856D02*
Y1512494D01*
G01Y1518793D02*
Y1516431D01*
G01Y1522730D02*
Y1520368D01*
G01Y1526667D02*
Y1524305D01*
G01Y1530604D02*
Y1528242D01*
G01Y1534541D02*
Y1532179D01*
G01X-31941Y1532575D02*
Y1534147D01*
G01Y1528638D02*
Y1530210D01*
G01Y1524701D02*
Y1526273D01*
G01Y1516827D02*
Y1518399D01*
G01Y1520764D02*
Y1522336D01*
G01Y1512890D02*
Y1514462D01*
G01D02*
Y1512890D01*
G01Y1522336D02*
Y1520764D01*
G01Y1518399D02*
Y1516827D01*
G01Y1526273D02*
Y1524701D01*
G01Y1530210D02*
Y1528638D01*
G01Y1534147D02*
Y1532575D01*
G01X-32318Y1532578D02*
Y1534142D01*
G01Y1528641D02*
Y1530205D01*
G01Y1524704D02*
Y1526268D01*
G01Y1516830D02*
Y1518394D01*
G01Y1520767D02*
Y1522331D01*
G01Y1512893D02*
Y1514457D01*
G01D02*
Y1512893D01*
G01Y1522331D02*
Y1520767D01*
G01Y1518394D02*
Y1516830D01*
G01Y1526268D02*
Y1524704D01*
G01Y1530205D02*
Y1528641D01*
G01Y1534142D02*
Y1532578D01*
G01X-33153Y1532588D02*
Y1534133D01*
G01Y1528651D02*
Y1530196D01*
G01Y1524714D02*
Y1526259D01*
G01Y1520777D02*
Y1522322D01*
G01Y1516840D02*
Y1518385D01*
G01Y1512903D02*
Y1514448D01*
G01D02*
Y1512903D01*
G01Y1518385D02*
Y1516840D01*
G01Y1522322D02*
Y1520777D01*
G01Y1526259D02*
Y1524714D01*
G01Y1530196D02*
Y1528651D01*
G01Y1534133D02*
Y1532588D01*
G01X-34136Y1532599D02*
Y1534122D01*
G01Y1528662D02*
Y1530185D01*
G01Y1524725D02*
Y1526248D01*
G01Y1516851D02*
Y1518374D01*
G01Y1520788D02*
Y1522311D01*
G01Y1512914D02*
Y1514437D01*
G01D02*
Y1512914D01*
G01Y1522311D02*
Y1520788D01*
G01Y1518374D02*
Y1516851D01*
G01Y1526248D02*
Y1524725D01*
G01Y1530185D02*
Y1528662D01*
G01Y1534122D02*
Y1532599D01*
G01X-34607Y1514778D02*
Y1512573D01*
G01Y1522652D02*
Y1520447D01*
G01Y1518715D02*
Y1516510D01*
G01Y1526589D02*
Y1524384D01*
G01Y1530526D02*
Y1528321D01*
G01Y1534463D02*
Y1532258D01*
G01X-35357Y1532613D02*
Y1534108D01*
G01Y1528676D02*
Y1530171D01*
G01Y1524739D02*
Y1526234D01*
G01Y1520802D02*
Y1522297D01*
G01Y1516865D02*
Y1518360D01*
G01Y1512928D02*
Y1514423D01*
G01D02*
Y1512928D01*
G01Y1518360D02*
Y1516865D01*
G01Y1522297D02*
Y1520802D01*
G01Y1526234D02*
Y1524739D01*
G01Y1530171D02*
Y1528676D01*
G01Y1534108D02*
Y1532613D01*
G01X-35545Y1514856D02*
Y1512494D01*
G01Y1518793D02*
Y1516431D01*
G01Y1522730D02*
Y1520368D01*
G01Y1526667D02*
Y1524305D01*
G01Y1530604D02*
Y1528242D01*
G01Y1534541D02*
Y1532179D01*
G01X-35594Y1532636D02*
Y1534085D01*
G01Y1528699D02*
Y1530148D01*
G01Y1524762D02*
Y1526211D01*
G01Y1520825D02*
Y1522274D01*
G01Y1516888D02*
Y1518337D01*
G01Y1512951D02*
Y1514400D01*
G01D02*
Y1512951D01*
G01Y1518337D02*
Y1516888D01*
G01Y1522274D02*
Y1520825D01*
G01Y1526211D02*
Y1524762D01*
G01Y1530148D02*
Y1528699D01*
G01Y1534085D02*
Y1532636D01*
G01X-37870Y1528918D02*
Y1529929D01*
G01Y1524981D02*
Y1525992D01*
G01Y1517107D02*
Y1518118D01*
G01Y1521044D02*
Y1522055D01*
G01Y1513170D02*
Y1514181D01*
G01D02*
Y1513170D01*
G01Y1522055D02*
Y1521044D01*
G01Y1518118D02*
Y1517107D01*
G01Y1525992D02*
Y1524981D01*
G01Y1529929D02*
Y1528918D01*
G01X-38108Y1528941D02*
Y1529906D01*
G01Y1525004D02*
Y1525969D01*
G01Y1517130D02*
Y1518095D01*
G01Y1521067D02*
Y1522032D01*
G01Y1513193D02*
Y1514158D01*
G01D02*
Y1513193D01*
G01Y1518095D02*
Y1517130D01*
G01Y1522032D02*
Y1521067D01*
G01Y1525969D02*
Y1525004D01*
G01Y1529906D02*
Y1528941D01*
G01X-38425Y1514856D02*
Y1512494D01*
G01Y1518793D02*
Y1516431D01*
G01Y1526667D02*
Y1524305D01*
G01Y1522730D02*
Y1520368D01*
G01Y1530604D02*
Y1528242D01*
G01Y1534541D02*
Y1532179D01*
G01X-35350Y1552297D02*
X-10630Y1552022D01*
G01D02*
X-35350Y1552297D01*
G01Y1548360D02*
X-10630Y1548085D01*
G01D02*
X-35350Y1548360D01*
G01X-39607Y1553144D02*
X-24843D01*
G01X-35545Y1551943D02*
X0D01*
G01X-39607Y1551864D02*
X-24508D01*
G01Y1550290D02*
X-39607D01*
G01X-35545Y1550211D02*
X0D01*
G01X-27992Y1549994D02*
X-39607D01*
G01X-35545Y1548006D02*
X0D01*
G01X-39607Y1547927D02*
X-24508D01*
G01Y1546353D02*
X-39607D01*
G01X-35545Y1546274D02*
X0D01*
G01X-35545Y1544069D02*
X0D01*
G01X-39607Y1543990D02*
X-24508D01*
G01Y1542416D02*
X-39607D01*
G01X-35545Y1542337D02*
X0D01*
G01X-35545Y1540132D02*
X0D01*
G01X-39607Y1540053D02*
X-24508D01*
G01X-35350Y1553793D02*
X-10630Y1554069D01*
G01X-35350Y1553793D02*
X-10630Y1554069D01*
G01X-35350Y1549856D02*
X-10630Y1550132D01*
G01X-35350Y1549856D02*
X-10630Y1550132D01*
G01X-35350Y1545919D02*
X-10630Y1546195D01*
G01X-35350Y1545919D02*
X-10630Y1546195D01*
G01X-35350Y1541982D02*
X-10630Y1542258D01*
G01X-35350Y1541982D02*
X-10630Y1542258D01*
G01X-35350Y1538045D02*
X-10630Y1538321D01*
G01X-35350Y1538045D02*
X-10630Y1538321D01*
G01X-35350Y1534108D02*
X-10630Y1534384D01*
G01X-35350Y1534108D02*
X-10630Y1534384D01*
G01X-38108Y1553528D02*
X-35350Y1553793D01*
G01D02*
X-38108Y1553528D01*
G01Y1549591D02*
X-35350Y1549856D01*
G01D02*
X-38108Y1549591D01*
G01Y1545654D02*
X-35350Y1545919D01*
G01D02*
X-38108Y1545654D01*
G01Y1541717D02*
X-35350Y1541982D01*
G01D02*
X-38108Y1541717D01*
G01Y1537780D02*
X-35350Y1538045D01*
G01D02*
X-38108Y1537780D01*
G01Y1533843D02*
X-35350Y1534108D01*
G01D02*
X-38108Y1533843D01*
G01Y1552563D02*
X-35350Y1552297D01*
G01X-38108Y1552563D02*
X-35350Y1552297D01*
G01X-38108Y1548626D02*
X-35350Y1548360D01*
G01X-38108Y1548626D02*
X-35350Y1548360D01*
G01X-38108Y1544689D02*
X-35350Y1544423D01*
G01X-38108Y1544689D02*
X-35350Y1544423D01*
G01X-38108Y1540752D02*
X-35350Y1540486D01*
G01X-38108Y1540752D02*
X-35350Y1540486D01*
G01X-38108Y1536815D02*
X-35350Y1536549D01*
G01X-38108Y1536815D02*
X-35350Y1536549D01*
G01Y1544423D02*
X-10630Y1544148D01*
G01D02*
X-35350Y1544423D01*
G01Y1540486D02*
X-10630Y1540211D01*
G01D02*
X-35350Y1540486D01*
G01Y1536549D02*
X-10630Y1536274D01*
G01D02*
X-35350Y1536549D01*
G01X-24508Y1538478D02*
X-39607D01*
G01X-35545Y1538400D02*
X0D01*
G01X-39607Y1536648D02*
X-27992D01*
G01X-35545Y1536195D02*
X0D01*
G01X-39607Y1536116D02*
X-24508D01*
G01Y1534541D02*
X-39607D01*
G01X-35545Y1534463D02*
X0D01*
G01X-39607Y1533498D02*
X-24843D01*
G01X-24121Y1552172D02*
Y1553919D01*
G01Y1548235D02*
Y1549982D01*
G01Y1544298D02*
Y1546045D01*
G01Y1540361D02*
Y1542108D01*
G01Y1536424D02*
Y1538171D01*
G01D02*
Y1536424D01*
G01Y1546045D02*
Y1544298D01*
G01Y1542108D02*
Y1540361D01*
G01Y1549982D02*
Y1548235D01*
G01Y1553919D02*
Y1552172D01*
G01X-24508Y1538478D02*
Y1536116D01*
G01Y1542416D02*
Y1540053D01*
G01Y1546353D02*
Y1543990D01*
G01Y1550290D02*
Y1547927D01*
G01Y1554227D02*
Y1551864D01*
G01X-24843Y1533498D02*
Y1553144D01*
G01X-26565Y1552199D02*
Y1553891D01*
G01Y1548262D02*
Y1549954D01*
G01Y1544325D02*
Y1546017D01*
G01Y1540388D02*
Y1542080D01*
G01Y1536451D02*
Y1538143D01*
G01D02*
Y1536451D01*
G01Y1546017D02*
Y1544325D01*
G01Y1542080D02*
Y1540388D01*
G01Y1549954D02*
Y1548262D01*
G01Y1553891D02*
Y1552199D01*
G01X-26942Y1552204D02*
Y1553887D01*
G01Y1548267D02*
Y1549950D01*
G01Y1544330D02*
Y1546013D01*
G01Y1540393D02*
Y1542076D01*
G01Y1536456D02*
Y1538139D01*
G01D02*
Y1536456D01*
G01Y1542076D02*
Y1540393D01*
G01Y1546013D02*
Y1544330D01*
G01Y1549950D02*
Y1548267D01*
G01Y1553887D02*
Y1552204D01*
G01X-27264Y1538478D02*
Y1536116D01*
G01Y1542416D02*
Y1540053D01*
G01Y1546353D02*
Y1543990D01*
G01Y1550290D02*
Y1547927D01*
G01Y1554227D02*
Y1551864D01*
G01X-27992Y1533498D02*
Y1553144D01*
G01X-31941Y1552260D02*
Y1553832D01*
G01Y1548323D02*
Y1549895D01*
G01Y1544386D02*
Y1545958D01*
G01Y1540449D02*
Y1542021D01*
G01Y1536512D02*
Y1538084D01*
G01D02*
Y1536512D01*
G01Y1545958D02*
Y1544386D01*
G01Y1542021D02*
Y1540449D01*
G01Y1549895D02*
Y1548323D01*
G01Y1553832D02*
Y1552260D01*
G01X-32318Y1552264D02*
Y1553827D01*
G01Y1548327D02*
Y1549890D01*
G01Y1540453D02*
Y1542016D01*
G01Y1544390D02*
Y1545953D01*
G01Y1536516D02*
Y1538079D01*
G01D02*
Y1536516D01*
G01Y1545953D02*
Y1544390D01*
G01Y1542016D02*
Y1540453D01*
G01Y1549890D02*
Y1548327D01*
G01Y1553827D02*
Y1552264D01*
G01X-33153Y1552273D02*
Y1553818D01*
G01Y1548336D02*
Y1549881D01*
G01Y1544399D02*
Y1545944D01*
G01Y1540462D02*
Y1542007D01*
G01Y1536525D02*
Y1538070D01*
G01D02*
Y1536525D01*
G01Y1545944D02*
Y1544399D01*
G01Y1542007D02*
Y1540462D01*
G01Y1549881D02*
Y1548336D01*
G01Y1553818D02*
Y1552273D01*
G01X-34136Y1552284D02*
Y1553807D01*
G01Y1548347D02*
Y1549870D01*
G01Y1540473D02*
Y1541996D01*
G01Y1544410D02*
Y1545933D01*
G01Y1536536D02*
Y1538059D01*
G01D02*
Y1536536D01*
G01Y1545933D02*
Y1544410D01*
G01Y1541996D02*
Y1540473D01*
G01Y1549870D02*
Y1548347D01*
G01Y1553807D02*
Y1552284D01*
G01X-34607Y1538400D02*
Y1536195D01*
G01Y1542337D02*
Y1540132D01*
G01Y1550211D02*
Y1548006D01*
G01Y1546274D02*
Y1544069D01*
G01Y1554148D02*
Y1551943D01*
G01X-35357Y1552298D02*
Y1553793D01*
G01Y1548361D02*
Y1549856D01*
G01Y1544424D02*
Y1545919D01*
G01Y1540487D02*
Y1541982D01*
G01Y1536550D02*
Y1538045D01*
G01D02*
Y1536550D01*
G01Y1541982D02*
Y1540487D01*
G01Y1545919D02*
Y1544424D01*
G01Y1549856D02*
Y1548361D01*
G01Y1553793D02*
Y1552298D01*
G01X-35545Y1538478D02*
Y1536116D01*
G01Y1542416D02*
Y1540053D01*
G01Y1546353D02*
Y1543990D01*
G01Y1550290D02*
Y1547927D01*
G01Y1554227D02*
Y1551864D01*
G01X-35594Y1552321D02*
Y1553770D01*
G01Y1548384D02*
Y1549833D01*
G01Y1544447D02*
Y1545896D01*
G01Y1540510D02*
Y1541959D01*
G01Y1536573D02*
Y1538022D01*
G01D02*
Y1536573D01*
G01Y1545896D02*
Y1544447D01*
G01Y1541959D02*
Y1540510D01*
G01Y1549833D02*
Y1548384D01*
G01Y1553770D02*
Y1552321D01*
G01X-37870Y1552540D02*
Y1553551D01*
G01Y1548603D02*
Y1549614D01*
G01Y1540729D02*
Y1541740D01*
G01Y1544666D02*
Y1545677D01*
G01Y1536792D02*
Y1537803D01*
G01Y1532855D02*
Y1533866D01*
G01D02*
Y1532855D01*
G01Y1537803D02*
Y1536792D01*
G01Y1545677D02*
Y1544666D01*
G01Y1541740D02*
Y1540729D01*
G01Y1549614D02*
Y1548603D01*
G01Y1553551D02*
Y1552540D01*
G01X-38108Y1552563D02*
Y1553528D01*
G01Y1548626D02*
Y1549591D01*
G01Y1540752D02*
Y1541717D01*
G01Y1544689D02*
Y1545654D01*
G01Y1536815D02*
Y1537780D01*
G01Y1532878D02*
Y1533843D01*
G01D02*
Y1532878D01*
G01Y1537780D02*
Y1536815D01*
G01Y1545654D02*
Y1544689D01*
G01Y1541717D02*
Y1540752D01*
G01Y1549591D02*
Y1548626D01*
G01Y1553528D02*
Y1552563D01*
G01X-38425Y1538478D02*
Y1536116D01*
G01Y1542416D02*
Y1540053D01*
G01Y1550290D02*
Y1547927D01*
G01Y1546353D02*
Y1543990D01*
G01Y1554227D02*
Y1551864D01*
G01X-38108Y1573213D02*
X-35350Y1573478D01*
G01D02*
X-38108Y1573213D01*
G01Y1569276D02*
X-35350Y1569541D01*
G01D02*
X-38108Y1569276D01*
G01Y1565339D02*
X-35350Y1565604D01*
G01D02*
X-38108Y1565339D01*
G01X-35350Y1571982D02*
X-10630Y1571707D01*
G01D02*
X-35350Y1571982D01*
G01Y1568045D02*
X-10630Y1567770D01*
G01D02*
X-35350Y1568045D01*
G01Y1564108D02*
X-10630Y1563833D01*
G01D02*
X-35350Y1564108D01*
G01Y1560171D02*
X-10630Y1559896D01*
G01D02*
X-35350Y1560171D01*
G01Y1556234D02*
X-10630Y1555959D01*
G01D02*
X-35350Y1556234D01*
G01X-24508Y1573912D02*
X-39607D01*
G01X-35545Y1573833D02*
X0D01*
G01X-27992Y1573616D02*
X-39607D01*
G01X-35545Y1571628D02*
X0D01*
G01X-39607Y1571549D02*
X-24508D01*
G01Y1569975D02*
X-39607D01*
G01X-35545Y1569896D02*
X0D01*
G01X-35545Y1567691D02*
X0D01*
G01X-39607Y1567612D02*
X-24508D01*
G01Y1566038D02*
X-39607D01*
G01X-35545Y1565959D02*
X0D01*
G01X-35545Y1563754D02*
X0D01*
G01X-39607Y1563675D02*
X-24508D01*
G01Y1562101D02*
X-39607D01*
G01X-35545Y1562022D02*
X0D01*
G01X-39607Y1560270D02*
X-27992D01*
G01X-35545Y1559817D02*
X0D01*
G01X-39607Y1559738D02*
X-24508D01*
G01Y1558164D02*
X-39607D01*
G01X-35545Y1558085D02*
X0D01*
G01X-39607Y1557120D02*
X-24843D01*
G01X-35545Y1555880D02*
X0D01*
G01X-39607Y1555801D02*
X-24508D01*
G01Y1554227D02*
X-39607D01*
G01X-35545Y1554148D02*
X0D01*
G01X-35350Y1573478D02*
X-10630Y1573754D01*
G01X-35350Y1573478D02*
X-10630Y1573754D01*
G01X-35350Y1569541D02*
X-10630Y1569817D01*
G01X-35350Y1569541D02*
X-10630Y1569817D01*
G01X-35350Y1565604D02*
X-10630Y1565880D01*
G01X-35350Y1565604D02*
X-10630Y1565880D01*
G01X-35350Y1561667D02*
X-10630Y1561943D01*
G01X-35350Y1561667D02*
X-10630Y1561943D01*
G01X-35350Y1557730D02*
X-10630Y1558006D01*
G01X-35350Y1557730D02*
X-10630Y1558006D01*
G01X-38108Y1561402D02*
X-35350Y1561667D01*
G01D02*
X-38108Y1561402D01*
G01Y1557465D02*
X-35350Y1557730D01*
G01D02*
X-38108Y1557465D01*
G01Y1572248D02*
X-35350Y1571982D01*
G01X-38108Y1572248D02*
X-35350Y1571982D01*
G01X-38108Y1568311D02*
X-35350Y1568045D01*
G01X-38108Y1568311D02*
X-35350Y1568045D01*
G01X-38108Y1564374D02*
X-35350Y1564108D01*
G01X-38108Y1564374D02*
X-35350Y1564108D01*
G01X-38108Y1560437D02*
X-35350Y1560171D01*
G01X-38108Y1560437D02*
X-35350Y1560171D01*
G01X-38108Y1556500D02*
X-35350Y1556234D01*
G01X-38108Y1556500D02*
X-35350Y1556234D01*
G01X-24121Y1571857D02*
Y1573604D01*
G01Y1567920D02*
Y1569667D01*
G01Y1563983D02*
Y1565730D01*
G01Y1560046D02*
Y1561793D01*
G01Y1556109D02*
Y1557856D01*
G01D02*
Y1556109D01*
G01Y1561793D02*
Y1560046D01*
G01Y1565730D02*
Y1563983D01*
G01Y1573604D02*
Y1571857D01*
G01Y1569667D02*
Y1567920D01*
G01X-24508Y1558164D02*
Y1555801D01*
G01Y1562101D02*
Y1559738D01*
G01Y1566038D02*
Y1563675D01*
G01Y1569975D02*
Y1567612D01*
G01Y1573912D02*
Y1571549D01*
G01X-24843Y1557120D02*
Y1576766D01*
G01X-26565Y1571884D02*
Y1573577D01*
G01Y1567947D02*
Y1569640D01*
G01Y1564010D02*
Y1565703D01*
G01Y1560073D02*
Y1561766D01*
G01Y1556136D02*
Y1557828D01*
G01D02*
Y1556136D01*
G01Y1561766D02*
Y1560073D01*
G01Y1565703D02*
Y1564010D01*
G01Y1573577D02*
Y1571884D01*
G01Y1569640D02*
Y1567947D01*
G01X-26942Y1571889D02*
Y1573572D01*
G01Y1567952D02*
Y1569635D01*
G01Y1564015D02*
Y1565698D01*
G01Y1560078D02*
Y1561761D01*
G01Y1556141D02*
Y1557824D01*
G01D02*
Y1556141D01*
G01Y1561761D02*
Y1560078D01*
G01Y1565698D02*
Y1564015D01*
G01Y1569635D02*
Y1567952D01*
G01Y1573572D02*
Y1571889D01*
G01X-27264Y1558164D02*
Y1555801D01*
G01Y1562101D02*
Y1559738D01*
G01Y1566038D02*
Y1563675D01*
G01Y1569975D02*
Y1567612D01*
G01Y1573912D02*
Y1571549D01*
G01X-27992Y1557120D02*
Y1576766D01*
G01X-31941Y1571945D02*
Y1573517D01*
G01Y1568008D02*
Y1569580D01*
G01Y1564071D02*
Y1565643D01*
G01Y1560134D02*
Y1561706D01*
G01Y1556197D02*
Y1557769D01*
G01D02*
Y1556197D01*
G01Y1561706D02*
Y1560134D01*
G01Y1565643D02*
Y1564071D01*
G01Y1573517D02*
Y1571945D01*
G01Y1569580D02*
Y1568008D01*
G01X-32318Y1568012D02*
Y1569575D01*
G01Y1571949D02*
Y1573512D01*
G01Y1564075D02*
Y1565638D01*
G01Y1560138D02*
Y1561701D01*
G01Y1556201D02*
Y1557764D01*
G01D02*
Y1556201D01*
G01Y1561701D02*
Y1560138D01*
G01Y1565638D02*
Y1564075D01*
G01Y1573512D02*
Y1571949D01*
G01Y1569575D02*
Y1568012D01*
G01X-33153Y1571958D02*
Y1573503D01*
G01Y1568021D02*
Y1569566D01*
G01Y1564084D02*
Y1565629D01*
G01Y1560147D02*
Y1561692D01*
G01Y1556210D02*
Y1557755D01*
G01D02*
Y1556210D01*
G01Y1561692D02*
Y1560147D01*
G01Y1565629D02*
Y1564084D01*
G01Y1573503D02*
Y1571958D01*
G01Y1569566D02*
Y1568021D01*
G01X-34136Y1568032D02*
Y1569555D01*
G01Y1571969D02*
Y1573492D01*
G01Y1564095D02*
Y1565618D01*
G01Y1560158D02*
Y1561681D01*
G01Y1556221D02*
Y1557744D01*
G01D02*
Y1556221D01*
G01Y1561681D02*
Y1560158D01*
G01Y1565618D02*
Y1564095D01*
G01Y1573492D02*
Y1571969D01*
G01Y1569555D02*
Y1568032D01*
G01X-34607Y1558085D02*
Y1555880D01*
G01Y1562022D02*
Y1559817D01*
G01Y1565959D02*
Y1563754D01*
G01Y1573833D02*
Y1571628D01*
G01Y1569896D02*
Y1567691D01*
G01X-35357Y1571983D02*
Y1573478D01*
G01Y1568046D02*
Y1569541D01*
G01Y1564109D02*
Y1565604D01*
G01Y1560172D02*
Y1561667D01*
G01Y1556235D02*
Y1557730D01*
G01D02*
Y1556235D01*
G01Y1561667D02*
Y1560172D01*
G01Y1565604D02*
Y1564109D01*
G01Y1569541D02*
Y1568046D01*
G01Y1573478D02*
Y1571983D01*
G01X-35545Y1558164D02*
Y1555801D01*
G01Y1562101D02*
Y1559738D01*
G01Y1566038D02*
Y1563675D01*
G01Y1569975D02*
Y1567612D01*
G01Y1573912D02*
Y1571549D01*
G01X-35594Y1572006D02*
Y1573455D01*
G01Y1568069D02*
Y1569518D01*
G01Y1564132D02*
Y1565581D01*
G01Y1560195D02*
Y1561644D01*
G01Y1556258D02*
Y1557707D01*
G01D02*
Y1556258D01*
G01Y1561644D02*
Y1560195D01*
G01Y1565581D02*
Y1564132D01*
G01Y1569518D02*
Y1568069D01*
G01Y1573455D02*
Y1572006D01*
G01X-37870Y1572225D02*
Y1573236D01*
G01Y1564351D02*
Y1565362D01*
G01Y1568288D02*
Y1569299D01*
G01Y1560414D02*
Y1561425D01*
G01Y1556477D02*
Y1557488D01*
G01D02*
Y1556477D01*
G01Y1561425D02*
Y1560414D01*
G01Y1569299D02*
Y1568288D01*
G01Y1565362D02*
Y1564351D01*
G01Y1573236D02*
Y1572225D01*
G01X-38108Y1572248D02*
Y1573213D01*
G01Y1564374D02*
Y1565339D01*
G01Y1568311D02*
Y1569276D01*
G01Y1560437D02*
Y1561402D01*
G01Y1556500D02*
Y1557465D01*
G01D02*
Y1556500D01*
G01Y1561402D02*
Y1560437D01*
G01Y1565339D02*
Y1564374D01*
G01Y1569276D02*
Y1568311D01*
G01Y1573213D02*
Y1572248D01*
G01X-38425Y1558164D02*
Y1555801D01*
G01Y1562101D02*
Y1559738D01*
G01Y1566038D02*
Y1563675D01*
G01Y1573912D02*
Y1571549D01*
G01Y1569975D02*
Y1567612D01*
G01X-38108Y1592898D02*
X-35350Y1593164D01*
G01D02*
X-38108Y1592898D01*
G01Y1588961D02*
X-35350Y1589227D01*
G01D02*
X-38108Y1588961D01*
G01Y1585024D02*
X-35350Y1585290D01*
G01D02*
X-38108Y1585024D01*
G01Y1581087D02*
X-35350Y1581353D01*
G01D02*
X-38108Y1581087D01*
G01Y1577150D02*
X-35350Y1577416D01*
G01D02*
X-38108Y1577150D01*
G01Y1595870D02*
X-35350Y1595604D01*
G01X-38108Y1595870D02*
X-35350Y1595604D01*
G01D02*
X-10630Y1595329D01*
G01D02*
X-35350Y1595604D01*
G01Y1591667D02*
X-10630Y1591392D01*
G01D02*
X-35350Y1591667D01*
G01Y1587730D02*
X-10630Y1587455D01*
G01D02*
X-35350Y1587730D01*
G01Y1583793D02*
X-10630Y1583518D01*
G01D02*
X-35350Y1583793D01*
G01Y1579856D02*
X-10630Y1579581D01*
G01D02*
X-35350Y1579856D01*
G01Y1575919D02*
X-10630Y1575644D01*
G01D02*
X-35350Y1575919D01*
G01X-35545Y1595250D02*
X0D01*
G01X-39607Y1595171D02*
X-24508D01*
G01Y1593597D02*
X-39607D01*
G01X-35545Y1593518D02*
X0D01*
G01X-35545Y1591313D02*
X0D01*
G01X-39607Y1591234D02*
X-24508D01*
G01Y1589660D02*
X-39607D01*
G01X-35545Y1589581D02*
X0D01*
G01X-35545Y1587376D02*
X0D01*
G01X-39607Y1587297D02*
X-24508D01*
G01Y1585723D02*
X-39607D01*
G01X-35545Y1585644D02*
X0D01*
G01X-39607Y1583892D02*
X-27992D01*
G01X-35545Y1583439D02*
X0D01*
G01X-39607Y1583360D02*
X-24508D01*
G01Y1581786D02*
X-39607D01*
G01X-35545Y1581707D02*
X0D01*
G01X-39607Y1580742D02*
X-24843D01*
G01X-35545Y1579502D02*
X0D01*
G01X-39607Y1579423D02*
X-24508D01*
G01Y1577849D02*
X-39607D01*
G01X-35545Y1577770D02*
X0D01*
G01X-39607Y1576766D02*
X-24843D01*
G01X-35545Y1575565D02*
X0D01*
G01X-39607Y1575486D02*
X-24508D01*
G01X-35350Y1593164D02*
X-10630Y1593439D01*
G01X-35350Y1593164D02*
X-10630Y1593439D01*
G01X-35350Y1589227D02*
X-10630Y1589502D01*
G01X-35350Y1589227D02*
X-10630Y1589502D01*
G01X-35350Y1585290D02*
X-10630Y1585565D01*
G01X-35350Y1585290D02*
X-10630Y1585565D01*
G01X-35350Y1581353D02*
X-10630Y1581628D01*
G01X-35350Y1581353D02*
X-10630Y1581628D01*
G01X-35350Y1577416D02*
X-10630Y1577691D01*
G01X-35350Y1577416D02*
X-10630Y1577691D01*
G01X-38108Y1591933D02*
X-35350Y1591667D01*
G01X-38108Y1591933D02*
X-35350Y1591667D01*
G01X-38108Y1587996D02*
X-35350Y1587730D01*
G01X-38108Y1587996D02*
X-35350Y1587730D01*
G01X-38108Y1584059D02*
X-35350Y1583793D01*
G01X-38108Y1584059D02*
X-35350Y1583793D01*
G01X-38108Y1580122D02*
X-35350Y1579856D01*
G01X-38108Y1580122D02*
X-35350Y1579856D01*
G01X-38108Y1576185D02*
X-35350Y1575919D01*
G01X-38108Y1576185D02*
X-35350Y1575919D01*
G01X-24121Y1595479D02*
Y1597226D01*
G01Y1591542D02*
Y1593289D01*
G01Y1587605D02*
Y1589352D01*
G01Y1583668D02*
Y1585415D01*
G01Y1579731D02*
Y1581478D01*
G01Y1575794D02*
Y1577541D01*
G01D02*
Y1575794D01*
G01Y1581478D02*
Y1579731D01*
G01Y1585415D02*
Y1583668D01*
G01Y1589352D02*
Y1587605D01*
G01Y1597226D02*
Y1595479D01*
G01Y1593289D02*
Y1591542D01*
G01X-24508Y1577849D02*
Y1575486D01*
G01Y1581786D02*
Y1579423D01*
G01Y1585723D02*
Y1583360D01*
G01Y1589660D02*
Y1587297D01*
G01Y1593597D02*
Y1591234D01*
G01Y1597534D02*
Y1595171D01*
G01X-24843Y1580742D02*
Y1600388D01*
G01X-26565Y1595506D02*
Y1597199D01*
G01Y1591569D02*
Y1593262D01*
G01Y1587632D02*
Y1589325D01*
G01Y1583695D02*
Y1585388D01*
G01Y1579758D02*
Y1581451D01*
G01Y1575821D02*
Y1577514D01*
G01D02*
Y1575821D01*
G01Y1581451D02*
Y1579758D01*
G01Y1585388D02*
Y1583695D01*
G01Y1589325D02*
Y1587632D01*
G01Y1597199D02*
Y1595506D01*
G01Y1593262D02*
Y1591569D01*
G01X-26942Y1595511D02*
Y1597194D01*
G01Y1591574D02*
Y1593257D01*
G01Y1587637D02*
Y1589320D01*
G01Y1583700D02*
Y1585383D01*
G01Y1579763D02*
Y1581446D01*
G01Y1575826D02*
Y1577509D01*
G01D02*
Y1575826D01*
G01Y1581446D02*
Y1579763D01*
G01Y1585383D02*
Y1583700D01*
G01Y1589320D02*
Y1587637D01*
G01Y1597194D02*
Y1595511D01*
G01Y1593257D02*
Y1591574D01*
G01X-27264Y1577849D02*
Y1575486D01*
G01Y1581786D02*
Y1579423D01*
G01Y1585723D02*
Y1583360D01*
G01Y1589660D02*
Y1587297D01*
G01Y1593597D02*
Y1591234D01*
G01Y1597534D02*
Y1595171D01*
G01X-27992Y1580742D02*
Y1600388D01*
G01X-31941Y1595567D02*
Y1597139D01*
G01Y1591630D02*
Y1593202D01*
G01Y1587693D02*
Y1589265D01*
G01Y1583756D02*
Y1585328D01*
G01Y1579819D02*
Y1581391D01*
G01Y1575882D02*
Y1577454D01*
G01D02*
Y1575882D01*
G01Y1581391D02*
Y1579819D01*
G01Y1585328D02*
Y1583756D01*
G01Y1589265D02*
Y1587693D01*
G01Y1597139D02*
Y1595567D01*
G01Y1593202D02*
Y1591630D01*
G01X-32318Y1595571D02*
Y1597134D01*
G01Y1591634D02*
Y1593197D01*
G01Y1587697D02*
Y1589260D01*
G01Y1583760D02*
Y1585323D01*
G01Y1579823D02*
Y1581386D01*
G01Y1575886D02*
Y1577449D01*
G01D02*
Y1575886D01*
G01Y1581386D02*
Y1579823D01*
G01Y1585323D02*
Y1583760D01*
G01Y1589260D02*
Y1587697D01*
G01Y1597134D02*
Y1595571D01*
G01Y1593197D02*
Y1591634D01*
G01X-33153Y1595580D02*
Y1597125D01*
G01Y1591643D02*
Y1593188D01*
G01Y1587706D02*
Y1589251D01*
G01Y1583769D02*
Y1585314D01*
G01Y1579832D02*
Y1581377D01*
G01Y1575895D02*
Y1577440D01*
G01D02*
Y1575895D01*
G01Y1581377D02*
Y1579832D01*
G01Y1585314D02*
Y1583769D01*
G01Y1589251D02*
Y1587706D01*
G01Y1597125D02*
Y1595580D01*
G01Y1593188D02*
Y1591643D01*
G01X-34136Y1595591D02*
Y1597114D01*
G01Y1591654D02*
Y1593177D01*
G01Y1587717D02*
Y1589240D01*
G01Y1583780D02*
Y1585303D01*
G01Y1579843D02*
Y1581366D01*
G01Y1575906D02*
Y1577429D01*
G01D02*
Y1575906D01*
G01Y1581366D02*
Y1579843D01*
G01Y1585303D02*
Y1583780D01*
G01Y1589240D02*
Y1587717D01*
G01Y1597114D02*
Y1595591D01*
G01Y1593177D02*
Y1591654D01*
G01X-34607Y1577770D02*
Y1575565D01*
G01Y1581707D02*
Y1579502D01*
G01Y1585644D02*
Y1583439D01*
G01Y1589581D02*
Y1587376D01*
G01Y1597455D02*
Y1595250D01*
G01Y1593518D02*
Y1591313D01*
G01X-35357Y1595605D02*
Y1597100D01*
G01Y1591668D02*
Y1593163D01*
G01Y1587731D02*
Y1589226D01*
G01Y1583794D02*
Y1585289D01*
G01Y1579857D02*
Y1581352D01*
G01Y1575920D02*
Y1577415D01*
G01D02*
Y1575920D01*
G01Y1581352D02*
Y1579857D01*
G01Y1585289D02*
Y1583794D01*
G01Y1589226D02*
Y1587731D01*
G01Y1597100D02*
Y1595605D01*
G01Y1593163D02*
Y1591668D01*
G01X-35545Y1577849D02*
Y1575486D01*
G01Y1581786D02*
Y1579423D01*
G01Y1585723D02*
Y1583360D01*
G01Y1589660D02*
Y1587297D01*
G01Y1593597D02*
Y1591234D01*
G01Y1597534D02*
Y1595171D01*
G01X-35594Y1595628D02*
Y1597077D01*
G01Y1591691D02*
Y1593140D01*
G01Y1587754D02*
Y1589203D01*
G01Y1583817D02*
Y1585266D01*
G01Y1579880D02*
Y1581329D01*
G01Y1575943D02*
Y1577392D01*
G01D02*
Y1575943D01*
G01Y1581329D02*
Y1579880D01*
G01Y1585266D02*
Y1583817D01*
G01Y1589203D02*
Y1587754D01*
G01Y1597077D02*
Y1595628D01*
G01Y1593140D02*
Y1591691D01*
G01X-37870Y1595847D02*
Y1596858D01*
G01Y1587973D02*
Y1588984D01*
G01Y1591910D02*
Y1592921D01*
G01Y1584036D02*
Y1585047D01*
G01Y1580099D02*
Y1581110D01*
G01Y1576162D02*
Y1577173D01*
G01D02*
Y1576162D01*
G01Y1581110D02*
Y1580099D01*
G01Y1585047D02*
Y1584036D01*
G01Y1592921D02*
Y1591910D01*
G01Y1588984D02*
Y1587973D01*
G01Y1596858D02*
Y1595847D01*
G01X-38108Y1595870D02*
Y1596835D01*
G01Y1587996D02*
Y1588961D01*
G01Y1591933D02*
Y1592898D01*
G01Y1584059D02*
Y1585024D01*
G01Y1580122D02*
Y1581087D01*
G01Y1576185D02*
Y1577150D01*
G01D02*
Y1576185D01*
G01Y1581087D02*
Y1580122D01*
G01Y1585024D02*
Y1584059D01*
G01Y1592898D02*
Y1591933D01*
G01Y1588961D02*
Y1587996D01*
G01Y1596835D02*
Y1595870D01*
G01X-38425Y1577849D02*
Y1575486D01*
G01Y1581786D02*
Y1579423D01*
G01Y1585723D02*
Y1583360D01*
G01Y1589660D02*
Y1587297D01*
G01Y1597534D02*
Y1595171D01*
G01Y1593597D02*
Y1591234D01*
G01X-24508Y1617219D02*
X-39607D01*
G01X-35545Y1617140D02*
X0D01*
G01X-35350Y1616786D02*
X-10630Y1617061D01*
G01X-35350Y1616786D02*
X-10630Y1617061D01*
G01X-35350Y1612849D02*
X-10630Y1613124D01*
G01X-35350Y1612849D02*
X-10630Y1613124D01*
G01X-38108Y1616520D02*
X-35350Y1616786D01*
G01D02*
X-38108Y1616520D01*
G01Y1612583D02*
X-35350Y1612849D01*
G01D02*
X-38108Y1612583D01*
G01Y1608646D02*
X-35350Y1608912D01*
G01D02*
X-38108Y1608646D01*
G01Y1604709D02*
X-35350Y1604975D01*
G01D02*
X-38108Y1604709D01*
G01Y1600772D02*
X-35350Y1601038D01*
G01D02*
X-38108Y1600772D01*
G01Y1596835D02*
X-35350Y1597101D01*
G01D02*
X-38108Y1596835D01*
G01Y1615555D02*
X-35350Y1615290D01*
G01X-38108Y1615555D02*
X-35350Y1615290D01*
G01X-38108Y1611618D02*
X-35350Y1611353D01*
G01X-38108Y1611618D02*
X-35350Y1611353D01*
G01X-38108Y1607681D02*
X-35350Y1607416D01*
G01X-38108Y1607681D02*
X-35350Y1607416D01*
G01X-38108Y1603744D02*
X-35350Y1603478D01*
G01X-38108Y1603744D02*
X-35350Y1603478D01*
G01X-38108Y1599807D02*
X-35350Y1599541D01*
G01X-38108Y1599807D02*
X-35350Y1599541D01*
G01Y1615290D02*
X-10630Y1615014D01*
G01D02*
X-35350Y1615290D01*
G01Y1611353D02*
X-10630Y1611077D01*
G01D02*
X-35350Y1611353D01*
G01Y1607416D02*
X-10630Y1607140D01*
G01D02*
X-35350Y1607416D01*
G01Y1603478D02*
X-10630Y1603203D01*
G01D02*
X-35350Y1603478D01*
G01Y1599541D02*
X-10630Y1599266D01*
G01D02*
X-35350Y1599541D01*
G01X-35545Y1614935D02*
X0D01*
G01X-39607Y1614856D02*
X-24508D01*
G01Y1613282D02*
X-39607D01*
G01X-35545Y1613203D02*
X0D01*
G01X-35545Y1610998D02*
X0D01*
G01X-39607Y1610919D02*
X-24508D01*
G01Y1609345D02*
X-39607D01*
G01X-35545Y1609266D02*
X0D01*
G01X-39607Y1607514D02*
X-27992D01*
G01X-35545Y1607061D02*
X0D01*
G01X-39607Y1606982D02*
X-24508D01*
G01Y1605408D02*
X-39607D01*
G01X-35545Y1605329D02*
X0D01*
G01X-39607Y1604364D02*
X-24843D01*
G01X-35545Y1603124D02*
X0D01*
G01X-39607Y1603045D02*
X-24508D01*
G01Y1601471D02*
X-39607D01*
G01X-35545Y1601392D02*
X0D01*
G01X-39607Y1600388D02*
X-24843D01*
G01X-35545Y1599187D02*
X0D01*
G01X-39607Y1599108D02*
X-24508D01*
G01Y1597534D02*
X-39607D01*
G01X-35545Y1597455D02*
X0D01*
G01X-27992Y1597238D02*
X-39607D01*
G01X-35350Y1608912D02*
X-10630Y1609187D01*
G01X-35350Y1608912D02*
X-10630Y1609187D01*
G01X-35350Y1604975D02*
X-10630Y1605250D01*
G01X-35350Y1604975D02*
X-10630Y1605250D01*
G01X-35350Y1601038D02*
X-10630Y1601313D01*
G01X-35350Y1601038D02*
X-10630Y1601313D01*
G01X-35350Y1597101D02*
X-10630Y1597376D01*
G01X-35350Y1597101D02*
X-10630Y1597376D01*
G01X-24121Y1615164D02*
Y1616911D01*
G01Y1611227D02*
Y1612974D01*
G01Y1607290D02*
Y1609037D01*
G01Y1603353D02*
Y1605100D01*
G01Y1599416D02*
Y1601163D01*
G01D02*
Y1599416D01*
G01Y1605100D02*
Y1603353D01*
G01Y1609037D02*
Y1607290D01*
G01Y1612974D02*
Y1611227D01*
G01Y1616911D02*
Y1615164D01*
G01X-24508Y1601471D02*
Y1599108D01*
G01Y1605408D02*
Y1603045D01*
G01Y1609345D02*
Y1606982D01*
G01Y1613282D02*
Y1610919D01*
G01Y1617219D02*
Y1614856D01*
G01X-24843Y1604364D02*
Y1624010D01*
G01X-26565Y1615191D02*
Y1616884D01*
G01Y1611254D02*
Y1612947D01*
G01Y1607317D02*
Y1609010D01*
G01Y1603380D02*
Y1605073D01*
G01Y1599443D02*
Y1601136D01*
G01D02*
Y1599443D01*
G01Y1605073D02*
Y1603380D01*
G01Y1609010D02*
Y1607317D01*
G01Y1612947D02*
Y1611254D01*
G01Y1616884D02*
Y1615191D01*
G01X-26942Y1615196D02*
Y1616879D01*
G01Y1611259D02*
Y1612942D01*
G01Y1607322D02*
Y1609005D01*
G01Y1603385D02*
Y1605068D01*
G01Y1599448D02*
Y1601131D01*
G01D02*
Y1599448D01*
G01Y1605068D02*
Y1603385D01*
G01Y1609005D02*
Y1607322D01*
G01Y1612942D02*
Y1611259D01*
G01Y1616879D02*
Y1615196D01*
G01X-27264Y1601471D02*
Y1599108D01*
G01Y1605408D02*
Y1603045D01*
G01Y1609345D02*
Y1606982D01*
G01Y1613282D02*
Y1610919D01*
G01Y1617219D02*
Y1614856D01*
G01X-27992Y1604364D02*
Y1624010D01*
G01X-31941Y1615252D02*
Y1616824D01*
G01Y1611315D02*
Y1612887D01*
G01Y1607378D02*
Y1608950D01*
G01Y1603441D02*
Y1605013D01*
G01Y1599504D02*
Y1601076D01*
G01D02*
Y1599504D01*
G01Y1605013D02*
Y1603441D01*
G01Y1608950D02*
Y1607378D01*
G01Y1612887D02*
Y1611315D01*
G01Y1616824D02*
Y1615252D01*
G01X-32318Y1615256D02*
Y1616819D01*
G01Y1611319D02*
Y1612882D01*
G01Y1607382D02*
Y1608945D01*
G01Y1603445D02*
Y1605008D01*
G01Y1599508D02*
Y1601071D01*
G01D02*
Y1599508D01*
G01Y1605008D02*
Y1603445D01*
G01Y1608945D02*
Y1607382D01*
G01Y1612882D02*
Y1611319D01*
G01Y1616819D02*
Y1615256D01*
G01X-33153Y1615265D02*
Y1616810D01*
G01Y1611328D02*
Y1612873D01*
G01Y1607391D02*
Y1608936D01*
G01Y1603454D02*
Y1604999D01*
G01Y1599517D02*
Y1601062D01*
G01D02*
Y1599517D01*
G01Y1604999D02*
Y1603454D01*
G01Y1608936D02*
Y1607391D01*
G01Y1612873D02*
Y1611328D01*
G01Y1616810D02*
Y1615265D01*
G01X-34136Y1615276D02*
Y1616799D01*
G01Y1611339D02*
Y1612862D01*
G01Y1607402D02*
Y1608925D01*
G01Y1603465D02*
Y1604988D01*
G01Y1599528D02*
Y1601051D01*
G01D02*
Y1599528D01*
G01Y1604988D02*
Y1603465D01*
G01Y1608925D02*
Y1607402D01*
G01Y1612862D02*
Y1611339D01*
G01Y1616799D02*
Y1615276D01*
G01X-34607Y1601392D02*
Y1599187D01*
G01Y1605329D02*
Y1603124D01*
G01Y1609266D02*
Y1607061D01*
G01Y1613203D02*
Y1610998D01*
G01Y1617140D02*
Y1614935D01*
G01X-35357Y1615290D02*
Y1616785D01*
G01Y1611353D02*
Y1612848D01*
G01Y1607416D02*
Y1608911D01*
G01Y1603479D02*
Y1604974D01*
G01Y1599542D02*
Y1601037D01*
G01D02*
Y1599542D01*
G01Y1604974D02*
Y1603479D01*
G01Y1608911D02*
Y1607416D01*
G01Y1612848D02*
Y1611353D01*
G01Y1616785D02*
Y1615290D01*
G01X-35545Y1601471D02*
Y1599108D01*
G01Y1605408D02*
Y1603045D01*
G01Y1609345D02*
Y1606982D01*
G01Y1613282D02*
Y1610919D01*
G01Y1617219D02*
Y1614856D01*
G01X-35594Y1615313D02*
Y1616762D01*
G01Y1611376D02*
Y1612825D01*
G01Y1607439D02*
Y1608888D01*
G01Y1603502D02*
Y1604951D01*
G01Y1599565D02*
Y1601014D01*
G01D02*
Y1599565D01*
G01Y1604951D02*
Y1603502D01*
G01Y1608888D02*
Y1607439D01*
G01Y1612825D02*
Y1611376D01*
G01Y1616762D02*
Y1615313D01*
G01X-37870Y1615532D02*
Y1616543D01*
G01Y1611595D02*
Y1612606D01*
G01Y1607658D02*
Y1608669D01*
G01Y1603721D02*
Y1604732D01*
G01Y1599784D02*
Y1600795D01*
G01D02*
Y1599784D01*
G01Y1604732D02*
Y1603721D01*
G01Y1608669D02*
Y1607658D01*
G01Y1612606D02*
Y1611595D01*
G01Y1616543D02*
Y1615532D01*
G01X-38108Y1615555D02*
Y1616520D01*
G01Y1611618D02*
Y1612583D01*
G01Y1607681D02*
Y1608646D01*
G01Y1603744D02*
Y1604709D01*
G01Y1599807D02*
Y1600772D01*
G01D02*
Y1599807D01*
G01Y1604709D02*
Y1603744D01*
G01Y1608646D02*
Y1607681D01*
G01Y1612583D02*
Y1611618D01*
G01Y1616520D02*
Y1615555D01*
G01X-38425Y1601471D02*
Y1599108D01*
G01Y1605408D02*
Y1603045D01*
G01Y1609345D02*
Y1606982D01*
G01Y1613282D02*
Y1610919D01*
G01Y1617219D02*
Y1614856D01*
G01X-35350Y1634975D02*
X-10630Y1634699D01*
G01D02*
X-35350Y1634975D01*
G01Y1631038D02*
X-10630Y1630762D01*
G01D02*
X-35350Y1631038D01*
G01Y1627101D02*
X-10630Y1626825D01*
G01D02*
X-35350Y1627101D01*
G01Y1623164D02*
X-10630Y1622888D01*
G01D02*
X-35350Y1623164D01*
G01X-24508Y1636904D02*
X-39607D01*
G01X-35545Y1636825D02*
X0D01*
G01X-35545Y1634620D02*
X0D01*
G01X-39607Y1634541D02*
X-24508D01*
G01Y1632967D02*
X-39607D01*
G01X-35545Y1632888D02*
X0D01*
G01X-39607Y1631136D02*
X-27992D01*
G01X-35545Y1630683D02*
X0D01*
G01X-39607Y1630604D02*
X-24508D01*
G01Y1629030D02*
X-39607D01*
G01X-35545Y1628951D02*
X0D01*
G01X-39607Y1627986D02*
X-24843D01*
G01X-35545Y1626746D02*
X0D01*
G01X-39607Y1626667D02*
X-24508D01*
G01Y1625093D02*
X-39607D01*
G01X-35545Y1625014D02*
X0D01*
G01X-39607Y1624010D02*
X-24843D01*
G01X-35545Y1622809D02*
X0D01*
G01X-39607Y1622730D02*
X-24508D01*
G01Y1621156D02*
X-39607D01*
G01X-35545Y1621077D02*
X0D01*
G01X-27992Y1620860D02*
X-39607D01*
G01X-35545Y1618872D02*
X0D01*
G01X-39607Y1618793D02*
X-24508D01*
G01X-35350Y1636471D02*
X-10630Y1636746D01*
G01X-35350Y1636471D02*
X-10630Y1636746D01*
G01X-35350Y1632534D02*
X-10630Y1632809D01*
G01X-35350Y1632534D02*
X-10630Y1632809D01*
G01X-35350Y1628597D02*
X-10630Y1628872D01*
G01X-35350Y1628597D02*
X-10630Y1628872D01*
G01X-35350Y1624660D02*
X-10630Y1624935D01*
G01X-35350Y1624660D02*
X-10630Y1624935D01*
G01X-35350Y1620723D02*
X-10630Y1620998D01*
G01X-35350Y1620723D02*
X-10630Y1620998D01*
G01X-38108Y1636205D02*
X-35350Y1636471D01*
G01D02*
X-38108Y1636205D01*
G01Y1632268D02*
X-35350Y1632534D01*
G01D02*
X-38108Y1632268D01*
G01Y1628331D02*
X-35350Y1628597D01*
G01D02*
X-38108Y1628331D01*
G01Y1624394D02*
X-35350Y1624660D01*
G01D02*
X-38108Y1624394D01*
G01Y1620457D02*
X-35350Y1620723D01*
G01D02*
X-38108Y1620457D01*
G01Y1635240D02*
X-35350Y1634975D01*
G01X-38108Y1635240D02*
X-35350Y1634975D01*
G01X-38108Y1631303D02*
X-35350Y1631038D01*
G01X-38108Y1631303D02*
X-35350Y1631038D01*
G01X-38108Y1627366D02*
X-35350Y1627101D01*
G01X-38108Y1627366D02*
X-35350Y1627101D01*
G01X-38108Y1623429D02*
X-35350Y1623164D01*
G01X-38108Y1623429D02*
X-35350Y1623164D01*
G01X-38108Y1619492D02*
X-35350Y1619227D01*
G01X-38108Y1619492D02*
X-35350Y1619227D01*
G01D02*
X-10630Y1618951D01*
G01D02*
X-35350Y1619227D01*
G01X-24121Y1634849D02*
Y1636596D01*
G01Y1630912D02*
Y1632659D01*
G01Y1626975D02*
Y1628722D01*
G01Y1623038D02*
Y1624785D01*
G01Y1619101D02*
Y1620848D01*
G01D02*
Y1619101D01*
G01Y1624785D02*
Y1623038D01*
G01Y1628722D02*
Y1626975D01*
G01Y1632659D02*
Y1630912D01*
G01Y1636596D02*
Y1634849D01*
G01X-24508Y1621156D02*
Y1618793D01*
G01Y1625093D02*
Y1622730D01*
G01Y1629030D02*
Y1626667D01*
G01Y1632967D02*
Y1630604D01*
G01Y1636904D02*
Y1634541D01*
G01X-24843Y1627986D02*
Y1647632D01*
G01X-26565Y1634877D02*
Y1636569D01*
G01Y1630940D02*
Y1632632D01*
G01Y1627003D02*
Y1628695D01*
G01Y1623066D02*
Y1624758D01*
G01Y1619128D02*
Y1620821D01*
G01D02*
Y1619128D01*
G01Y1624758D02*
Y1623066D01*
G01Y1628695D02*
Y1627003D01*
G01Y1632632D02*
Y1630940D01*
G01Y1636569D02*
Y1634877D01*
G01X-26942Y1634881D02*
Y1636564D01*
G01Y1630944D02*
Y1632627D01*
G01Y1627007D02*
Y1628690D01*
G01Y1623070D02*
Y1624753D01*
G01Y1619133D02*
Y1620816D01*
G01D02*
Y1619133D01*
G01Y1624753D02*
Y1623070D01*
G01Y1628690D02*
Y1627007D01*
G01Y1632627D02*
Y1630944D01*
G01Y1636564D02*
Y1634881D01*
G01X-27264Y1621156D02*
Y1618793D01*
G01Y1625093D02*
Y1622730D01*
G01Y1629030D02*
Y1626667D01*
G01Y1632967D02*
Y1630604D01*
G01Y1636904D02*
Y1634541D01*
G01X-27992Y1627986D02*
Y1647632D01*
G01X-31941Y1634937D02*
Y1636509D01*
G01Y1631000D02*
Y1632572D01*
G01Y1627063D02*
Y1628635D01*
G01Y1623126D02*
Y1624698D01*
G01Y1619189D02*
Y1620761D01*
G01D02*
Y1619189D01*
G01Y1624698D02*
Y1623126D01*
G01Y1628635D02*
Y1627063D01*
G01Y1632572D02*
Y1631000D01*
G01Y1636509D02*
Y1634937D01*
G01X-32318Y1634941D02*
Y1636504D01*
G01Y1631004D02*
Y1632567D01*
G01Y1627067D02*
Y1628630D01*
G01Y1623130D02*
Y1624693D01*
G01Y1619193D02*
Y1620756D01*
G01D02*
Y1619193D01*
G01Y1624693D02*
Y1623130D01*
G01Y1628630D02*
Y1627067D01*
G01Y1632567D02*
Y1631004D01*
G01Y1636504D02*
Y1634941D01*
G01X-33153Y1634950D02*
Y1636495D01*
G01Y1631013D02*
Y1632558D01*
G01Y1627076D02*
Y1628621D01*
G01Y1623139D02*
Y1624684D01*
G01Y1619202D02*
Y1620747D01*
G01D02*
Y1619202D01*
G01Y1624684D02*
Y1623139D01*
G01Y1628621D02*
Y1627076D01*
G01Y1632558D02*
Y1631013D01*
G01Y1636495D02*
Y1634950D01*
G01X-34136Y1634961D02*
Y1636484D01*
G01Y1631024D02*
Y1632547D01*
G01Y1627087D02*
Y1628610D01*
G01Y1623150D02*
Y1624673D01*
G01Y1619213D02*
Y1620736D01*
G01D02*
Y1619213D01*
G01Y1624673D02*
Y1623150D01*
G01Y1628610D02*
Y1627087D01*
G01Y1632547D02*
Y1631024D01*
G01Y1636484D02*
Y1634961D01*
G01X-34607Y1621077D02*
Y1618872D01*
G01Y1625014D02*
Y1622809D01*
G01Y1628951D02*
Y1626746D01*
G01Y1632888D02*
Y1630683D01*
G01Y1636825D02*
Y1634620D01*
G01X-35357Y1634975D02*
Y1636470D01*
G01Y1631038D02*
Y1632533D01*
G01Y1627101D02*
Y1628596D01*
G01Y1623164D02*
Y1624659D01*
G01Y1619227D02*
Y1620722D01*
G01D02*
Y1619227D01*
G01Y1624659D02*
Y1623164D01*
G01Y1628596D02*
Y1627101D01*
G01Y1632533D02*
Y1631038D01*
G01Y1636470D02*
Y1634975D01*
G01X-35545Y1621156D02*
Y1618793D01*
G01Y1625093D02*
Y1622730D01*
G01Y1629030D02*
Y1626667D01*
G01Y1632967D02*
Y1630604D01*
G01Y1636904D02*
Y1634541D01*
G01X-35594Y1634998D02*
Y1636447D01*
G01Y1631061D02*
Y1632510D01*
G01Y1627124D02*
Y1628573D01*
G01Y1623187D02*
Y1624636D01*
G01Y1619250D02*
Y1620699D01*
G01D02*
Y1619250D01*
G01Y1624636D02*
Y1623187D01*
G01Y1628573D02*
Y1627124D01*
G01Y1632510D02*
Y1631061D01*
G01Y1636447D02*
Y1634998D01*
G01X-37870Y1635217D02*
Y1636228D01*
G01Y1631280D02*
Y1632291D01*
G01Y1627343D02*
Y1628354D01*
G01Y1623406D02*
Y1624417D01*
G01Y1619469D02*
Y1620480D01*
G01D02*
Y1619469D01*
G01Y1624417D02*
Y1623406D01*
G01Y1628354D02*
Y1627343D01*
G01Y1632291D02*
Y1631280D01*
G01Y1636228D02*
Y1635217D01*
G01X-38108Y1635240D02*
Y1636205D01*
G01Y1631303D02*
Y1632268D01*
G01Y1627366D02*
Y1628331D01*
G01Y1623429D02*
Y1624394D01*
G01Y1619492D02*
Y1620457D01*
G01D02*
Y1619492D01*
G01Y1624394D02*
Y1623429D01*
G01Y1628331D02*
Y1627366D01*
G01Y1632268D02*
Y1631303D01*
G01Y1636205D02*
Y1635240D01*
G01X-38425Y1621156D02*
Y1618793D01*
G01Y1625093D02*
Y1622730D01*
G01Y1629030D02*
Y1626667D01*
G01Y1632967D02*
Y1630604D01*
G01Y1636904D02*
Y1634541D01*
G01X-38108Y1655890D02*
X-35350Y1656156D01*
G01D02*
X-38108Y1655890D01*
G01Y1651953D02*
X-35350Y1652219D01*
G01D02*
X-38108Y1651953D01*
G01Y1648016D02*
X-35350Y1648282D01*
G01D02*
X-38108Y1648016D01*
G01Y1644079D02*
X-35350Y1644345D01*
G01D02*
X-38108Y1644079D01*
G01X-35350Y1658597D02*
X-10630Y1658321D01*
G01D02*
X-35350Y1658597D01*
G01Y1654660D02*
X-10630Y1654384D01*
G01D02*
X-35350Y1654660D01*
G01Y1650723D02*
X-10630Y1650447D01*
G01D02*
X-35350Y1650723D01*
G01Y1646786D02*
X-10630Y1646510D01*
G01D02*
X-35350Y1646786D01*
G01Y1642849D02*
X-10630Y1642573D01*
G01D02*
X-35350Y1642849D01*
G01Y1638912D02*
X-10630Y1638636D01*
G01D02*
X-35350Y1638912D01*
G01X-35545Y1658242D02*
X0D01*
G01X-39607Y1658164D02*
X-24508D01*
G01Y1656589D02*
X-39607D01*
G01X-35545Y1656510D02*
X0D01*
G01X-39607Y1654758D02*
X-27992D01*
G01X-35545Y1654305D02*
X0D01*
G01X-39607Y1654227D02*
X-24508D01*
G01Y1652652D02*
X-39607D01*
G01X-35545Y1652573D02*
X0D01*
G01X-39607Y1651608D02*
X-24843D01*
G01X-35545Y1650368D02*
X0D01*
G01X-39607Y1650290D02*
X-24508D01*
G01Y1648715D02*
X-39607D01*
G01X-35545Y1648636D02*
X0D01*
G01X-39607Y1647632D02*
X-24843D01*
G01X-35545Y1646431D02*
X0D01*
G01X-39607Y1646353D02*
X-24508D01*
G01Y1644778D02*
X-39607D01*
G01X-35545Y1644699D02*
X0D01*
G01X-27992Y1644482D02*
X-39607D01*
G01X-35545Y1642494D02*
X0D01*
G01X-39607Y1642416D02*
X-24508D01*
G01Y1640841D02*
X-39607D01*
G01X-35545Y1640762D02*
X0D01*
G01X-35545Y1638557D02*
X0D01*
G01X-39607Y1638478D02*
X-24508D01*
G01X-35350Y1656156D02*
X-10630Y1656431D01*
G01X-35350Y1656156D02*
X-10630Y1656431D01*
G01X-35350Y1652219D02*
X-10630Y1652494D01*
G01X-35350Y1652219D02*
X-10630Y1652494D01*
G01X-35350Y1648282D02*
X-10630Y1648557D01*
G01X-35350Y1648282D02*
X-10630Y1648557D01*
G01X-35350Y1644345D02*
X-10630Y1644620D01*
G01X-35350Y1644345D02*
X-10630Y1644620D01*
G01X-35350Y1640408D02*
X-10630Y1640683D01*
G01X-35350Y1640408D02*
X-10630Y1640683D01*
G01X-38108Y1640142D02*
X-35350Y1640408D01*
G01D02*
X-38108Y1640142D01*
G01Y1658862D02*
X-35350Y1658597D01*
G01X-38108Y1658862D02*
X-35350Y1658597D01*
G01X-38108Y1654925D02*
X-35350Y1654660D01*
G01X-38108Y1654925D02*
X-35350Y1654660D01*
G01X-38108Y1650988D02*
X-35350Y1650723D01*
G01X-38108Y1650988D02*
X-35350Y1650723D01*
G01X-38108Y1647051D02*
X-35350Y1646786D01*
G01X-38108Y1647051D02*
X-35350Y1646786D01*
G01X-38108Y1643114D02*
X-35350Y1642849D01*
G01X-38108Y1643114D02*
X-35350Y1642849D01*
G01X-38108Y1639177D02*
X-35350Y1638912D01*
G01X-38108Y1639177D02*
X-35350Y1638912D01*
G01X-24121Y1658471D02*
Y1660218D01*
G01Y1654534D02*
Y1656281D01*
G01Y1650597D02*
Y1652344D01*
G01Y1642723D02*
Y1644470D01*
G01Y1646660D02*
Y1648407D01*
G01Y1638786D02*
Y1640533D01*
G01D02*
Y1638786D01*
G01Y1648407D02*
Y1646660D01*
G01Y1644470D02*
Y1642723D01*
G01Y1652344D02*
Y1650597D01*
G01Y1656281D02*
Y1654534D01*
G01Y1660218D02*
Y1658471D01*
G01X-24508Y1640841D02*
Y1638478D01*
G01Y1644778D02*
Y1642416D01*
G01Y1648715D02*
Y1646353D01*
G01Y1652652D02*
Y1650290D01*
G01Y1656589D02*
Y1654227D01*
G01Y1660526D02*
Y1658164D01*
G01X-24843Y1651608D02*
Y1671254D01*
G01X-26565Y1658499D02*
Y1660191D01*
G01Y1654562D02*
Y1656254D01*
G01Y1650625D02*
Y1652317D01*
G01Y1646688D02*
Y1648380D01*
G01Y1642751D02*
Y1644443D01*
G01Y1638814D02*
Y1640506D01*
G01D02*
Y1638814D01*
G01Y1644443D02*
Y1642751D01*
G01Y1648380D02*
Y1646688D01*
G01Y1652317D02*
Y1650625D01*
G01Y1656254D02*
Y1654562D01*
G01Y1660191D02*
Y1658499D01*
G01X-26942Y1658503D02*
Y1660186D01*
G01Y1654566D02*
Y1656249D01*
G01Y1650629D02*
Y1652312D01*
G01Y1646692D02*
Y1648375D01*
G01Y1642755D02*
Y1644438D01*
G01Y1638818D02*
Y1640501D01*
G01D02*
Y1638818D01*
G01Y1644438D02*
Y1642755D01*
G01Y1648375D02*
Y1646692D01*
G01Y1652312D02*
Y1650629D01*
G01Y1656249D02*
Y1654566D01*
G01Y1660186D02*
Y1658503D01*
G01X-27264Y1640841D02*
Y1638478D01*
G01Y1644778D02*
Y1642416D01*
G01Y1648715D02*
Y1646353D01*
G01Y1652652D02*
Y1650290D01*
G01Y1656589D02*
Y1654227D01*
G01Y1660526D02*
Y1658164D01*
G01X-27992Y1651608D02*
Y1671254D01*
G01X-31941Y1658559D02*
Y1660131D01*
G01Y1654622D02*
Y1656194D01*
G01Y1650685D02*
Y1652257D01*
G01Y1646748D02*
Y1648320D01*
G01Y1642811D02*
Y1644383D01*
G01Y1638874D02*
Y1640446D01*
G01Y1644383D02*
Y1642811D01*
G01Y1640446D02*
Y1638874D01*
G01Y1648320D02*
Y1646748D01*
G01Y1652257D02*
Y1650685D01*
G01Y1656194D02*
Y1654622D01*
G01Y1660131D02*
Y1658559D01*
G01X-32318Y1658563D02*
Y1660127D01*
G01Y1654626D02*
Y1656190D01*
G01Y1650689D02*
Y1652253D01*
G01Y1646752D02*
Y1648316D01*
G01Y1638878D02*
Y1640441D01*
G01Y1642815D02*
Y1644378D01*
G01D02*
Y1642815D01*
G01Y1640441D02*
Y1638878D01*
G01Y1648316D02*
Y1646752D01*
G01Y1652253D02*
Y1650689D01*
G01Y1656190D02*
Y1654626D01*
G01Y1660127D02*
Y1658563D01*
G01X-33153Y1658572D02*
Y1660117D01*
G01Y1654635D02*
Y1656180D01*
G01Y1650698D02*
Y1652243D01*
G01Y1646761D02*
Y1648306D01*
G01Y1642824D02*
Y1644369D01*
G01Y1638887D02*
Y1640432D01*
G01Y1644369D02*
Y1642824D01*
G01Y1640432D02*
Y1638887D01*
G01Y1648306D02*
Y1646761D01*
G01Y1652243D02*
Y1650698D01*
G01Y1656180D02*
Y1654635D01*
G01Y1660117D02*
Y1658572D01*
G01X-34136Y1658583D02*
Y1660106D01*
G01Y1654646D02*
Y1656169D01*
G01Y1650709D02*
Y1652232D01*
G01Y1646772D02*
Y1648295D01*
G01Y1638898D02*
Y1640421D01*
G01Y1642835D02*
Y1644358D01*
G01D02*
Y1642835D01*
G01Y1640421D02*
Y1638898D01*
G01Y1648295D02*
Y1646772D01*
G01Y1652232D02*
Y1650709D01*
G01Y1656169D02*
Y1654646D01*
G01Y1660106D02*
Y1658583D01*
G01X-34607Y1640762D02*
Y1638557D01*
G01Y1648636D02*
Y1646431D01*
G01Y1644699D02*
Y1642494D01*
G01Y1652573D02*
Y1650368D01*
G01Y1656510D02*
Y1654305D01*
G01Y1660447D02*
Y1658242D01*
G01X-35357Y1658597D02*
Y1660092D01*
G01Y1654660D02*
Y1656155D01*
G01Y1650723D02*
Y1652218D01*
G01Y1646786D02*
Y1648281D01*
G01Y1642849D02*
Y1644344D01*
G01Y1638912D02*
Y1640407D01*
G01D02*
Y1638912D01*
G01Y1644344D02*
Y1642849D01*
G01Y1648281D02*
Y1646786D01*
G01Y1652218D02*
Y1650723D01*
G01Y1656155D02*
Y1654660D01*
G01Y1660092D02*
Y1658597D01*
G01X-35545Y1640841D02*
Y1638478D01*
G01Y1644778D02*
Y1642416D01*
G01Y1648715D02*
Y1646353D01*
G01Y1652652D02*
Y1650290D01*
G01Y1656589D02*
Y1654227D01*
G01Y1660526D02*
Y1658164D01*
G01X-35594Y1658620D02*
Y1660069D01*
G01Y1654683D02*
Y1656132D01*
G01Y1650746D02*
Y1652195D01*
G01Y1646809D02*
Y1648258D01*
G01Y1642872D02*
Y1644321D01*
G01Y1638935D02*
Y1640384D01*
G01Y1644321D02*
Y1642872D01*
G01Y1640384D02*
Y1638935D01*
G01Y1648258D02*
Y1646809D01*
G01Y1652195D02*
Y1650746D01*
G01Y1656132D02*
Y1654683D01*
G01Y1660069D02*
Y1658620D01*
G01X-37870Y1658840D02*
Y1659850D01*
G01Y1654903D02*
Y1655913D01*
G01Y1650966D02*
Y1651976D01*
G01Y1647028D02*
Y1648039D01*
G01Y1639154D02*
Y1640165D01*
G01Y1643091D02*
Y1644102D01*
G01D02*
Y1643091D01*
G01Y1640165D02*
Y1639154D01*
G01Y1648039D02*
Y1647028D01*
G01Y1651976D02*
Y1650966D01*
G01Y1655913D02*
Y1654903D01*
G01Y1659850D02*
Y1658840D01*
G01X-38108Y1658862D02*
Y1659827D01*
G01Y1654925D02*
Y1655890D01*
G01Y1650988D02*
Y1651953D01*
G01Y1647051D02*
Y1648016D01*
G01Y1639177D02*
Y1640142D01*
G01Y1643114D02*
Y1644079D01*
G01D02*
Y1643114D01*
G01Y1640142D02*
Y1639177D01*
G01Y1648016D02*
Y1647051D01*
G01Y1651953D02*
Y1650988D01*
G01Y1655890D02*
Y1654925D01*
G01Y1659827D02*
Y1658862D01*
G01X-38425Y1640841D02*
Y1638478D01*
G01Y1648715D02*
Y1646353D01*
G01Y1644778D02*
Y1642416D01*
G01Y1652652D02*
Y1650290D01*
G01Y1656589D02*
Y1654227D01*
G01Y1660526D02*
Y1658164D01*
G01X-38108Y1679512D02*
X-35350Y1679778D01*
G01D02*
X-38108Y1679512D01*
G01Y1675575D02*
X-35350Y1675841D01*
G01D02*
X-38108Y1675575D01*
G01Y1671638D02*
X-35350Y1671904D01*
G01D02*
X-38108Y1671638D01*
G01Y1667701D02*
X-35350Y1667967D01*
G01D02*
X-38108Y1667701D01*
G01Y1663764D02*
X-35350Y1664030D01*
G01D02*
X-38108Y1663764D01*
G01Y1659827D02*
X-35350Y1660093D01*
G01D02*
X-38108Y1659827D01*
G01Y1678547D02*
X-35350Y1678282D01*
G01X-38108Y1678547D02*
X-35350Y1678282D01*
G01X-38108Y1674610D02*
X-35350Y1674345D01*
G01X-38108Y1674610D02*
X-35350Y1674345D01*
G01Y1678282D02*
X-10630Y1678006D01*
G01D02*
X-35350Y1678282D01*
G01Y1674345D02*
X-10630Y1674069D01*
G01D02*
X-35350Y1674345D01*
G01Y1670408D02*
X-10630Y1670132D01*
G01D02*
X-35350Y1670408D01*
G01Y1666471D02*
X-10630Y1666195D01*
G01D02*
X-35350Y1666471D01*
G01Y1662534D02*
X-10630Y1662258D01*
G01D02*
X-35350Y1662534D01*
G01X-24508Y1680211D02*
X-39607D01*
G01X-35545Y1680132D02*
X0D01*
G01X-39607Y1678380D02*
X-27992D01*
G01X-35545Y1677927D02*
X0D01*
G01X-39607Y1677849D02*
X-24508D01*
G01Y1676274D02*
X-39607D01*
G01X-35545Y1676195D02*
X0D01*
G01X-39607Y1675230D02*
X-24843D01*
G01X-35545Y1673990D02*
X0D01*
G01X-39607Y1673912D02*
X-24508D01*
G01Y1672337D02*
X-39607D01*
G01X-35545Y1672258D02*
X0D01*
G01X-39607Y1671254D02*
X-24843D01*
G01X-35545Y1670053D02*
X0D01*
G01X-39607Y1669975D02*
X-24508D01*
G01Y1668400D02*
X-39607D01*
G01X-35545Y1668321D02*
X0D01*
G01X-27992Y1668104D02*
X-39607D01*
G01X-35545Y1666116D02*
X0D01*
G01X-39607Y1666038D02*
X-24508D01*
G01Y1664463D02*
X-39607D01*
G01X-35545Y1664384D02*
X0D01*
G01X-35545Y1662179D02*
X0D01*
G01X-39607Y1662101D02*
X-24508D01*
G01Y1660526D02*
X-39607D01*
G01X-35545Y1660447D02*
X0D01*
G01X-35350Y1679778D02*
X-10630Y1680053D01*
G01X-35350Y1679778D02*
X-10630Y1680053D01*
G01X-35350Y1675841D02*
X-10630Y1676116D01*
G01X-35350Y1675841D02*
X-10630Y1676116D01*
G01X-35350Y1671904D02*
X-10630Y1672179D01*
G01X-35350Y1671904D02*
X-10630Y1672179D01*
G01X-35350Y1667967D02*
X-10630Y1668242D01*
G01X-35350Y1667967D02*
X-10630Y1668242D01*
G01X-35350Y1664030D02*
X-10630Y1664305D01*
G01X-35350Y1664030D02*
X-10630Y1664305D01*
G01X-35350Y1660093D02*
X-10630Y1660368D01*
G01X-35350Y1660093D02*
X-10630Y1660368D01*
G01X-38108Y1670673D02*
X-35350Y1670408D01*
G01X-38108Y1670673D02*
X-35350Y1670408D01*
G01X-38108Y1666736D02*
X-35350Y1666471D01*
G01X-38108Y1666736D02*
X-35350Y1666471D01*
G01X-38108Y1662799D02*
X-35350Y1662534D01*
G01X-38108Y1662799D02*
X-35350Y1662534D01*
G01X-24121Y1678156D02*
Y1679903D01*
G01Y1674219D02*
Y1675966D01*
G01Y1666345D02*
Y1668092D01*
G01Y1670282D02*
Y1672029D01*
G01Y1662408D02*
Y1664155D01*
G01D02*
Y1662408D01*
G01Y1672029D02*
Y1670282D01*
G01Y1668092D02*
Y1666345D01*
G01Y1675966D02*
Y1674219D01*
G01Y1679903D02*
Y1678156D01*
G01X-24508Y1664463D02*
Y1662101D01*
G01Y1668400D02*
Y1666038D01*
G01Y1672337D02*
Y1669975D01*
G01Y1676274D02*
Y1673912D01*
G01Y1680211D02*
Y1677849D01*
G01X-24843Y1675230D02*
Y1694876D01*
G01X-26565Y1678184D02*
Y1679876D01*
G01Y1674247D02*
Y1675939D01*
G01Y1670310D02*
Y1672002D01*
G01Y1666373D02*
Y1668065D01*
G01Y1662436D02*
Y1664128D01*
G01D02*
Y1662436D01*
G01Y1668065D02*
Y1666373D01*
G01Y1672002D02*
Y1670310D01*
G01Y1675939D02*
Y1674247D01*
G01Y1679876D02*
Y1678184D01*
G01X-26942Y1678188D02*
Y1679871D01*
G01Y1674251D02*
Y1675934D01*
G01Y1670314D02*
Y1671997D01*
G01Y1666377D02*
Y1668060D01*
G01Y1662440D02*
Y1664123D01*
G01D02*
Y1662440D01*
G01Y1671997D02*
Y1670314D01*
G01Y1668060D02*
Y1666377D01*
G01Y1675934D02*
Y1674251D01*
G01Y1679871D02*
Y1678188D01*
G01X-27264Y1664463D02*
Y1662101D01*
G01Y1668400D02*
Y1666038D01*
G01Y1672337D02*
Y1669975D01*
G01Y1676274D02*
Y1673912D01*
G01Y1680211D02*
Y1677849D01*
G01X-27992Y1675230D02*
Y1694876D01*
G01X-31941Y1678244D02*
Y1679816D01*
G01Y1674307D02*
Y1675879D01*
G01Y1666433D02*
Y1668005D01*
G01Y1670370D02*
Y1671942D01*
G01Y1662496D02*
Y1664068D01*
G01D02*
Y1662496D01*
G01Y1671942D02*
Y1670370D01*
G01Y1668005D02*
Y1666433D01*
G01Y1675879D02*
Y1674307D01*
G01Y1679816D02*
Y1678244D01*
G01X-32318Y1678248D02*
Y1679812D01*
G01Y1674311D02*
Y1675875D01*
G01Y1670374D02*
Y1671938D01*
G01Y1666437D02*
Y1668001D01*
G01Y1662500D02*
Y1664064D01*
G01D02*
Y1662500D01*
G01Y1671938D02*
Y1670374D01*
G01Y1668001D02*
Y1666437D01*
G01Y1675875D02*
Y1674311D01*
G01Y1679812D02*
Y1678248D01*
G01X-33153Y1678257D02*
Y1679802D01*
G01Y1674320D02*
Y1675865D01*
G01Y1670383D02*
Y1671928D01*
G01Y1666446D02*
Y1667991D01*
G01Y1662509D02*
Y1664054D01*
G01D02*
Y1662509D01*
G01Y1667991D02*
Y1666446D01*
G01Y1671928D02*
Y1670383D01*
G01Y1675865D02*
Y1674320D01*
G01Y1679802D02*
Y1678257D01*
G01X-34136Y1678268D02*
Y1679791D01*
G01Y1674331D02*
Y1675854D01*
G01Y1670394D02*
Y1671917D01*
G01Y1666457D02*
Y1667980D01*
G01Y1662520D02*
Y1664043D01*
G01D02*
Y1662520D01*
G01Y1671917D02*
Y1670394D01*
G01Y1667980D02*
Y1666457D01*
G01Y1675854D02*
Y1674331D01*
G01Y1679791D02*
Y1678268D01*
G01X-34607Y1664384D02*
Y1662179D01*
G01Y1672258D02*
Y1670053D01*
G01Y1668321D02*
Y1666116D01*
G01Y1676195D02*
Y1673990D01*
G01Y1680132D02*
Y1677927D01*
G01X-35357Y1678282D02*
Y1679777D01*
G01Y1674345D02*
Y1675840D01*
G01Y1670408D02*
Y1671903D01*
G01Y1666471D02*
Y1667966D01*
G01Y1662534D02*
Y1664029D01*
G01D02*
Y1662534D01*
G01Y1671903D02*
Y1670408D01*
G01Y1667966D02*
Y1666471D01*
G01Y1675840D02*
Y1674345D01*
G01Y1679777D02*
Y1678282D01*
G01X-35545Y1664463D02*
Y1662101D01*
G01Y1668400D02*
Y1666038D01*
G01Y1672337D02*
Y1669975D01*
G01Y1676274D02*
Y1673912D01*
G01Y1680211D02*
Y1677849D01*
G01X-35594Y1678305D02*
Y1679754D01*
G01Y1674368D02*
Y1675817D01*
G01Y1670431D02*
Y1671880D01*
G01Y1666494D02*
Y1667943D01*
G01Y1662557D02*
Y1664006D01*
G01D02*
Y1662557D01*
G01Y1667943D02*
Y1666494D01*
G01Y1671880D02*
Y1670431D01*
G01Y1675817D02*
Y1674368D01*
G01Y1679754D02*
Y1678305D01*
G01X-37870Y1678525D02*
Y1679535D01*
G01Y1674588D02*
Y1675598D01*
G01Y1670651D02*
Y1671661D01*
G01Y1662777D02*
Y1663787D01*
G01Y1666714D02*
Y1667724D01*
G01D02*
Y1666714D01*
G01Y1663787D02*
Y1662777D01*
G01Y1671661D02*
Y1670651D01*
G01Y1675598D02*
Y1674588D01*
G01Y1679535D02*
Y1678525D01*
G01X-38108Y1678547D02*
Y1679512D01*
G01Y1674610D02*
Y1675575D01*
G01Y1670673D02*
Y1671638D01*
G01Y1662799D02*
Y1663764D01*
G01Y1666736D02*
Y1667701D01*
G01Y1663764D02*
Y1662799D01*
G01Y1667701D02*
Y1666736D01*
G01Y1671638D02*
Y1670673D01*
G01Y1675575D02*
Y1674610D01*
G01Y1679512D02*
Y1678547D01*
G01X-38425Y1664463D02*
Y1662101D01*
G01Y1672337D02*
Y1669975D01*
G01Y1668400D02*
Y1666038D01*
G01Y1676274D02*
Y1673912D01*
G01Y1680211D02*
Y1677849D01*
G01X-36560Y1687740D02*
G03X-34844Y1687199I1716J2451D01*
G01X-39607Y1694876D02*
X0D01*
G01X-38108Y1683449D02*
X-35350Y1683715D01*
G01D02*
X-38108Y1683449D01*
G01Y1682484D02*
X-35350Y1682219D01*
G01X-38108Y1682484D02*
X-35350Y1682219D01*
G01D02*
X-10630Y1681943D01*
G01D02*
X-35350Y1682219D01*
G01X-27992Y1691727D02*
X-39607D01*
G01X-8898Y1687199D02*
X-34844D01*
G01X-24508Y1684148D02*
X-39607D01*
G01X-35545Y1684069D02*
X0D01*
G01X-35545Y1681864D02*
X0D01*
G01X-39607Y1681786D02*
X-24508D01*
G01X-35350Y1683715D02*
X-10630Y1683990D01*
G01X-35350Y1683715D02*
X-10630Y1683990D01*
G01X-36560Y1687740D02*
X-39607Y1689873D01*
G01X-24121Y1682093D02*
Y1683840D01*
G01D02*
Y1682093D01*
G01X-24508Y1684148D02*
Y1681786D01*
G01X-26565Y1682121D02*
Y1683813D01*
G01D02*
Y1682121D01*
G01X-26942Y1682125D02*
Y1683808D01*
G01D02*
Y1682125D01*
G01X-27264Y1684148D02*
Y1681786D01*
G01X-31941Y1682181D02*
Y1683753D01*
G01D02*
Y1682181D01*
G01X-32318Y1682185D02*
Y1683749D01*
G01D02*
Y1682185D01*
G01X-33153Y1682194D02*
Y1683739D01*
G01D02*
Y1682194D01*
G01X-34136Y1682205D02*
Y1683728D01*
G01D02*
Y1682205D01*
G01X-34607Y1684069D02*
Y1681864D01*
G01X-35357Y1682219D02*
Y1683714D01*
G01D02*
Y1682219D01*
G01X-35545Y1684148D02*
Y1681786D01*
G01X-35594Y1682242D02*
Y1683691D01*
G01D02*
Y1682242D01*
G01X-37870Y1682462D02*
Y1683472D01*
G01D02*
Y1682462D01*
G01X-38108Y1682484D02*
Y1683449D01*
G01D02*
Y1682484D01*
G01X-38425Y1684148D02*
Y1681786D01*
G01X-36191Y1764975D02*
X-35350Y1764894D01*
G01D02*
X-10630Y1764619D01*
G01X-35545Y1764555D02*
X0D01*
G01X-39607Y1764477D02*
X-24508D01*
G01X-39607Y1761819D02*
X-9607D01*
G01X-33701Y1757882D02*
X-39607D01*
G01Y1757095D02*
X-27992D01*
G01X-39607Y1753945D02*
X0D01*
G01X-23997Y1766517D02*
Y1764768D01*
G01X-24508Y1766839D02*
Y1764477D01*
G01X-24843Y1753945D02*
Y1769693D01*
G01X-26241Y1766492D02*
Y1764793D01*
G01X-26511Y1766489D02*
Y1764796D01*
G01X-27264Y1766839D02*
Y1764477D01*
G01X-27992Y1769693D02*
Y1753945D01*
G01X-31725Y1764854D02*
Y1766431D01*
G01X-31994Y1766428D02*
Y1764857D01*
G01X-33153Y1766415D02*
Y1764870D01*
G01X-33701Y1761819D02*
Y1757882D01*
G01X-34136Y1764881D02*
Y1766404D01*
G01X-34607Y1766760D02*
Y1764555D01*
G01X-35331Y1766392D02*
Y1764894D01*
G01X-35545Y1764913D02*
Y1764477D01*
G01X-35594Y1766367D02*
Y1764918D01*
G01X-36191Y1766309D02*
Y1764975D01*
G01X-36811Y1808343D02*
Y1760273D01*
G01X-38425Y1766839D02*
Y1764477D01*
G01X-39607Y1852370D02*
Y1753945D01*
G01X-34602Y1761819D02*
X-39607Y1758315D01*
G01X-35350Y1784579D02*
X-10630Y1784304D01*
G01X-35350Y1780642D02*
X-10630Y1780367D01*
G01X-35350Y1776705D02*
X-10630Y1776430D01*
G01X-35545Y1786445D02*
X0D01*
G01X-35545Y1784240D02*
X0D01*
G01X-39607Y1784162D02*
X-24508D01*
G01Y1782587D02*
X-39607D01*
G01X-35545Y1782508D02*
X0D01*
G01X-35545Y1780303D02*
X0D01*
G01X-39607Y1780225D02*
X-24508D01*
G01Y1778650D02*
X-39607D01*
G01X-35545Y1778571D02*
X0D01*
G01X-27992Y1777567D02*
X-39607D01*
G01X-35545Y1776366D02*
X0D01*
G01X-39607Y1776288D02*
X-24508D01*
G01Y1774713D02*
X-39607D01*
G01X-35545Y1774634D02*
X0D01*
G01X-39607Y1774417D02*
X-24843D01*
G01X-35545Y1772429D02*
X0D01*
G01X-39607Y1772351D02*
X-24508D01*
G01Y1770776D02*
X-39607D01*
G01X-35545Y1770697D02*
X0D01*
G01X-39607Y1769693D02*
X-24843D01*
G01X-35545Y1768492D02*
X0D01*
G01X-39607Y1768414D02*
X-24508D01*
G01X-35350Y1786075D02*
X-10630Y1786351D01*
G01X-35350Y1782138D02*
X-10630Y1782414D01*
G01X-35350Y1778201D02*
X-10630Y1778477D01*
G01X-35350Y1774264D02*
X-10630Y1774540D01*
G01X-35350Y1770327D02*
X-10630Y1770603D01*
G01X-35350Y1766390D02*
X-10630Y1766666D01*
G01X-36191Y1785994D02*
X-35340Y1786077D01*
G01X-36191Y1782057D02*
X-35340Y1782140D01*
G01X-36191Y1778120D02*
X-35340Y1778203D01*
G01X-36191Y1774183D02*
X-35340Y1774266D01*
G01X-36191Y1770246D02*
X-35340Y1770328D01*
G01X-36191Y1766309D02*
X-35340Y1766391D01*
G01X-36191Y1784660D02*
X-35350Y1784579D01*
G01X-36191Y1780723D02*
X-35350Y1780642D01*
G01X-36191Y1776786D02*
X-35350Y1776705D01*
G01X-36191Y1772849D02*
X-35350Y1772768D01*
G01X-36191Y1768912D02*
X-35350Y1768831D01*
G01Y1772768D02*
X-10630Y1772493D01*
G01X-35350Y1768831D02*
X-10630Y1768556D01*
G01X-24508Y1766839D02*
X-39607D01*
G01X-35545Y1766760D02*
X0D01*
G01X-39607Y1766543D02*
X-27992D01*
G01X-23997Y1770454D02*
Y1768705D01*
G01Y1774391D02*
Y1772642D01*
G01Y1778328D02*
Y1776579D01*
G01Y1782265D02*
Y1780516D01*
G01Y1786202D02*
Y1784453D01*
G01X-24508Y1770776D02*
Y1768414D01*
G01Y1774713D02*
Y1772351D01*
G01Y1778650D02*
Y1776288D01*
G01Y1786524D02*
Y1784162D01*
G01Y1782587D02*
Y1780225D01*
G01X-24843Y1774417D02*
Y1790166D01*
G01X-26241Y1770429D02*
Y1768730D01*
G01Y1774366D02*
Y1772667D01*
G01Y1778303D02*
Y1776604D01*
G01Y1782240D02*
Y1780541D01*
G01Y1786177D02*
Y1784478D01*
G01X-26511Y1770426D02*
Y1768733D01*
G01Y1774363D02*
Y1772670D01*
G01Y1778300D02*
Y1776607D01*
G01Y1782237D02*
Y1780544D01*
G01Y1786174D02*
Y1784481D01*
G01X-27264Y1770776D02*
Y1768414D01*
G01Y1774713D02*
Y1772351D01*
G01Y1778650D02*
Y1776288D01*
G01Y1782587D02*
Y1780225D01*
G01Y1786524D02*
Y1784162D01*
G01X-27992Y1774417D02*
Y1790166D01*
G01X-31725Y1784539D02*
Y1786116D01*
G01Y1780602D02*
Y1782179D01*
G01Y1776665D02*
Y1778242D01*
G01Y1772728D02*
Y1774305D01*
G01Y1768791D02*
Y1770368D01*
G01X-31994Y1770365D02*
Y1768794D01*
G01Y1774302D02*
Y1772731D01*
G01Y1778239D02*
Y1776668D01*
G01Y1782176D02*
Y1780605D01*
G01Y1786113D02*
Y1784542D01*
G01X-33153Y1770352D02*
Y1768807D01*
G01Y1774289D02*
Y1772744D01*
G01Y1778226D02*
Y1776681D01*
G01Y1782163D02*
Y1780618D01*
G01Y1786100D02*
Y1784555D01*
G01X-34136Y1784566D02*
Y1786089D01*
G01Y1780629D02*
Y1782152D01*
G01Y1776692D02*
Y1778215D01*
G01Y1772755D02*
Y1774278D01*
G01Y1768818D02*
Y1770341D01*
G01X-34607Y1768492D02*
Y1770697D01*
G01Y1774634D02*
Y1772429D01*
G01Y1778571D02*
Y1776366D01*
G01Y1782508D02*
Y1780303D01*
G01Y1786445D02*
Y1784240D01*
G01X-35331Y1770329D02*
Y1768831D01*
G01Y1774266D02*
Y1772768D01*
G01Y1778203D02*
Y1776705D01*
G01Y1782140D02*
Y1780642D01*
G01Y1786077D02*
Y1784579D01*
G01X-35545Y1766839D02*
Y1766371D01*
G01Y1770776D02*
Y1770308D01*
G01Y1768850D02*
Y1768414D01*
G01Y1774713D02*
Y1774245D01*
G01Y1772787D02*
Y1772351D01*
G01Y1778650D02*
Y1778182D01*
G01Y1776724D02*
Y1776288D01*
G01Y1784598D02*
Y1784162D01*
G01Y1782587D02*
Y1782119D01*
G01Y1780661D02*
Y1780225D01*
G01Y1786524D02*
Y1786056D01*
G01X-35594Y1770304D02*
Y1768855D01*
G01Y1774241D02*
Y1772792D01*
G01Y1778178D02*
Y1776729D01*
G01Y1782115D02*
Y1780666D01*
G01Y1786052D02*
Y1784603D01*
G01X-36191Y1770246D02*
Y1768912D01*
G01Y1774183D02*
Y1772849D01*
G01Y1778120D02*
Y1776786D01*
G01Y1782057D02*
Y1780723D01*
G01Y1785994D02*
Y1784660D01*
G01X-38425Y1770776D02*
Y1768414D01*
G01Y1774713D02*
Y1772351D01*
G01Y1778650D02*
Y1776288D01*
G01Y1782587D02*
Y1780225D01*
G01Y1786524D02*
Y1784162D01*
G01X-36560Y1808167D02*
G03X-34844Y1807626I1716J2451D01*
G01X-36191Y1805679D02*
X-35340Y1805762D01*
G01X-36191Y1801742D02*
X-35340Y1801825D01*
G01X-36191Y1797805D02*
X-35340Y1797888D01*
G01X-35350Y1804264D02*
X-10630Y1803989D01*
G01X-35350Y1800327D02*
X-10630Y1800052D01*
G01X-35350Y1796390D02*
X-10630Y1796115D01*
G01X-35350Y1792453D02*
X-10630Y1792178D01*
G01X-35350Y1788516D02*
X-10630Y1788241D01*
G01X-9607Y1807626D02*
X-34844D01*
G01X-39607Y1807488D02*
X-27992D01*
G01X-24508Y1806209D02*
X-39607D01*
G01X-35545Y1806130D02*
X0D01*
G01X-35545Y1803925D02*
X0D01*
G01X-39607Y1803847D02*
X-24508D01*
G01Y1802272D02*
X-39607D01*
G01X-35545Y1802193D02*
X0D01*
G01X-35545Y1799988D02*
X0D01*
G01X-39607Y1799910D02*
X-24508D01*
G01Y1798335D02*
X-39607D01*
G01X-35545Y1798256D02*
X0D01*
G01X-27992Y1798040D02*
X-39607D01*
G01X-35545Y1796051D02*
X0D01*
G01X-39607Y1795973D02*
X-24508D01*
G01X-39607Y1794890D02*
X-24843D01*
G01X-24508Y1794398D02*
X-39607D01*
G01X-35545Y1794319D02*
X0D01*
G01X-35545Y1792114D02*
X0D01*
G01X-39607Y1792036D02*
X-24508D01*
G01Y1790461D02*
X-39607D01*
G01X-35545Y1790382D02*
X0D01*
G01X-39607Y1790166D02*
X-24843D01*
G01X-35545Y1788177D02*
X0D01*
G01X-39607Y1788099D02*
X-24508D01*
G01X-39607Y1787016D02*
X-27992D01*
G01X-24508Y1786524D02*
X-39607D01*
G01X-35350Y1805760D02*
X-10630Y1806036D01*
G01X-35350Y1801823D02*
X-10630Y1802099D01*
G01X-35350Y1797886D02*
X-10630Y1798162D01*
G01X-35350Y1793949D02*
X-10630Y1794225D01*
G01X-35350Y1790012D02*
X-10630Y1790288D01*
G01X-36191Y1793868D02*
X-35340Y1793951D01*
G01X-36191Y1789931D02*
X-35340Y1790014D01*
G01X-36191Y1804345D02*
X-35350Y1804264D01*
G01X-36191Y1800408D02*
X-35350Y1800327D01*
G01X-36191Y1796471D02*
X-35350Y1796390D01*
G01X-36191Y1792534D02*
X-35350Y1792453D01*
G01X-36191Y1788597D02*
X-35350Y1788516D01*
G01X-23997Y1794076D02*
Y1792327D01*
G01Y1790139D02*
Y1788390D01*
G01Y1798013D02*
Y1796264D01*
G01Y1801950D02*
Y1800201D01*
G01Y1805887D02*
Y1804138D01*
G01X-24508Y1790461D02*
Y1788099D01*
G01Y1794398D02*
Y1792036D01*
G01Y1798335D02*
Y1795973D01*
G01Y1802272D02*
Y1799910D01*
G01Y1806209D02*
Y1803847D01*
G01X-24843Y1794890D02*
Y1810638D01*
G01X-26241Y1794051D02*
Y1792352D01*
G01Y1790114D02*
Y1788415D01*
G01Y1797988D02*
Y1796289D01*
G01Y1801925D02*
Y1800226D01*
G01Y1805862D02*
Y1804163D01*
G01X-26511Y1794048D02*
Y1792355D01*
G01Y1790111D02*
Y1788418D01*
G01Y1797985D02*
Y1796292D01*
G01Y1801922D02*
Y1800229D01*
G01Y1805859D02*
Y1804166D01*
G01X-27264Y1790461D02*
Y1788099D01*
G01Y1794398D02*
Y1792036D01*
G01Y1798335D02*
Y1795973D01*
G01Y1802272D02*
Y1799910D01*
G01Y1806209D02*
Y1803847D01*
G01X-27992Y1794890D02*
Y1810638D01*
G01X-31725Y1804224D02*
Y1805801D01*
G01Y1800287D02*
Y1801864D01*
G01Y1796350D02*
Y1797927D01*
G01Y1792413D02*
Y1793990D01*
G01Y1788476D02*
Y1790053D01*
G01X-31994Y1793987D02*
Y1792416D01*
G01Y1790050D02*
Y1788479D01*
G01Y1797924D02*
Y1796353D01*
G01Y1801861D02*
Y1800290D01*
G01Y1805798D02*
Y1804227D01*
G01X-33153Y1793974D02*
Y1792429D01*
G01Y1790037D02*
Y1788492D01*
G01Y1797911D02*
Y1796366D01*
G01Y1801848D02*
Y1800303D01*
G01Y1805785D02*
Y1804240D01*
G01X-34136Y1804251D02*
Y1805774D01*
G01Y1800314D02*
Y1801837D01*
G01Y1796377D02*
Y1797900D01*
G01Y1792440D02*
Y1793963D01*
G01Y1788503D02*
Y1790026D01*
G01X-34607Y1790382D02*
Y1788177D01*
G01Y1794319D02*
Y1792114D01*
G01Y1798256D02*
Y1796051D01*
G01Y1802193D02*
Y1799988D01*
G01Y1806130D02*
Y1803925D01*
G01X-35331Y1793951D02*
Y1792453D01*
G01Y1790014D02*
Y1788516D01*
G01Y1797888D02*
Y1796390D01*
G01Y1801825D02*
Y1800327D01*
G01Y1805762D02*
Y1804264D01*
G01X-35545Y1788535D02*
Y1788099D01*
G01Y1792472D02*
Y1792036D01*
G01Y1790461D02*
Y1789993D01*
G01Y1798335D02*
Y1797867D01*
G01Y1796409D02*
Y1795973D01*
G01Y1794398D02*
Y1793930D01*
G01Y1802272D02*
Y1801804D01*
G01Y1800346D02*
Y1799910D01*
G01Y1806209D02*
Y1805741D01*
G01Y1804283D02*
Y1803847D01*
G01X-35594Y1793926D02*
Y1792477D01*
G01Y1789989D02*
Y1788540D01*
G01Y1797863D02*
Y1796414D01*
G01Y1801800D02*
Y1800351D01*
G01Y1805737D02*
Y1804288D01*
G01X-36191Y1793868D02*
Y1792534D01*
G01Y1789931D02*
Y1788597D01*
G01Y1797805D02*
Y1796471D01*
G01Y1801742D02*
Y1800408D01*
G01Y1805679D02*
Y1804345D01*
G01X-38425Y1790461D02*
Y1788099D01*
G01Y1798335D02*
Y1795973D01*
G01Y1794398D02*
Y1792036D01*
G01Y1802272D02*
Y1799910D01*
G01Y1806209D02*
Y1803847D01*
G01X-39607Y1811017D02*
G03X-39019Y1809889I1378J1D01*
G01Y1812175D02*
G03X-39607Y1811046I791J-1129D01*
G01X-34844Y1814437D02*
G03X-36560Y1813896I0J-2992D01*
G01X-36191Y1825364D02*
X-35340Y1825447D01*
G01X-36191Y1821427D02*
X-35340Y1821510D01*
G01X-36191Y1817490D02*
X-35340Y1817573D01*
G01X-36191Y1827967D02*
X-35350Y1827886D01*
G01D02*
X-10630Y1827611D01*
G01X-35350Y1823949D02*
X-10630Y1823674D01*
G01X-35350Y1820012D02*
X-10630Y1819737D01*
G01X-35350Y1816075D02*
X-10630Y1815800D01*
G01X-39607Y1827961D02*
X-27992D01*
G01X-35545Y1827547D02*
X0D01*
G01X-39607Y1827469D02*
X-24508D01*
G01Y1825894D02*
X-39607D01*
G01X-35545Y1825815D02*
X0D01*
G01X-35545Y1823610D02*
X0D01*
G01X-39607Y1823532D02*
X-24508D01*
G01Y1821957D02*
X-39607D01*
G01X-35545Y1821878D02*
X0D01*
G01X-35545Y1819673D02*
X0D01*
G01X-39607Y1819595D02*
X-24508D01*
G01X-27992Y1818512D02*
X-39607D01*
G01X-24508Y1818020D02*
X-39607D01*
G01X-35545Y1817941D02*
X0D01*
G01X-35545Y1815736D02*
X0D01*
G01X-39607Y1815658D02*
X-24508D01*
G01X-39607Y1815362D02*
X-24843D01*
G01X-34844Y1814437D02*
X-9607D01*
G01X-35433Y1813433D02*
X0D01*
G01X-39607Y1810638D02*
X-24843D01*
G01X0Y1808433D02*
X-35433D01*
G01X-35350Y1825445D02*
X-10630Y1825721D01*
G01X-35350Y1821508D02*
X-10630Y1821784D01*
G01X-35350Y1817571D02*
X-10630Y1817847D01*
G01X-36191Y1824030D02*
X-35350Y1823949D01*
G01X-36191Y1820093D02*
X-35350Y1820012D01*
G01X-36191Y1816156D02*
X-35350Y1816075D01*
G01X-36560Y1808167D02*
X-39019Y1809889D01*
G01X-23997Y1827760D02*
Y1829509D01*
G01Y1823823D02*
Y1825572D01*
G01Y1819886D02*
Y1821635D01*
G01Y1815949D02*
Y1817698D01*
G01X-24508Y1818020D02*
Y1815658D01*
G01Y1821957D02*
Y1819595D01*
G01Y1825894D02*
Y1823532D01*
G01Y1829831D02*
Y1827469D01*
G01X-24843Y1815362D02*
Y1831110D01*
G01X-26241Y1821610D02*
Y1819911D01*
G01Y1817673D02*
Y1815974D01*
G01Y1825547D02*
Y1823848D01*
G01Y1829484D02*
Y1827785D01*
G01X-26511Y1821607D02*
Y1819914D01*
G01Y1817670D02*
Y1815977D01*
G01Y1825544D02*
Y1823851D01*
G01Y1829481D02*
Y1827788D01*
G01X-27264Y1818020D02*
Y1815658D01*
G01Y1821957D02*
Y1819595D01*
G01Y1825894D02*
Y1823532D01*
G01Y1829831D02*
Y1827469D01*
G01X-27992Y1815362D02*
Y1831110D01*
G01X-31725Y1827846D02*
Y1829423D01*
G01Y1823909D02*
Y1825486D01*
G01Y1819972D02*
Y1821549D01*
G01Y1816035D02*
Y1817612D01*
G01X-31994Y1817609D02*
Y1816038D01*
G01Y1821546D02*
Y1819975D01*
G01Y1825483D02*
Y1823912D01*
G01Y1829420D02*
Y1827849D01*
G01X-33153Y1817596D02*
Y1816051D01*
G01Y1821533D02*
Y1819988D01*
G01Y1825470D02*
Y1823925D01*
G01Y1829407D02*
Y1827862D01*
G01X-34136Y1827873D02*
Y1829396D01*
G01Y1823936D02*
Y1825459D01*
G01Y1819999D02*
Y1821522D01*
G01Y1816062D02*
Y1817585D01*
G01X-34607Y1815736D02*
Y1817941D01*
G01Y1821878D02*
Y1819673D01*
G01Y1825815D02*
Y1823610D01*
G01Y1829752D02*
Y1827547D01*
G01X-35331Y1817573D02*
Y1816075D01*
G01Y1821510D02*
Y1820012D01*
G01Y1825447D02*
Y1823949D01*
G01Y1829384D02*
Y1827886D01*
G01X-35433Y1808433D02*
Y1813433D01*
G01X-35545Y1816094D02*
Y1815658D01*
G01Y1821957D02*
Y1821490D01*
G01Y1820031D02*
Y1819595D01*
G01Y1818020D02*
Y1817553D01*
G01Y1825894D02*
Y1825427D01*
G01Y1823968D02*
Y1823532D01*
G01Y1827905D02*
Y1827469D01*
G01X-35594Y1817548D02*
Y1816099D01*
G01Y1821485D02*
Y1820036D01*
G01Y1825422D02*
Y1823973D01*
G01Y1829359D02*
Y1827910D01*
G01X-36191Y1817490D02*
Y1816156D01*
G01Y1821427D02*
Y1820093D01*
G01Y1825364D02*
Y1824030D01*
G01Y1829301D02*
Y1827967D01*
G01X-36811Y1845272D02*
Y1813721D01*
G01X-38425Y1821957D02*
Y1819595D01*
G01Y1818020D02*
Y1815658D01*
G01Y1825894D02*
Y1823532D01*
G01Y1829831D02*
Y1827469D01*
G01X-39019Y1812175D02*
X-36560Y1813896D01*
G01Y1845097D02*
G03X-34844Y1844555I1717J2450D01*
G01X-27992Y1849221D02*
X-39607D01*
G01X-9607Y1844555D02*
X-34844D01*
G01X-35350Y1841193D02*
X-10630Y1841469D01*
G01X-36191Y1841112D02*
X-35340Y1841195D01*
G01X-36191Y1837175D02*
X-35340Y1837258D01*
G01X-36191Y1833238D02*
X-35340Y1833321D01*
G01X-36191Y1829301D02*
X-35340Y1829384D01*
G01X-36191Y1839778D02*
X-35350Y1839697D01*
G01X-36191Y1835841D02*
X-35350Y1835760D01*
G01X-36191Y1831904D02*
X-35350Y1831823D01*
G01Y1839697D02*
X-10630Y1839422D01*
G01X-35350Y1835760D02*
X-10630Y1835485D01*
G01X-35350Y1831823D02*
X-10630Y1831548D01*
G01X-24508Y1841642D02*
X-39607D01*
G01X-35545Y1841563D02*
X0D01*
G01X-35545Y1839358D02*
X0D01*
G01X-39607Y1839280D02*
X-24508D01*
G01X-27992Y1838984D02*
X-39607D01*
G01X-24508Y1837705D02*
X-39607D01*
G01X-35545Y1837626D02*
X0D01*
G01X-39607Y1835835D02*
X-24843D01*
G01X-35545Y1835421D02*
X0D01*
G01X-39607Y1835343D02*
X-24508D01*
G01Y1833768D02*
X-39607D01*
G01X-35545Y1833689D02*
X0D01*
G01X-35545Y1831484D02*
X0D01*
G01X-39607Y1831406D02*
X-24508D01*
G01X-39607Y1831110D02*
X-24843D01*
G01X-24508Y1829831D02*
X-39607D01*
G01X-35545Y1829752D02*
X0D01*
G01X-35350Y1837256D02*
X-10630Y1837532D01*
G01X-35350Y1833319D02*
X-10630Y1833595D01*
G01X-35350Y1829382D02*
X-10630Y1829658D01*
G01X-39607Y1847229D02*
X-36560Y1845097D01*
G01X-23997Y1839571D02*
Y1841320D01*
G01Y1835634D02*
Y1837383D01*
G01Y1831697D02*
Y1833446D01*
G01X-24508Y1833768D02*
Y1831406D01*
G01Y1837705D02*
Y1835343D01*
G01Y1841642D02*
Y1839280D01*
G01X-24843Y1835835D02*
Y1852370D01*
G01X-26241Y1837358D02*
Y1835659D01*
G01Y1833421D02*
Y1831722D01*
G01Y1841295D02*
Y1839596D01*
G01X-26511Y1837355D02*
Y1835662D01*
G01Y1833418D02*
Y1831725D01*
G01Y1841292D02*
Y1839599D01*
G01X-27264Y1833768D02*
Y1831406D01*
G01Y1837705D02*
Y1835343D01*
G01Y1841642D02*
Y1839280D01*
G01X-27992Y1835835D02*
Y1852370D01*
G01X-31725Y1839657D02*
Y1841234D01*
G01Y1835720D02*
Y1837297D01*
G01Y1831783D02*
Y1833360D01*
G01X-31994Y1833357D02*
Y1831786D01*
G01Y1837294D02*
Y1835723D01*
G01Y1841231D02*
Y1839660D01*
G01X-33153Y1837281D02*
Y1835736D01*
G01Y1833344D02*
Y1831799D01*
G01Y1841218D02*
Y1839673D01*
G01X-34136Y1839684D02*
Y1841207D01*
G01Y1835747D02*
Y1837270D01*
G01Y1831810D02*
Y1833333D01*
G01X-34607Y1837626D02*
Y1835421D01*
G01Y1833689D02*
Y1831484D01*
G01Y1841563D02*
Y1839358D01*
G01X-35331Y1833321D02*
Y1831823D01*
G01Y1837258D02*
Y1835760D01*
G01Y1841195D02*
Y1839697D01*
G01X-35545Y1831842D02*
Y1831406D01*
G01Y1829831D02*
Y1829364D01*
G01Y1835779D02*
Y1835343D01*
G01Y1833768D02*
Y1833301D01*
G01Y1839716D02*
Y1839280D01*
G01Y1837705D02*
Y1837238D01*
G01Y1841642D02*
Y1841175D01*
G01X-35594Y1837233D02*
Y1835784D01*
G01Y1833296D02*
Y1831847D01*
G01Y1841170D02*
Y1839721D01*
G01X-36191Y1833238D02*
Y1831904D01*
G01Y1837175D02*
Y1835841D01*
G01Y1841112D02*
Y1839778D01*
G01X-38425Y1837705D02*
Y1835343D01*
G01Y1833768D02*
Y1831406D01*
G01Y1841642D02*
Y1839280D01*
G01X-39607Y1852370D02*
X0D01*
G01X-29468Y1939630D02*
Y1955630D01*
G01X-39968Y1945130D02*
X-34968D01*
G01Y1950130D02*
X-39968D01*
G01Y1945130D02*
Y1950130D01*
G01X-34968D02*
Y1945130D01*
G01X-37468Y1950130D02*
Y1945130D01*
G01X-39968Y1947630D02*
X-34968D01*
G01X-31629Y1969498D02*
G03I-4291J0D01*
G01X-7874Y17253D02*
Y0D01*
G01X0Y17214D02*
G03X-7874I-3937J0D01*
G01X0D02*
G03X-7874I-3937J0D01*
G01Y41772D02*
Y167110D01*
G01Y41772D02*
G03X0I3937J0D01*
G01X-7874D02*
G03X0I3937J0D01*
G01Y167110D02*
G03X-7874I-3937J0D01*
G01X0D02*
G03X-7874I-3937J0D01*
G01Y191667D02*
Y308383D01*
G01Y191667D02*
G03X0I3937J0D01*
G01X-7874D02*
G03X0I3937J0D01*
G01Y308383D02*
G03X-7874I-3937J0D01*
G01X0D02*
G03X-7874I-3937J0D01*
G01Y331986D02*
Y334646D01*
G01Y332003D02*
G03X0I3937J0D01*
G01X-7874D02*
G03X0I3937J0D01*
G01X-9055Y360230D02*
Y340939D01*
G01D02*
X24803D01*
G01X-8898Y368104D02*
Y413912D01*
G01X-9055Y358252D02*
X9842Y357081D01*
G01Y349207D02*
X-9055Y348803D01*
G01X-10630Y372967D02*
X-9843Y373321D01*
G01D02*
X-10630Y372967D01*
G01Y376904D02*
X-9843Y377258D01*
G01D02*
X-10630Y376904D01*
G01Y380841D02*
X-9843Y381195D01*
G01D02*
X-10630Y380841D01*
G01Y384778D02*
X-9843Y385132D01*
G01D02*
X-10630Y384778D01*
G01Y388715D02*
X-9843Y389069D01*
G01D02*
X-10630Y388715D01*
G01X-3377Y370486D02*
X-3150Y370880D01*
G01X-3377Y370486D02*
X-3150Y370880D01*
G01X-3377Y374423D02*
X-3150Y374817D01*
G01X-3377Y374423D02*
X-3150Y374817D01*
G01X-3377Y378360D02*
X-3150Y378754D01*
G01X-3377Y378360D02*
X-3150Y378754D01*
G01X-3377Y382297D02*
X-3150Y382691D01*
G01X-3377Y382297D02*
X-3150Y382691D01*
G01X-3377Y386234D02*
X-3150Y386628D01*
G01X-3377Y386234D02*
X-3150Y386628D01*
G01X-3377Y390171D02*
X-3150Y390565D01*
G01X-3377Y390171D02*
X-3150Y390565D01*
G01X-6693Y389069D02*
X-4725Y389384D01*
G01X-6693Y389069D02*
X-4725Y389384D01*
G01X-6693Y385132D02*
X-4725Y385447D01*
G01X-6693Y385132D02*
X-4725Y385447D01*
G01X-3377Y389148D02*
X-4258Y388912D01*
G01X-3377Y389148D02*
X-4258Y388912D01*
G01X-3377Y385211D02*
X-4258Y384975D01*
G01X-3377Y385211D02*
X-4258Y384975D01*
G01X-3377Y381274D02*
X-4258Y381038D01*
G01X-3377Y381274D02*
X-4258Y381038D01*
G01X-3377Y377337D02*
X-4258Y377101D01*
G01X-3377Y377337D02*
X-4258Y377101D01*
G01X-3377Y373400D02*
X-4258Y373164D01*
G01X-3377Y373400D02*
X-4258Y373164D01*
G01X-6693Y381195D02*
X-4725Y381510D01*
G01X-6693Y381195D02*
X-4725Y381510D01*
G01X-6693Y377258D02*
X-4725Y377573D01*
G01X-6693Y377258D02*
X-4725Y377573D01*
G01X-6693Y373321D02*
X-4725Y373636D01*
G01X-6693Y373321D02*
X-4725Y373636D01*
G01X-3756Y373045D02*
Y370841D01*
G01Y376982D02*
Y374778D01*
G01Y380919D02*
Y378715D01*
G01Y384856D02*
Y382652D01*
G01Y388793D02*
Y386589D01*
G01X-4725Y389935D02*
Y390841D01*
G01Y384541D02*
Y385447D01*
G01Y385998D02*
Y386904D01*
G01Y388478D02*
Y389384D01*
G01Y380604D02*
Y381510D01*
G01Y382061D02*
Y382967D01*
G01Y376667D02*
Y377573D01*
G01Y378124D02*
Y379030D01*
G01Y372730D02*
Y373636D01*
G01Y374187D02*
Y375093D01*
G01Y370250D02*
Y371156D01*
G01D02*
Y370250D01*
G01Y373636D02*
Y372730D01*
G01Y375093D02*
Y374187D01*
G01Y379030D02*
Y378124D01*
G01Y377573D02*
Y376667D01*
G01Y382967D02*
Y382061D01*
G01Y381510D02*
Y380604D01*
G01Y385447D02*
Y384541D01*
G01Y386904D02*
Y385998D01*
G01Y389384D02*
Y388478D01*
G01Y390841D02*
Y389935D01*
G01X-6693Y371156D02*
Y370565D01*
G01Y371156D02*
Y370565D01*
G01Y373321D02*
Y372730D01*
G01Y375093D02*
Y374502D01*
G01Y373321D02*
Y372730D01*
G01Y375093D02*
Y374502D01*
G01Y379030D02*
Y378439D01*
G01Y377258D02*
Y376667D01*
G01Y377258D02*
Y376667D01*
G01Y379030D02*
Y378439D01*
G01Y382967D02*
Y382376D01*
G01Y385132D02*
Y384541D01*
G01Y381195D02*
Y380604D01*
G01Y381195D02*
Y380604D01*
G01Y382967D02*
Y382376D01*
G01Y385132D02*
Y384541D01*
G01Y386904D02*
Y386313D01*
G01Y389069D02*
Y388478D01*
G01Y386904D02*
Y386313D01*
G01Y389069D02*
Y388478D01*
G01Y390841D02*
Y390250D01*
G01Y390841D02*
Y390250D01*
G01X-10530Y373012D02*
Y370875D01*
G01Y373012D02*
Y370875D01*
G01Y376949D02*
Y374812D01*
G01Y376949D02*
Y374812D01*
G01Y384823D02*
Y382686D01*
G01Y380886D02*
Y378749D01*
G01Y384823D02*
Y382686D01*
G01Y380886D02*
Y378749D01*
G01Y388760D02*
Y386623D01*
G01Y388760D02*
Y386623D01*
G01X-11842Y386681D02*
Y388701D01*
G01Y382744D02*
Y384764D01*
G01Y378807D02*
Y380827D01*
G01Y374870D02*
Y376890D01*
G01Y370933D02*
Y372953D01*
G01D02*
Y370933D01*
G01Y376890D02*
Y374870D01*
G01Y380827D02*
Y378807D01*
G01Y384764D02*
Y382744D01*
G01Y388701D02*
Y386681D01*
G01X-12280Y386686D02*
Y388696D01*
G01Y382749D02*
Y384759D01*
G01Y378812D02*
Y380822D01*
G01Y374875D02*
Y376885D01*
G01Y370938D02*
Y372948D01*
G01D02*
Y370938D01*
G01Y376885D02*
Y374875D01*
G01Y384759D02*
Y382749D01*
G01Y380822D02*
Y378812D01*
G01Y388696D02*
Y386686D01*
G01X-12992Y370841D02*
Y370526D01*
G01Y373360D02*
Y373045D01*
G01Y374778D02*
Y374463D01*
G01Y378715D02*
Y378400D01*
G01Y377297D02*
Y376982D01*
G01Y385171D02*
Y384856D01*
G01Y382652D02*
Y382337D01*
G01Y381234D02*
Y380919D01*
G01Y389108D02*
Y388793D01*
G01Y386589D02*
Y386274D01*
G01Y390526D02*
Y390211D01*
G01X-23684Y386813D02*
Y388569D01*
G01Y378939D02*
Y380695D01*
G01Y382876D02*
Y384632D01*
G01Y375002D02*
Y376758D01*
G01Y371065D02*
Y372821D01*
G01D02*
Y371065D01*
G01Y376758D02*
Y375002D01*
G01Y384632D02*
Y382876D01*
G01Y380695D02*
Y378939D01*
G01Y388569D02*
Y386813D01*
G01X-4258Y390408D02*
X-4725D01*
G01X-4258D02*
X-4725D01*
G01X-6693Y390250D02*
X-9843D01*
G01X-6693D02*
X-9843D01*
G01X-12992Y390211D02*
X0D01*
G01Y389108D02*
X-12992D01*
G01X-9843Y389069D02*
X-6693D01*
G01X-9843D02*
X-6693D01*
G01X-4725Y388912D02*
X-4258D01*
G01X-4725D02*
X-4258D01*
G01X-3150Y388754D02*
X-2196D01*
G01X-3150D02*
X-2196D01*
G01X-4725Y388478D02*
X-6693D01*
G01X-4725D02*
X-6693D01*
G01X-4725Y386904D02*
X-6693D01*
G01X-4725D02*
X-6693D01*
G01X-2196Y386628D02*
X-3150D01*
G01X-2196D02*
X-3150D01*
G01X-4258Y386471D02*
X-4725D01*
G01X-4258D02*
X-4725D01*
G01X-6693Y386313D02*
X-9843D01*
G01X-6693D02*
X-9843D01*
G01X-12992Y386274D02*
X0D01*
G01Y385171D02*
X-12992D01*
G01X-9843Y385132D02*
X-6693D01*
G01X-9843D02*
X-6693D01*
G01X-4725Y384975D02*
X-4258D01*
G01X-4725D02*
X-4258D01*
G01X-3150Y384817D02*
X-2196D01*
G01X-3150D02*
X-2196D01*
G01X-4725Y384541D02*
X-6693D01*
G01X-4725D02*
X-6693D01*
G01X-4725Y382967D02*
X-6693D01*
G01X-4725D02*
X-6693D01*
G01X-2196Y382691D02*
X-3150D01*
G01X-2196D02*
X-3150D01*
G01X-4258Y382534D02*
X-4725D01*
G01X-4258D02*
X-4725D01*
G01X-6693Y382376D02*
X-9843D01*
G01X-6693D02*
X-9843D01*
G01X-12992Y382337D02*
X0D01*
G01Y381234D02*
X-12992D01*
G01X-9843Y381195D02*
X-6693D01*
G01X-9843D02*
X-6693D01*
G01X-4725Y381038D02*
X-4258D01*
G01X-4725D02*
X-4258D01*
G01X-3150Y380880D02*
X-2196D01*
G01X-3150D02*
X-2196D01*
G01X-4725Y380604D02*
X-6693D01*
G01X-4725D02*
X-6693D01*
G01X-4725Y379030D02*
X-6693D01*
G01X-4725D02*
X-6693D01*
G01X-2196Y378754D02*
X-3150D01*
G01X-2196D02*
X-3150D01*
G01X-4258Y378597D02*
X-4725D01*
G01X-4258D02*
X-4725D01*
G01X-6693Y378439D02*
X-9843D01*
G01X-6693D02*
X-9843D01*
G01X-12992Y378400D02*
X0D01*
G01Y377297D02*
X-12992D01*
G01X-9843Y377258D02*
X-6693D01*
G01X-9843D02*
X-6693D01*
G01X-4725Y377101D02*
X-4258D01*
G01X-4725D02*
X-4258D01*
G01X-3150Y376943D02*
X-2196D01*
G01X-3150D02*
X-2196D01*
G01X-4725Y376667D02*
X-6693D01*
G01X-4725D02*
X-6693D01*
G01X-4725Y375093D02*
X-6693D01*
G01X-4725D02*
X-6693D01*
G01X-2196Y374817D02*
X-3150D01*
G01X-2196D02*
X-3150D01*
G01X-4258Y374660D02*
X-4725D01*
G01X-4258D02*
X-4725D01*
G01X-6693Y374502D02*
X-9843D01*
G01X-6693D02*
X-9843D01*
G01X-12992Y374463D02*
X0D01*
G01Y373360D02*
X-12992D01*
G01X-9843Y373321D02*
X-6693D01*
G01X-9843D02*
X-6693D01*
G01X-4725Y373164D02*
X-4258D01*
G01X-4725D02*
X-4258D01*
G01X-3150Y373006D02*
X-2196D01*
G01X-3150D02*
X-2196D01*
G01X-4725Y372730D02*
X-6693D01*
G01X-4725D02*
X-6693D01*
G01X-4725Y371156D02*
X-6693D01*
G01X-4725D02*
X-6693D01*
G01X-2196Y370880D02*
X-3150D01*
G01X-2196D02*
X-3150D01*
G01X-4258Y370723D02*
X-4725D01*
G01X-4258D02*
X-4725D01*
G01X-6693Y370565D02*
X-9843D01*
G01X-6693D02*
X-9843D01*
G01X-12992Y370526D02*
X0D01*
G01X-4258Y390408D02*
X-3377Y390171D01*
G01X-4258Y390408D02*
X-3377Y390171D01*
G01X-4258Y386471D02*
X-3377Y386234D01*
G01X-4258Y386471D02*
X-3377Y386234D01*
G01X-4258Y382534D02*
X-3377Y382297D01*
G01X-4258Y382534D02*
X-3377Y382297D01*
G01X-4258Y378597D02*
X-3377Y378360D01*
G01X-4258Y378597D02*
X-3377Y378360D01*
G01X-4258Y374660D02*
X-3377Y374423D01*
G01X-4258Y374660D02*
X-3377Y374423D01*
G01X-4258Y370723D02*
X-3377Y370486D01*
G01X-4258Y370723D02*
X-3377Y370486D01*
G01X-4725Y389935D02*
X-6693Y390250D01*
G01X-4725Y389935D02*
X-6693Y390250D01*
G01X-4725Y385998D02*
X-6693Y386313D01*
G01X-4725Y385998D02*
X-6693Y386313D01*
G01X-4725Y382061D02*
X-6693Y382376D01*
G01X-4725Y382061D02*
X-6693Y382376D01*
G01X-4725Y378124D02*
X-6693Y378439D01*
G01X-4725Y378124D02*
X-6693Y378439D01*
G01X-4725Y374187D02*
X-6693Y374502D01*
G01X-4725Y374187D02*
X-6693Y374502D01*
G01X-4725Y370250D02*
X-6693Y370565D01*
G01X-4725Y370250D02*
X-6693Y370565D01*
G01X-3150Y388754D02*
X-3377Y389148D01*
G01X-3150Y388754D02*
X-3377Y389148D01*
G01X-3150Y384817D02*
X-3377Y385211D01*
G01X-3150Y384817D02*
X-3377Y385211D01*
G01X-3150Y380880D02*
X-3377Y381274D01*
G01X-3150Y380880D02*
X-3377Y381274D01*
G01X-3150Y376943D02*
X-3377Y377337D01*
G01X-3150Y376943D02*
X-3377Y377337D01*
G01X-3150Y373006D02*
X-3377Y373400D01*
G01X-3150Y373006D02*
X-3377Y373400D01*
G01X-10630Y390604D02*
X-9843Y390250D01*
G01X-10630Y390604D02*
X-9843Y390250D01*
G01X-10630Y386667D02*
X-9843Y386313D01*
G01X-10630Y386667D02*
X-9843Y386313D01*
G01X-10630Y382730D02*
X-9843Y382376D01*
G01X-10630Y382730D02*
X-9843Y382376D01*
G01X-10630Y378793D02*
X-9843Y378439D01*
G01X-10630Y378793D02*
X-9843Y378439D01*
G01X-10630Y374856D02*
X-9843Y374502D01*
G01X-10630Y374856D02*
X-9843Y374502D01*
G01X-10630Y370919D02*
X-9843Y370565D01*
G01X-10630Y370919D02*
X-9843Y370565D01*
G01X-10630Y392652D02*
X-9843Y393006D01*
G01D02*
X-10630Y392652D01*
G01Y396589D02*
X-9843Y396943D01*
G01D02*
X-10630Y396589D01*
G01Y400526D02*
X-9843Y400880D01*
G01D02*
X-10630Y400526D01*
G01Y404463D02*
X-9843Y404817D01*
G01D02*
X-10630Y404463D01*
G01Y408400D02*
X-9843Y408754D01*
G01D02*
X-10630Y408400D01*
G01X-3377Y394108D02*
X-3150Y394502D01*
G01X-3377Y394108D02*
X-3150Y394502D01*
G01X-3377Y398045D02*
X-3150Y398439D01*
G01X-3377Y398045D02*
X-3150Y398439D01*
G01X-3377Y401982D02*
X-3150Y402376D01*
G01X-3377Y401982D02*
X-3150Y402376D01*
G01X-3377Y405919D02*
X-3150Y406313D01*
G01X-3377Y405919D02*
X-3150Y406313D01*
G01X-3377Y409856D02*
X-3150Y410250D01*
G01X-3377Y409856D02*
X-3150Y410250D01*
G01X-3377Y408833D02*
X-4258Y408597D01*
G01X-3377Y408833D02*
X-4258Y408597D01*
G01X-3377Y404896D02*
X-4258Y404660D01*
G01X-3377Y404896D02*
X-4258Y404660D01*
G01X-3377Y400959D02*
X-4258Y400723D01*
G01X-3377Y400959D02*
X-4258Y400723D01*
G01X-3377Y397022D02*
X-4258Y396786D01*
G01X-3377Y397022D02*
X-4258Y396786D01*
G01X-6693Y408754D02*
X-4725Y409069D01*
G01X-6693Y408754D02*
X-4725Y409069D01*
G01X-6693Y404817D02*
X-4725Y405132D01*
G01X-6693Y404817D02*
X-4725Y405132D01*
G01X-6693Y400880D02*
X-4725Y401195D01*
G01X-6693Y400880D02*
X-4725Y401195D01*
G01X-6693Y396943D02*
X-4725Y397258D01*
G01X-6693Y396943D02*
X-4725Y397258D01*
G01X-6693Y393006D02*
X-4725Y393321D01*
G01X-6693Y393006D02*
X-4725Y393321D01*
G01X-3377Y393085D02*
X-4258Y392849D01*
G01X-3377Y393085D02*
X-4258Y392849D01*
G01X-4725Y410526D02*
X-6693D01*
G01X-4725D02*
X-6693D01*
G01X-2196Y410250D02*
X-3150D01*
G01X-2196D02*
X-3150D01*
G01X-4258Y410093D02*
X-4725D01*
G01X-4258D02*
X-4725D01*
G01X-6693Y409935D02*
X-9843D01*
G01X-6693D02*
X-9843D01*
G01X-12992Y409896D02*
X0D01*
G01Y408793D02*
X-12992D01*
G01X-9843Y408754D02*
X-6693D01*
G01X-9843D02*
X-6693D01*
G01X-4725Y408597D02*
X-4258D01*
G01X-4725D02*
X-4258D01*
G01X-3150Y408439D02*
X-2196D01*
G01X-3150D02*
X-2196D01*
G01X-4725Y408164D02*
X-6693D01*
G01X-4725D02*
X-6693D01*
G01X-4725Y406589D02*
X-6693D01*
G01X-4725D02*
X-6693D01*
G01X-2196Y406313D02*
X-3150D01*
G01X-2196D02*
X-3150D01*
G01X-4258Y406156D02*
X-4725D01*
G01X-4258D02*
X-4725D01*
G01X-6693Y405998D02*
X-9843D01*
G01X-6693D02*
X-9843D01*
G01X-12992Y405959D02*
X0D01*
G01Y404856D02*
X-12992D01*
G01X-9843Y404817D02*
X-6693D01*
G01X-9843D02*
X-6693D01*
G01X-4725Y404660D02*
X-4258D01*
G01X-4725D02*
X-4258D01*
G01X-3150Y404502D02*
X-2196D01*
G01X-3150D02*
X-2196D01*
G01X-4725Y404227D02*
X-6693D01*
G01X-4725D02*
X-6693D01*
G01X-4725Y402652D02*
X-6693D01*
G01X-4725D02*
X-6693D01*
G01X-2196Y402376D02*
X-3150D01*
G01X-2196D02*
X-3150D01*
G01X-4258Y402219D02*
X-4725D01*
G01X-4258D02*
X-4725D01*
G01X-6693Y402061D02*
X-9843D01*
G01X-6693D02*
X-9843D01*
G01X-12992Y402022D02*
X0D01*
G01Y400919D02*
X-12992D01*
G01X-9843Y400880D02*
X-6693D01*
G01X-9843D02*
X-6693D01*
G01X-4725Y400723D02*
X-4258D01*
G01X-4725D02*
X-4258D01*
G01X-3150Y400565D02*
X-2196D01*
G01X-3150D02*
X-2196D01*
G01X-4725Y400290D02*
X-6693D01*
G01X-4725D02*
X-6693D01*
G01X-4725Y398715D02*
X-6693D01*
G01X-4725D02*
X-6693D01*
G01X-2196Y398439D02*
X-3150D01*
G01X-2196D02*
X-3150D01*
G01X-4258Y398282D02*
X-4725D01*
G01X-4258D02*
X-4725D01*
G01X-6693Y398124D02*
X-9843D01*
G01X-6693D02*
X-9843D01*
G01X-12992Y398085D02*
X0D01*
G01X-3756Y392730D02*
Y390526D01*
G01Y396667D02*
Y394463D01*
G01Y400604D02*
Y398400D01*
G01Y404541D02*
Y402337D01*
G01Y408478D02*
Y406274D01*
G01Y412416D02*
Y410211D01*
G01X-4725Y408164D02*
Y409069D01*
G01Y409620D02*
Y410526D01*
G01Y405683D02*
Y406589D01*
G01Y404227D02*
Y405132D01*
G01Y401746D02*
Y402652D01*
G01Y400290D02*
Y401195D01*
G01Y393872D02*
Y394778D01*
G01Y396353D02*
Y397258D01*
G01Y397809D02*
Y398715D01*
G01Y392416D02*
Y393321D01*
G01Y394778D02*
Y393872D01*
G01Y393321D02*
Y392416D01*
G01Y398715D02*
Y397809D01*
G01Y397258D02*
Y396353D01*
G01Y402652D02*
Y401746D01*
G01Y401195D02*
Y400290D01*
G01Y406589D02*
Y405683D01*
G01Y405132D02*
Y404227D01*
G01Y409069D02*
Y408164D01*
G01Y410526D02*
Y409620D01*
G01X-6693Y393006D02*
Y392416D01*
G01Y393006D02*
Y392416D01*
G01Y398715D02*
Y398124D01*
G01Y394778D02*
Y394187D01*
G01Y396943D02*
Y396353D01*
G01Y394778D02*
Y394187D01*
G01Y396943D02*
Y396353D01*
G01Y398715D02*
Y398124D01*
G01Y402652D02*
Y402061D01*
G01Y400880D02*
Y400290D01*
G01Y402652D02*
Y402061D01*
G01Y400880D02*
Y400290D01*
G01Y406589D02*
Y405998D01*
G01Y404817D02*
Y404227D01*
G01Y406589D02*
Y405998D01*
G01Y404817D02*
Y404227D01*
G01Y410526D02*
Y409935D01*
G01Y408754D02*
Y408164D01*
G01Y408754D02*
Y408164D01*
G01Y410526D02*
Y409935D01*
G01X-10530Y392697D02*
Y390560D01*
G01Y392697D02*
Y390560D01*
G01Y396634D02*
Y394497D01*
G01Y396634D02*
Y394497D01*
G01Y400571D02*
Y398434D01*
G01Y400571D02*
Y398434D01*
G01Y408445D02*
Y406308D01*
G01Y404508D02*
Y402371D01*
G01Y408445D02*
Y406308D01*
G01Y404508D02*
Y402371D01*
G01Y412382D02*
Y410245D01*
G01Y412382D02*
Y410245D01*
G01X-11842Y410303D02*
Y412323D01*
G01Y406366D02*
Y408386D01*
G01Y402429D02*
Y404449D01*
G01Y398492D02*
Y400512D01*
G01Y394555D02*
Y396575D01*
G01Y390618D02*
Y392638D01*
G01D02*
Y390618D01*
G01Y396575D02*
Y394555D01*
G01Y400512D02*
Y398492D01*
G01Y408386D02*
Y406366D01*
G01Y404449D02*
Y402429D01*
G01Y412323D02*
Y410303D01*
G01X-12280Y410308D02*
Y412318D01*
G01Y406371D02*
Y408381D01*
G01Y402434D02*
Y404444D01*
G01Y398497D02*
Y400507D01*
G01Y394560D02*
Y396570D01*
G01Y390623D02*
Y392633D01*
G01D02*
Y390623D01*
G01Y396570D02*
Y394560D01*
G01Y400507D02*
Y398497D01*
G01Y408381D02*
Y406371D01*
G01Y404444D02*
Y402434D01*
G01Y412318D02*
Y410308D01*
G01X-12992Y394463D02*
Y394148D01*
G01Y393045D02*
Y392730D01*
G01Y398400D02*
Y398085D01*
G01Y396982D02*
Y396667D01*
G01Y402337D02*
Y402022D01*
G01Y400919D02*
Y400604D01*
G01Y406274D02*
Y405959D01*
G01Y404856D02*
Y404541D01*
G01Y410211D02*
Y409896D01*
G01Y408793D02*
Y408478D01*
G01X-23684Y410435D02*
Y412191D01*
G01Y406498D02*
Y408254D01*
G01Y402561D02*
Y404317D01*
G01Y398624D02*
Y400380D01*
G01Y394687D02*
Y396443D01*
G01Y390750D02*
Y392506D01*
G01D02*
Y390750D01*
G01Y396443D02*
Y394687D01*
G01Y400380D02*
Y398624D01*
G01Y408254D02*
Y406498D01*
G01Y404317D02*
Y402561D01*
G01Y412191D02*
Y410435D01*
G01X-4725Y409620D02*
X-6693Y409935D01*
G01X-4725Y409620D02*
X-6693Y409935D01*
G01X-4725Y405683D02*
X-6693Y405998D01*
G01X-4725Y405683D02*
X-6693Y405998D01*
G01X-4725Y401746D02*
X-6693Y402061D01*
G01X-4725Y401746D02*
X-6693Y402061D01*
G01X-4725Y397809D02*
X-6693Y398124D01*
G01X-4725Y397809D02*
X-6693Y398124D01*
G01X0Y396982D02*
X-12992D01*
G01X-9843Y396943D02*
X-6693D01*
G01X-9843D02*
X-6693D01*
G01X-4725Y396786D02*
X-4258D01*
G01X-4725D02*
X-4258D01*
G01X-3150Y396628D02*
X-2196D01*
G01X-3150D02*
X-2196D01*
G01X-4725Y396353D02*
X-6693D01*
G01X-4725D02*
X-6693D01*
G01X-4725Y394778D02*
X-6693D01*
G01X-4725D02*
X-6693D01*
G01X-2196Y394502D02*
X-3150D01*
G01X-2196D02*
X-3150D01*
G01X-4258Y394345D02*
X-4725D01*
G01X-4258D02*
X-4725D01*
G01X-6693Y394187D02*
X-9843D01*
G01X-6693D02*
X-9843D01*
G01X-12992Y394148D02*
X0D01*
G01Y393045D02*
X-12992D01*
G01X-9843Y393006D02*
X-6693D01*
G01X-9843D02*
X-6693D01*
G01X-4725Y392849D02*
X-4258D01*
G01X-4725D02*
X-4258D01*
G01X-3150Y392691D02*
X-2196D01*
G01X-3150D02*
X-2196D01*
G01X-4725Y392416D02*
X-6693D01*
G01X-4725D02*
X-6693D01*
G01X-4725Y390841D02*
X-6693D01*
G01X-4725D02*
X-6693D01*
G01X-2196Y390565D02*
X-3150D01*
G01X-2196D02*
X-3150D01*
G01Y408439D02*
X-3377Y408833D01*
G01X-3150Y408439D02*
X-3377Y408833D01*
G01X-3150Y404502D02*
X-3377Y404896D01*
G01X-3150Y404502D02*
X-3377Y404896D01*
G01X-3150Y400565D02*
X-3377Y400959D01*
G01X-3150Y400565D02*
X-3377Y400959D01*
G01X-4258Y410093D02*
X-3377Y409856D01*
G01X-4258Y410093D02*
X-3377Y409856D01*
G01X-4258Y406156D02*
X-3377Y405919D01*
G01X-4258Y406156D02*
X-3377Y405919D01*
G01X-4258Y402219D02*
X-3377Y401982D01*
G01X-4258Y402219D02*
X-3377Y401982D01*
G01X-4258Y398282D02*
X-3377Y398045D01*
G01X-4258Y398282D02*
X-3377Y398045D01*
G01X-4258Y394345D02*
X-3377Y394108D01*
G01X-4258Y394345D02*
X-3377Y394108D01*
G01X-4725Y393872D02*
X-6693Y394187D01*
G01X-4725Y393872D02*
X-6693Y394187D01*
G01X-3150Y396628D02*
X-3377Y397022D01*
G01X-3150Y396628D02*
X-3377Y397022D01*
G01X-3150Y392691D02*
X-3377Y393085D01*
G01X-3150Y392691D02*
X-3377Y393085D01*
G01X-10630Y410290D02*
X-9843Y409935D01*
G01X-10630Y410290D02*
X-9843Y409935D01*
G01X-10630Y406353D02*
X-9843Y405998D01*
G01X-10630Y406353D02*
X-9843Y405998D01*
G01X-10630Y402416D02*
X-9843Y402061D01*
G01X-10630Y402416D02*
X-9843Y402061D01*
G01X-10630Y398478D02*
X-9843Y398124D01*
G01X-10630Y398478D02*
X-9843Y398124D01*
G01X-10630Y394541D02*
X-9843Y394187D01*
G01X-10630Y394541D02*
X-9843Y394187D01*
G01X-10630Y412337D02*
X-9843Y412691D01*
G01D02*
X-10630Y412337D01*
G01Y424148D02*
X-9843Y424502D01*
G01D02*
X-10630Y424148D01*
G01Y428085D02*
X-9843Y428439D01*
G01D02*
X-10630Y428085D01*
G01Y432022D02*
X-9843Y432376D01*
G01D02*
X-10630Y432022D01*
G01X-3377Y421667D02*
X-3150Y422061D01*
G01X-3377Y421667D02*
X-3150Y422061D01*
G01X-3377Y425604D02*
X-3150Y425998D01*
G01X-3377Y425604D02*
X-3150Y425998D01*
G01X-3377Y429541D02*
X-3150Y429935D01*
G01X-3377Y429541D02*
X-3150Y429935D01*
G01X-3377Y432455D02*
X-4258Y432219D01*
G01X-3377Y432455D02*
X-4258Y432219D01*
G01X-3377Y428518D02*
X-4258Y428282D01*
G01X-3377Y428518D02*
X-4258Y428282D01*
G01X-3377Y424581D02*
X-4258Y424345D01*
G01X-3377Y424581D02*
X-4258Y424345D01*
G01X-3377Y412770D02*
X-4258Y412534D01*
G01X-3377Y412770D02*
X-4258Y412534D01*
G01X-6693Y432376D02*
X-4725Y432691D01*
G01X-6693Y432376D02*
X-4725Y432691D01*
G01X-6693Y428439D02*
X-4725Y428754D01*
G01X-6693Y428439D02*
X-4725Y428754D01*
G01X-6693Y424502D02*
X-4725Y424817D01*
G01X-6693Y424502D02*
X-4725Y424817D01*
G01X-6693Y412691D02*
X-4725Y413006D01*
G01X-6693Y412691D02*
X-4725Y413006D01*
G01X0Y432416D02*
X-12992D01*
G01X-9843Y432376D02*
X-6693D01*
G01X-9843D02*
X-6693D01*
G01X-4725Y432219D02*
X-4258D01*
G01X-4725D02*
X-4258D01*
G01X-3150Y432061D02*
X-2196D01*
G01X-3150D02*
X-2196D01*
G01X-4725Y431786D02*
X-6693D01*
G01X-4725D02*
X-6693D01*
G01X-4725Y430211D02*
X-6693D01*
G01X-4725D02*
X-6693D01*
G01X-2196Y429935D02*
X-3150D01*
G01X-2196D02*
X-3150D01*
G01X-4258Y429778D02*
X-4725D01*
G01X-4258D02*
X-4725D01*
G01X-6693Y429620D02*
X-9843D01*
G01X-6693D02*
X-9843D01*
G01X-12992Y429581D02*
X0D01*
G01Y428478D02*
X-12992D01*
G01X-9843Y428439D02*
X-6693D01*
G01X-9843D02*
X-6693D01*
G01X-4725Y428282D02*
X-4258D01*
G01X-4725D02*
X-4258D01*
G01X-3150Y428124D02*
X-2196D01*
G01X-3150D02*
X-2196D01*
G01X-4725Y427849D02*
X-6693D01*
G01X-4725D02*
X-6693D01*
G01X-4725Y426274D02*
X-6693D01*
G01X-4725D02*
X-6693D01*
G01X-2196Y425998D02*
X-3150D01*
G01X-2196D02*
X-3150D01*
G01X-4258Y425841D02*
X-4725D01*
G01X-4258D02*
X-4725D01*
G01X-6693Y425683D02*
X-9843D01*
G01X-6693D02*
X-9843D01*
G01X-12992Y425644D02*
X0D01*
G01Y424541D02*
X-12992D01*
G01X-9843Y424502D02*
X-6693D01*
G01X-9843D02*
X-6693D01*
G01X-4725Y424345D02*
X-4258D01*
G01X-4725D02*
X-4258D01*
G01X-3150Y424187D02*
X-2196D01*
G01X-3150D02*
X-2196D01*
G01X-4725Y423912D02*
X-6693D01*
G01X-4725D02*
X-6693D01*
G01X-4725Y422337D02*
X-6693D01*
G01X-4725D02*
X-6693D01*
G01X-2196Y422061D02*
X-3150D01*
G01X-2196D02*
X-3150D01*
G01X-4258Y421904D02*
X-4725D01*
G01X-4258D02*
X-4725D01*
G01X-6693Y421746D02*
X-9843D01*
G01X-6693D02*
X-9843D01*
G01X-12992Y421707D02*
X0D01*
G01Y412730D02*
X-12992D01*
G01X-9843Y412691D02*
X-6693D01*
G01X-9843D02*
X-6693D01*
G01X-4725Y412534D02*
X-4258D01*
G01X-4725D02*
X-4258D01*
G01X-3150Y412376D02*
X-2196D01*
G01X-3150D02*
X-2196D01*
G01X-4725Y412101D02*
X-6693D01*
G01X-4725D02*
X-6693D01*
G01X-3756Y424227D02*
Y422022D01*
G01Y428164D02*
Y425959D01*
G01Y432101D02*
Y429896D01*
G01X-4725Y431786D02*
Y432691D01*
G01Y427849D02*
Y428754D01*
G01Y429305D02*
Y430211D01*
G01Y423912D02*
Y424817D01*
G01Y425368D02*
Y426274D01*
G01Y421431D02*
Y422337D01*
G01Y412101D02*
Y413006D01*
G01D02*
Y412101D01*
G01Y422337D02*
Y421431D01*
G01Y426274D02*
Y425368D01*
G01Y424817D02*
Y423912D01*
G01Y430211D02*
Y429305D01*
G01Y428754D02*
Y427849D01*
G01Y432691D02*
Y431786D01*
G01X-6693Y412691D02*
Y412101D01*
G01Y412691D02*
Y412101D01*
G01Y422337D02*
Y421746D01*
G01Y422337D02*
Y421746D01*
G01Y426274D02*
Y425683D01*
G01Y424502D02*
Y423912D01*
G01Y424502D02*
Y423912D01*
G01Y426274D02*
Y425683D01*
G01Y430211D02*
Y429620D01*
G01Y428439D02*
Y427849D01*
G01Y428439D02*
Y427849D01*
G01Y430211D02*
Y429620D01*
G01Y432376D02*
Y431786D01*
G01Y432376D02*
Y431786D01*
G01X-8898Y420723D02*
Y702947D01*
G01X-10530Y424193D02*
Y422056D01*
G01Y424193D02*
Y422056D01*
G01Y428130D02*
Y425993D01*
G01Y428130D02*
Y425993D01*
G01Y432067D02*
Y429930D01*
G01Y432067D02*
Y429930D01*
G01X-11842Y429988D02*
Y432008D01*
G01Y426051D02*
Y428071D01*
G01Y422114D02*
Y424134D01*
G01D02*
Y422114D01*
G01Y428071D02*
Y426051D01*
G01Y432008D02*
Y429988D01*
G01X-12280Y429993D02*
Y432003D01*
G01Y426056D02*
Y428066D01*
G01Y422119D02*
Y424129D01*
G01D02*
Y422119D01*
G01Y432003D02*
Y429993D01*
G01Y428066D02*
Y426056D01*
G01X-12992Y412730D02*
Y412416D01*
G01Y422022D02*
Y421707D01*
G01Y425959D02*
Y425644D01*
G01Y424541D02*
Y424227D01*
G01Y428478D02*
Y428164D01*
G01Y429896D02*
Y429581D01*
G01Y432416D02*
Y432101D01*
G01X-23684Y426183D02*
Y427940D01*
G01Y430120D02*
Y431877D01*
G01Y422246D02*
Y424003D01*
G01D02*
Y422246D01*
G01Y431877D02*
Y430120D01*
G01Y427940D02*
Y426183D01*
G01X-4725Y429305D02*
X-6693Y429620D01*
G01X-4725Y429305D02*
X-6693Y429620D01*
G01X-4725Y425368D02*
X-6693Y425683D01*
G01X-4725Y425368D02*
X-6693Y425683D01*
G01X-4725Y421431D02*
X-6693Y421746D01*
G01X-4725Y421431D02*
X-6693Y421746D01*
G01X-3150Y432061D02*
X-3377Y432455D01*
G01X-3150Y432061D02*
X-3377Y432455D01*
G01X-3150Y428124D02*
X-3377Y428518D01*
G01X-3150Y428124D02*
X-3377Y428518D01*
G01X-3150Y424187D02*
X-3377Y424581D01*
G01X-3150Y424187D02*
X-3377Y424581D01*
G01X-3150Y412376D02*
X-3377Y412770D01*
G01X-3150Y412376D02*
X-3377Y412770D01*
G01X-10630Y429975D02*
X-9843Y429620D01*
G01X-10630Y429975D02*
X-9843Y429620D01*
G01X-10630Y426038D02*
X-9843Y425683D01*
G01X-10630Y426038D02*
X-9843Y425683D01*
G01X-10630Y422101D02*
X-9843Y421746D01*
G01X-10630Y422101D02*
X-9843Y421746D01*
G01X-4258Y429778D02*
X-3377Y429541D01*
G01X-4258Y429778D02*
X-3377Y429541D01*
G01X-4258Y425841D02*
X-3377Y425604D01*
G01X-4258Y425841D02*
X-3377Y425604D01*
G01X-4258Y421904D02*
X-3377Y421667D01*
G01X-4258Y421904D02*
X-3377Y421667D01*
G01X-10630Y435959D02*
X-9843Y436313D01*
G01D02*
X-10630Y435959D01*
G01Y439896D02*
X-9843Y440250D01*
G01D02*
X-10630Y439896D01*
G01Y443833D02*
X-9843Y444187D01*
G01D02*
X-10630Y443833D01*
G01Y447770D02*
X-9843Y448124D01*
G01D02*
X-10630Y447770D01*
G01Y451707D02*
X-9843Y452061D01*
G01D02*
X-10630Y451707D01*
G01X-3377Y433478D02*
X-3150Y433872D01*
G01X-3377Y433478D02*
X-3150Y433872D01*
G01X-3377Y437416D02*
X-3150Y437809D01*
G01X-3377Y437416D02*
X-3150Y437809D01*
G01X-3377Y441353D02*
X-3150Y441746D01*
G01X-3377Y441353D02*
X-3150Y441746D01*
G01X-3377Y445290D02*
X-3150Y445683D01*
G01X-3377Y445290D02*
X-3150Y445683D01*
G01X-3377Y449227D02*
X-3150Y449620D01*
G01X-3377Y449227D02*
X-3150Y449620D01*
G01X-3377Y453164D02*
X-3150Y453557D01*
G01X-3377Y453164D02*
X-3150Y453557D01*
G01X-3377Y452140D02*
X-4258Y451904D01*
G01X-3377Y452140D02*
X-4258Y451904D01*
G01X-3377Y448203D02*
X-4258Y447967D01*
G01X-3377Y448203D02*
X-4258Y447967D01*
G01X-3377Y444266D02*
X-4258Y444030D01*
G01X-3377Y444266D02*
X-4258Y444030D01*
G01X-3377Y440329D02*
X-4258Y440093D01*
G01X-3377Y440329D02*
X-4258Y440093D01*
G01X-3377Y436392D02*
X-4258Y436156D01*
G01X-3377Y436392D02*
X-4258Y436156D01*
G01X-6693Y452061D02*
X-4725Y452376D01*
G01X-6693Y452061D02*
X-4725Y452376D01*
G01X-6693Y448124D02*
X-4725Y448439D01*
G01X-6693Y448124D02*
X-4725Y448439D01*
G01X-6693Y444187D02*
X-4725Y444502D01*
G01X-6693Y444187D02*
X-4725Y444502D01*
G01X-6693Y440250D02*
X-4725Y440565D01*
G01X-6693Y440250D02*
X-4725Y440565D01*
G01X-6693Y436313D02*
X-4725Y436628D01*
G01X-6693Y436313D02*
X-4725Y436628D01*
G01Y453833D02*
X-6693D01*
G01X-4725D02*
X-6693D01*
G01X-2196Y453557D02*
X-3150D01*
G01X-2196D02*
X-3150D01*
G01X-4258Y453400D02*
X-4725D01*
G01X-4258D02*
X-4725D01*
G01X-6693Y453242D02*
X-9843D01*
G01X-6693D02*
X-9843D01*
G01X-12992Y453203D02*
X0D01*
G01Y452101D02*
X-12992D01*
G01X-9843Y452061D02*
X-6693D01*
G01X-9843D02*
X-6693D01*
G01X-4725Y451904D02*
X-4258D01*
G01X-4725D02*
X-4258D01*
G01X-3150Y451746D02*
X-2196D01*
G01X-3150D02*
X-2196D01*
G01X-4725Y451471D02*
X-6693D01*
G01X-4725D02*
X-6693D01*
G01X-4725Y449896D02*
X-6693D01*
G01X-4725D02*
X-6693D01*
G01X-2196Y449620D02*
X-3150D01*
G01X-2196D02*
X-3150D01*
G01X-4258Y449463D02*
X-4725D01*
G01X-4258D02*
X-4725D01*
G01X-6693Y449305D02*
X-9843D01*
G01X-6693D02*
X-9843D01*
G01X-12992Y449266D02*
X0D01*
G01Y448164D02*
X-12992D01*
G01X-9843Y448124D02*
X-6693D01*
G01X-9843D02*
X-6693D01*
G01X-4725Y447967D02*
X-4258D01*
G01X-4725D02*
X-4258D01*
G01X-3150Y447809D02*
X-2196D01*
G01X-3150D02*
X-2196D01*
G01X-4725Y447534D02*
X-6693D01*
G01X-4725D02*
X-6693D01*
G01X-4725Y445959D02*
X-6693D01*
G01X-4725D02*
X-6693D01*
G01X-2196Y445683D02*
X-3150D01*
G01X-2196D02*
X-3150D01*
G01X-4258Y445526D02*
X-4725D01*
G01X-4258D02*
X-4725D01*
G01X-6693Y445368D02*
X-9843D01*
G01X-6693D02*
X-9843D01*
G01X-12992Y445329D02*
X0D01*
G01Y444227D02*
X-12992D01*
G01X-9843Y444187D02*
X-6693D01*
G01X-9843D02*
X-6693D01*
G01X-4725Y444030D02*
X-4258D01*
G01X-4725D02*
X-4258D01*
G01X-3150Y443872D02*
X-2196D01*
G01X-3150D02*
X-2196D01*
G01X-4725Y443597D02*
X-6693D01*
G01X-4725D02*
X-6693D01*
G01X-4725Y442022D02*
X-6693D01*
G01X-4725D02*
X-6693D01*
G01X-2196Y441746D02*
X-3150D01*
G01X-2196D02*
X-3150D01*
G01X-4258Y441589D02*
X-4725D01*
G01X-4258D02*
X-4725D01*
G01X-6693Y441431D02*
X-9843D01*
G01X-6693D02*
X-9843D01*
G01X-12992Y441392D02*
X0D01*
G01Y440290D02*
X-12992D01*
G01X-9843Y440250D02*
X-6693D01*
G01X-9843D02*
X-6693D01*
G01X-4725Y440093D02*
X-4258D01*
G01X-4725D02*
X-4258D01*
G01X-3150Y439935D02*
X-2196D01*
G01X-3150D02*
X-2196D01*
G01X-4725Y439660D02*
X-6693D01*
G01X-4725D02*
X-6693D01*
G01X-4725Y438085D02*
X-6693D01*
G01X-4725D02*
X-6693D01*
G01X-2196Y437809D02*
X-3150D01*
G01X-2196D02*
X-3150D01*
G01X-4258Y437652D02*
X-4725D01*
G01X-4258D02*
X-4725D01*
G01X-6693Y437494D02*
X-9843D01*
G01X-6693D02*
X-9843D01*
G01X-12992Y437455D02*
X0D01*
G01Y436353D02*
X-12992D01*
G01X-9843Y436313D02*
X-6693D01*
G01X-9843D02*
X-6693D01*
G01X-4725Y436156D02*
X-4258D01*
G01X-4725D02*
X-4258D01*
G01X-3150Y435998D02*
X-2196D01*
G01X-3150D02*
X-2196D01*
G01X-4725Y435723D02*
X-6693D01*
G01X-4725D02*
X-6693D01*
G01X-4725Y434148D02*
X-6693D01*
G01X-4725D02*
X-6693D01*
G01X-2196Y433872D02*
X-3150D01*
G01X-2196D02*
X-3150D01*
G01X-4258Y433715D02*
X-4725D01*
G01X-4258D02*
X-4725D01*
G01X-6693Y433557D02*
X-9843D01*
G01X-6693D02*
X-9843D01*
G01X-12992Y433518D02*
X0D01*
G01X-3756Y436038D02*
Y433833D01*
G01Y439975D02*
Y437770D01*
G01Y443912D02*
Y441707D01*
G01Y447849D02*
Y445644D01*
G01Y451786D02*
Y449581D01*
G01Y455723D02*
Y453518D01*
G01X-4725Y451471D02*
Y452376D01*
G01Y452927D02*
Y453833D01*
G01Y447534D02*
Y448439D01*
G01Y448990D02*
Y449896D01*
G01Y441116D02*
Y442022D01*
G01Y443597D02*
Y444502D01*
G01Y445053D02*
Y445959D01*
G01Y437179D02*
Y438085D01*
G01Y439660D02*
Y440565D01*
G01Y433242D02*
Y434148D01*
G01Y435723D02*
Y436628D01*
G01Y434148D02*
Y433242D01*
G01Y436628D02*
Y435723D01*
G01Y438085D02*
Y437179D01*
G01Y440565D02*
Y439660D01*
G01Y445959D02*
Y445053D01*
G01Y442022D02*
Y441116D01*
G01Y444502D02*
Y443597D01*
G01Y449896D02*
Y448990D01*
G01Y448439D02*
Y447534D01*
G01Y452376D02*
Y451471D01*
G01Y453833D02*
Y452927D01*
G01X-6693Y434148D02*
Y433557D01*
G01Y436313D02*
Y435723D01*
G01Y434148D02*
Y433557D01*
G01Y436313D02*
Y435723D01*
G01Y438085D02*
Y437494D01*
G01Y440250D02*
Y439660D01*
G01Y438085D02*
Y437494D01*
G01Y440250D02*
Y439660D01*
G01Y445959D02*
Y445368D01*
G01Y442022D02*
Y441431D01*
G01Y444187D02*
Y443597D01*
G01Y442022D02*
Y441431D01*
G01Y444187D02*
Y443597D01*
G01Y445959D02*
Y445368D01*
G01Y449896D02*
Y449305D01*
G01Y448124D02*
Y447534D01*
G01Y448124D02*
Y447534D01*
G01Y449896D02*
Y449305D01*
G01Y452061D02*
Y451471D01*
G01Y453833D02*
Y453242D01*
G01Y452061D02*
Y451471D01*
G01Y453833D02*
Y453242D01*
G01X-10530Y436004D02*
Y433867D01*
G01Y436004D02*
Y433867D01*
G01Y439941D02*
Y437804D01*
G01Y439941D02*
Y437804D01*
G01Y443878D02*
Y441741D01*
G01Y443878D02*
Y441741D01*
G01Y447815D02*
Y445678D01*
G01Y447815D02*
Y445678D01*
G01Y451752D02*
Y449615D01*
G01Y451752D02*
Y449615D01*
G01Y455689D02*
Y453552D01*
G01Y455689D02*
Y453552D01*
G01X-11842Y453610D02*
Y455630D01*
G01Y449673D02*
Y451693D01*
G01Y445736D02*
Y447756D01*
G01Y441799D02*
Y443819D01*
G01Y437862D02*
Y439882D01*
G01Y433925D02*
Y435945D01*
G01D02*
Y433925D01*
G01Y439882D02*
Y437862D01*
G01Y443819D02*
Y441799D01*
G01Y447756D02*
Y445736D01*
G01Y451693D02*
Y449673D01*
G01Y455630D02*
Y453610D01*
G01X-12280Y453615D02*
Y455625D01*
G01Y449678D02*
Y451688D01*
G01Y445741D02*
Y447751D01*
G01Y441804D02*
Y443814D01*
G01Y437867D02*
Y439877D01*
G01Y433930D02*
Y435940D01*
G01D02*
Y433930D01*
G01Y439877D02*
Y437867D01*
G01Y443814D02*
Y441804D01*
G01Y447751D02*
Y445741D01*
G01Y451688D02*
Y449678D01*
G01Y455625D02*
Y453615D01*
G01X-12992Y436353D02*
Y436038D01*
G01Y433833D02*
Y433518D01*
G01Y440290D02*
Y439975D01*
G01Y437770D02*
Y437455D01*
G01Y444227D02*
Y443912D01*
G01Y441707D02*
Y441392D01*
G01Y445644D02*
Y445329D01*
G01Y448164D02*
Y447849D01*
G01Y449581D02*
Y449266D01*
G01Y452101D02*
Y451786D01*
G01Y453518D02*
Y453203D01*
G01X-23684Y453742D02*
Y455499D01*
G01Y449805D02*
Y451562D01*
G01Y445868D02*
Y447625D01*
G01Y441931D02*
Y443688D01*
G01Y437994D02*
Y439751D01*
G01Y434057D02*
Y435814D01*
G01D02*
Y434057D01*
G01Y439751D02*
Y437994D01*
G01Y443688D02*
Y441931D01*
G01Y447625D02*
Y445868D01*
G01Y451562D02*
Y449805D01*
G01Y455499D02*
Y453742D01*
G01X-4258Y453400D02*
X-3377Y453164D01*
G01X-4258Y453400D02*
X-3377Y453164D01*
G01X-4258Y449463D02*
X-3377Y449227D01*
G01X-4258Y449463D02*
X-3377Y449227D01*
G01X-4258Y445526D02*
X-3377Y445290D01*
G01X-4258Y445526D02*
X-3377Y445290D01*
G01X-4258Y441589D02*
X-3377Y441353D01*
G01X-4258Y441589D02*
X-3377Y441353D01*
G01X-4258Y437652D02*
X-3377Y437416D01*
G01X-4258Y437652D02*
X-3377Y437416D01*
G01X-4725Y452927D02*
X-6693Y453242D01*
G01X-4725Y452927D02*
X-6693Y453242D01*
G01X-4725Y448990D02*
X-6693Y449305D01*
G01X-4725Y448990D02*
X-6693Y449305D01*
G01X-4725Y445053D02*
X-6693Y445368D01*
G01X-4725Y445053D02*
X-6693Y445368D01*
G01X-4725Y441116D02*
X-6693Y441431D01*
G01X-4725Y441116D02*
X-6693Y441431D01*
G01X-4725Y437179D02*
X-6693Y437494D01*
G01X-4725Y437179D02*
X-6693Y437494D01*
G01X-4725Y433242D02*
X-6693Y433557D01*
G01X-4725Y433242D02*
X-6693Y433557D01*
G01X-3150Y451746D02*
X-3377Y452140D01*
G01X-3150Y451746D02*
X-3377Y452140D01*
G01X-3150Y447809D02*
X-3377Y448203D01*
G01X-3150Y447809D02*
X-3377Y448203D01*
G01X-3150Y443872D02*
X-3377Y444266D01*
G01X-3150Y443872D02*
X-3377Y444266D01*
G01X-3150Y439935D02*
X-3377Y440329D01*
G01X-3150Y439935D02*
X-3377Y440329D01*
G01X-3150Y435998D02*
X-3377Y436392D01*
G01X-3150Y435998D02*
X-3377Y436392D01*
G01X-10630Y453597D02*
X-9843Y453242D01*
G01X-10630Y453597D02*
X-9843Y453242D01*
G01X-10630Y449660D02*
X-9843Y449305D01*
G01X-10630Y449660D02*
X-9843Y449305D01*
G01X-10630Y445723D02*
X-9843Y445368D01*
G01X-10630Y445723D02*
X-9843Y445368D01*
G01X-10630Y441786D02*
X-9843Y441431D01*
G01X-10630Y441786D02*
X-9843Y441431D01*
G01X-10630Y437849D02*
X-9843Y437494D01*
G01X-10630Y437849D02*
X-9843Y437494D01*
G01X-10630Y433912D02*
X-9843Y433557D01*
G01X-10630Y433912D02*
X-9843Y433557D01*
G01X-4258Y433715D02*
X-3377Y433478D01*
G01X-4258Y433715D02*
X-3377Y433478D01*
G01X-10630Y455644D02*
X-9843Y455998D01*
G01D02*
X-10630Y455644D01*
G01Y459581D02*
X-9843Y459935D01*
G01D02*
X-10630Y459581D01*
G01Y463518D02*
X-9843Y463872D01*
G01D02*
X-10630Y463518D01*
G01Y467455D02*
X-9843Y467809D01*
G01D02*
X-10630Y467455D01*
G01Y471392D02*
X-9843Y471746D01*
G01D02*
X-10630Y471392D01*
G01X-3377Y457101D02*
X-3150Y457494D01*
G01X-3377Y457101D02*
X-3150Y457494D01*
G01X-3377Y461038D02*
X-3150Y461431D01*
G01X-3377Y461038D02*
X-3150Y461431D01*
G01X-3377Y464975D02*
X-3150Y465368D01*
G01X-3377Y464975D02*
X-3150Y465368D01*
G01X-3377Y468912D02*
X-3150Y469305D01*
G01X-3377Y468912D02*
X-3150Y469305D01*
G01X-3377Y472849D02*
X-3150Y473242D01*
G01X-3377Y472849D02*
X-3150Y473242D01*
G01X-6693Y471746D02*
X-4725Y472061D01*
G01X-6693Y471746D02*
X-4725Y472061D01*
G01X-6693Y467809D02*
X-4725Y468124D01*
G01X-6693Y467809D02*
X-4725Y468124D01*
G01X-6693Y463872D02*
X-4725Y464187D01*
G01X-6693Y463872D02*
X-4725Y464187D01*
G01X-6693Y459935D02*
X-4725Y460250D01*
G01X-6693Y459935D02*
X-4725Y460250D01*
G01X-3377Y471825D02*
X-4258Y471589D01*
G01X-3377Y471825D02*
X-4258Y471589D01*
G01X-3377Y467888D02*
X-4258Y467652D01*
G01X-3377Y467888D02*
X-4258Y467652D01*
G01X-3377Y463951D02*
X-4258Y463715D01*
G01X-3377Y463951D02*
X-4258Y463715D01*
G01X-3377Y460014D02*
X-4258Y459778D01*
G01X-3377Y460014D02*
X-4258Y459778D01*
G01X-3377Y456077D02*
X-4258Y455841D01*
G01X-3377Y456077D02*
X-4258Y455841D01*
G01X-4725Y475093D02*
X-6693D01*
G01X-4725D02*
X-6693D01*
G01X-4725Y473518D02*
X-6693D01*
G01X-4725D02*
X-6693D01*
G01X-2196Y473242D02*
X-3150D01*
G01X-2196D02*
X-3150D01*
G01X-6693Y455998D02*
X-4725Y456313D01*
G01X-6693Y455998D02*
X-4725Y456313D01*
G01X-4258Y473085D02*
X-4725D01*
G01X-4258D02*
X-4725D01*
G01X-6693Y472927D02*
X-9843D01*
G01X-6693D02*
X-9843D01*
G01X-12992Y472888D02*
X0D01*
G01Y471786D02*
X-12992D01*
G01X-9843Y471746D02*
X-6693D01*
G01X-9843D02*
X-6693D01*
G01X-4725Y471589D02*
X-4258D01*
G01X-4725D02*
X-4258D01*
G01X-3150Y471431D02*
X-2196D01*
G01X-3150D02*
X-2196D01*
G01X-4725Y471156D02*
X-6693D01*
G01X-4725D02*
X-6693D01*
G01X-4725Y469581D02*
X-6693D01*
G01X-4725D02*
X-6693D01*
G01X-2196Y469305D02*
X-3150D01*
G01X-2196D02*
X-3150D01*
G01X-4258Y469148D02*
X-4725D01*
G01X-4258D02*
X-4725D01*
G01X-6693Y468990D02*
X-9843D01*
G01X-6693D02*
X-9843D01*
G01X-12992Y468951D02*
X0D01*
G01Y467849D02*
X-12992D01*
G01X-9843Y467809D02*
X-6693D01*
G01X-9843D02*
X-6693D01*
G01X-4725Y467652D02*
X-4258D01*
G01X-4725D02*
X-4258D01*
G01X-3150Y467494D02*
X-2196D01*
G01X-3150D02*
X-2196D01*
G01X-4725Y467219D02*
X-6693D01*
G01X-4725D02*
X-6693D01*
G01X-4725Y465644D02*
X-6693D01*
G01X-4725D02*
X-6693D01*
G01X-2196Y465368D02*
X-3150D01*
G01X-2196D02*
X-3150D01*
G01X-4258Y465211D02*
X-4725D01*
G01X-4258D02*
X-4725D01*
G01X-6693Y465053D02*
X-9843D01*
G01X-6693D02*
X-9843D01*
G01X-12992Y465014D02*
X0D01*
G01Y463912D02*
X-12992D01*
G01X-9843Y463872D02*
X-6693D01*
G01X-9843D02*
X-6693D01*
G01X-4725Y463715D02*
X-4258D01*
G01X-4725D02*
X-4258D01*
G01X-3150Y463557D02*
X-2196D01*
G01X-3150D02*
X-2196D01*
G01X-4725Y463282D02*
X-6693D01*
G01X-4725D02*
X-6693D01*
G01X-4725Y461707D02*
X-6693D01*
G01X-4725D02*
X-6693D01*
G01X-2196Y461431D02*
X-3150D01*
G01X-2196D02*
X-3150D01*
G01X-4258Y461274D02*
X-4725D01*
G01X-4258D02*
X-4725D01*
G01X-6693Y461116D02*
X-9843D01*
G01X-6693D02*
X-9843D01*
G01X-12992Y461077D02*
X0D01*
G01Y459975D02*
X-12992D01*
G01X-9843Y459935D02*
X-6693D01*
G01X-9843D02*
X-6693D01*
G01X-4725Y459778D02*
X-4258D01*
G01X-4725D02*
X-4258D01*
G01X-3150Y459620D02*
X-2196D01*
G01X-3150D02*
X-2196D01*
G01X-4725Y459345D02*
X-6693D01*
G01X-4725D02*
X-6693D01*
G01X-4725Y457770D02*
X-6693D01*
G01X-4725D02*
X-6693D01*
G01X-2196Y457494D02*
X-3150D01*
G01X-2196D02*
X-3150D01*
G01X-4258Y457337D02*
X-4725D01*
G01X-4258D02*
X-4725D01*
G01X-6693Y457179D02*
X-9843D01*
G01X-6693D02*
X-9843D01*
G01X-12992Y457140D02*
X0D01*
G01Y456038D02*
X-12992D01*
G01X-9843Y455998D02*
X-6693D01*
G01X-9843D02*
X-6693D01*
G01X-4725Y455841D02*
X-4258D01*
G01X-4725D02*
X-4258D01*
G01X-3150Y455683D02*
X-2196D01*
G01X-3150D02*
X-2196D01*
G01X-4725Y455408D02*
X-6693D01*
G01X-4725D02*
X-6693D01*
G01X-3756Y459660D02*
Y457455D01*
G01Y463597D02*
Y461392D01*
G01Y467534D02*
Y465329D01*
G01Y471471D02*
Y469266D01*
G01Y475408D02*
Y473203D01*
G01X-4725Y475093D02*
Y475998D01*
G01Y468675D02*
Y469581D01*
G01Y471156D02*
Y472061D01*
G01Y472612D02*
Y473518D01*
G01Y464738D02*
Y465644D01*
G01Y467219D02*
Y468124D01*
G01Y459345D02*
Y460250D01*
G01Y460801D02*
Y461707D01*
G01Y463282D02*
Y464187D01*
G01Y455408D02*
Y456313D01*
G01Y456864D02*
Y457770D01*
G01Y456313D02*
Y455408D01*
G01Y457770D02*
Y456864D01*
G01Y460250D02*
Y459345D01*
G01Y461707D02*
Y460801D01*
G01Y464187D02*
Y463282D01*
G01Y465644D02*
Y464738D01*
G01Y468124D02*
Y467219D01*
G01Y469581D02*
Y468675D01*
G01Y472061D02*
Y471156D01*
G01Y473518D02*
Y472612D01*
G01Y475998D02*
Y475093D01*
G01X-6693Y455998D02*
Y455408D01*
G01Y457770D02*
Y457179D01*
G01Y459935D02*
Y459345D01*
G01Y455998D02*
Y455408D01*
G01Y457770D02*
Y457179D01*
G01Y459935D02*
Y459345D01*
G01Y461707D02*
Y461116D01*
G01Y463872D02*
Y463282D01*
G01Y461707D02*
Y461116D01*
G01Y463872D02*
Y463282D01*
G01Y465644D02*
Y465053D01*
G01Y467809D02*
Y467219D01*
G01Y465644D02*
Y465053D01*
G01Y467809D02*
Y467219D01*
G01Y469581D02*
Y468990D01*
G01Y471746D02*
Y471156D01*
G01Y473518D02*
Y472927D01*
G01Y469581D02*
Y468990D01*
G01Y471746D02*
Y471156D01*
G01Y473518D02*
Y472927D01*
G01Y475683D02*
Y475093D01*
G01Y475683D02*
Y475093D01*
G01X-10530Y459626D02*
Y457489D01*
G01Y459626D02*
Y457489D01*
G01Y463563D02*
Y461426D01*
G01Y463563D02*
Y461426D01*
G01Y467500D02*
Y465363D01*
G01Y467500D02*
Y465363D01*
G01Y471437D02*
Y469300D01*
G01Y471437D02*
Y469300D01*
G01Y475374D02*
Y473237D01*
G01Y475374D02*
Y473237D01*
G01X-11842Y473295D02*
Y475316D01*
G01Y469358D02*
Y471378D01*
G01Y465421D02*
Y467441D01*
G01Y461484D02*
Y463504D01*
G01Y457547D02*
Y459567D01*
G01D02*
Y457547D01*
G01Y463504D02*
Y461484D01*
G01Y467441D02*
Y465421D01*
G01Y471378D02*
Y469358D01*
G01Y475316D02*
Y473295D01*
G01X-12280Y473300D02*
Y475310D01*
G01Y469363D02*
Y471373D01*
G01Y465426D02*
Y467436D01*
G01Y461489D02*
Y463499D01*
G01Y457552D02*
Y459562D01*
G01D02*
Y457552D01*
G01Y463499D02*
Y461489D01*
G01Y467436D02*
Y465426D01*
G01Y471373D02*
Y469363D01*
G01Y475310D02*
Y473300D01*
G01X-12992Y456038D02*
Y455723D01*
G01Y459975D02*
Y459660D01*
G01Y457455D02*
Y457140D01*
G01Y463912D02*
Y463597D01*
G01Y461392D02*
Y461077D01*
G01Y467849D02*
Y467534D01*
G01Y465329D02*
Y465014D01*
G01Y469266D02*
Y468951D01*
G01Y471786D02*
Y471471D01*
G01Y473203D02*
Y472888D01*
G01X-23684Y473427D02*
Y475184D01*
G01Y469490D02*
Y471247D01*
G01Y465553D02*
Y467310D01*
G01Y461616D02*
Y463373D01*
G01Y457679D02*
Y459436D01*
G01D02*
Y457679D01*
G01Y463373D02*
Y461616D01*
G01Y467310D02*
Y465553D01*
G01Y471247D02*
Y469490D01*
G01Y475184D02*
Y473427D01*
G01X-4258Y473085D02*
X-3377Y472849D01*
G01X-4258Y473085D02*
X-3377Y472849D01*
G01X-4258Y469148D02*
X-3377Y468912D01*
G01X-4258Y469148D02*
X-3377Y468912D01*
G01X-4258Y465211D02*
X-3377Y464975D01*
G01X-4258Y465211D02*
X-3377Y464975D01*
G01X-4258Y461274D02*
X-3377Y461038D01*
G01X-4258Y461274D02*
X-3377Y461038D01*
G01X-4258Y457337D02*
X-3377Y457101D01*
G01X-4258Y457337D02*
X-3377Y457101D01*
G01X-4725Y472612D02*
X-6693Y472927D01*
G01X-4725Y472612D02*
X-6693Y472927D01*
G01X-4725Y468675D02*
X-6693Y468990D01*
G01X-4725Y468675D02*
X-6693Y468990D01*
G01X-4725Y464738D02*
X-6693Y465053D01*
G01X-4725Y464738D02*
X-6693Y465053D01*
G01X-4725Y460801D02*
X-6693Y461116D01*
G01X-4725Y460801D02*
X-6693Y461116D01*
G01X-4725Y456864D02*
X-6693Y457179D01*
G01X-4725Y456864D02*
X-6693Y457179D01*
G01X-3150Y471431D02*
X-3377Y471825D01*
G01X-3150Y471431D02*
X-3377Y471825D01*
G01X-3150Y467494D02*
X-3377Y467888D01*
G01X-3150Y467494D02*
X-3377Y467888D01*
G01X-3150Y463557D02*
X-3377Y463951D01*
G01X-3150Y463557D02*
X-3377Y463951D01*
G01X-3150Y459620D02*
X-3377Y460014D01*
G01X-3150Y459620D02*
X-3377Y460014D01*
G01X-3150Y455683D02*
X-3377Y456077D01*
G01X-3150Y455683D02*
X-3377Y456077D01*
G01X-10630Y473282D02*
X-9843Y472927D01*
G01X-10630Y473282D02*
X-9843Y472927D01*
G01X-10630Y469345D02*
X-9843Y468990D01*
G01X-10630Y469345D02*
X-9843Y468990D01*
G01X-10630Y465408D02*
X-9843Y465053D01*
G01X-10630Y465408D02*
X-9843Y465053D01*
G01X-10630Y461471D02*
X-9843Y461116D01*
G01X-10630Y461471D02*
X-9843Y461116D01*
G01X-10630Y457534D02*
X-9843Y457179D01*
G01X-10630Y457534D02*
X-9843Y457179D01*
G01X-10630Y475329D02*
X-9843Y475683D01*
G01D02*
X-10630Y475329D01*
G01Y479266D02*
X-9843Y479620D01*
G01D02*
X-10630Y479266D01*
G01Y483203D02*
X-9843Y483557D01*
G01D02*
X-10630Y483203D01*
G01Y487140D02*
X-9843Y487494D01*
G01D02*
X-10630Y487140D01*
G01Y491077D02*
X-9843Y491431D01*
G01D02*
X-10630Y491077D01*
G01Y495014D02*
X-9843Y495368D01*
G01D02*
X-10630Y495014D01*
G01X-3377Y476786D02*
X-3150Y477179D01*
G01X-3377Y476786D02*
X-3150Y477179D01*
G01X-3377Y480723D02*
X-3150Y481116D01*
G01X-3377Y480723D02*
X-3150Y481116D01*
G01X-3377Y484660D02*
X-3150Y485053D01*
G01X-3377Y484660D02*
X-3150Y485053D01*
G01X-3377Y488597D02*
X-3150Y488990D01*
G01X-3377Y488597D02*
X-3150Y488990D01*
G01X-3377Y492534D02*
X-3150Y492927D01*
G01X-3377Y492534D02*
X-3150Y492927D01*
G01X-3377Y495447D02*
X-4258Y495211D01*
G01X-3377Y495447D02*
X-4258Y495211D01*
G01X-3377Y491510D02*
X-4258Y491274D01*
G01X-3377Y491510D02*
X-4258Y491274D01*
G01X-3377Y487573D02*
X-4258Y487337D01*
G01X-3377Y487573D02*
X-4258Y487337D01*
G01X-3377Y483636D02*
X-4258Y483400D01*
G01X-3377Y483636D02*
X-4258Y483400D01*
G01X-3377Y479699D02*
X-4258Y479463D01*
G01X-3377Y479699D02*
X-4258Y479463D01*
G01X-3377Y475762D02*
X-4258Y475526D01*
G01X-3377Y475762D02*
X-4258Y475526D01*
G01X-6693Y495368D02*
X-4725Y495683D01*
G01X-6693Y495368D02*
X-4725Y495683D01*
G01X-6693Y491431D02*
X-4725Y491746D01*
G01X-6693Y491431D02*
X-4725Y491746D01*
G01X-6693Y487494D02*
X-4725Y487809D01*
G01X-6693Y487494D02*
X-4725Y487809D01*
G01X-6693Y483557D02*
X-4725Y483872D01*
G01X-6693Y483557D02*
X-4725Y483872D01*
G01X-6693Y479620D02*
X-4725Y479935D01*
G01X-6693Y479620D02*
X-4725Y479935D01*
G01X-6693Y475683D02*
X-4725Y475998D01*
G01X-6693Y475683D02*
X-4725Y475998D01*
G01X0Y495408D02*
X-12992D01*
G01X-9843Y495368D02*
X-6693D01*
G01X-9843D02*
X-6693D01*
G01X-4725Y495211D02*
X-4258D01*
G01X-4725D02*
X-4258D01*
G01X-3150Y495053D02*
X-2196D01*
G01X-3150D02*
X-2196D01*
G01X-4725Y494778D02*
X-6693D01*
G01X-4725D02*
X-6693D01*
G01X-4725Y493203D02*
X-6693D01*
G01X-4725D02*
X-6693D01*
G01X-2196Y492927D02*
X-3150D01*
G01X-2196D02*
X-3150D01*
G01X-4258Y492770D02*
X-4725D01*
G01X-4258D02*
X-4725D01*
G01X-6693Y492612D02*
X-9843D01*
G01X-6693D02*
X-9843D01*
G01X-12992Y492573D02*
X0D01*
G01Y491471D02*
X-12992D01*
G01X-9843Y491431D02*
X-6693D01*
G01X-9843D02*
X-6693D01*
G01X-4725Y491274D02*
X-4258D01*
G01X-4725D02*
X-4258D01*
G01X-3150Y491116D02*
X-2196D01*
G01X-3150D02*
X-2196D01*
G01X-4725Y490841D02*
X-6693D01*
G01X-4725D02*
X-6693D01*
G01X-4725Y489266D02*
X-6693D01*
G01X-4725D02*
X-6693D01*
G01X-2196Y488990D02*
X-3150D01*
G01X-2196D02*
X-3150D01*
G01X-4258Y488833D02*
X-4725D01*
G01X-4258D02*
X-4725D01*
G01X-6693Y488675D02*
X-9843D01*
G01X-6693D02*
X-9843D01*
G01X-12992Y488636D02*
X0D01*
G01Y487534D02*
X-12992D01*
G01X-9843Y487494D02*
X-6693D01*
G01X-9843D02*
X-6693D01*
G01X-4725Y487337D02*
X-4258D01*
G01X-4725D02*
X-4258D01*
G01X-3150Y487179D02*
X-2196D01*
G01X-3150D02*
X-2196D01*
G01X-4725Y486904D02*
X-6693D01*
G01X-4725D02*
X-6693D01*
G01X-4725Y485329D02*
X-6693D01*
G01X-4725D02*
X-6693D01*
G01X-2196Y485053D02*
X-3150D01*
G01X-2196D02*
X-3150D01*
G01X-4258Y484896D02*
X-4725D01*
G01X-4258D02*
X-4725D01*
G01X-6693Y484738D02*
X-9843D01*
G01X-6693D02*
X-9843D01*
G01X-12992Y484699D02*
X0D01*
G01Y483597D02*
X-12992D01*
G01X-9843Y483557D02*
X-6693D01*
G01X-9843D02*
X-6693D01*
G01X-4725Y483400D02*
X-4258D01*
G01X-4725D02*
X-4258D01*
G01X-3150Y483242D02*
X-2196D01*
G01X-3150D02*
X-2196D01*
G01X-4725Y482967D02*
X-6693D01*
G01X-4725D02*
X-6693D01*
G01X-4725Y481392D02*
X-6693D01*
G01X-4725D02*
X-6693D01*
G01X-2196Y481116D02*
X-3150D01*
G01X-2196D02*
X-3150D01*
G01X-4258Y480959D02*
X-4725D01*
G01X-4258D02*
X-4725D01*
G01X-6693Y480801D02*
X-9843D01*
G01X-6693D02*
X-9843D01*
G01X-12992Y480762D02*
X0D01*
G01Y479660D02*
X-12992D01*
G01X-9843Y479620D02*
X-6693D01*
G01X-9843D02*
X-6693D01*
G01X-4725Y479463D02*
X-4258D01*
G01X-4725D02*
X-4258D01*
G01X-3150Y479305D02*
X-2196D01*
G01X-3150D02*
X-2196D01*
G01X-4725Y479030D02*
X-6693D01*
G01X-4725D02*
X-6693D01*
G01X-4725Y477455D02*
X-6693D01*
G01X-4725D02*
X-6693D01*
G01X-2196Y477179D02*
X-3150D01*
G01X-2196D02*
X-3150D01*
G01X-4258Y477022D02*
X-4725D01*
G01X-4258D02*
X-4725D01*
G01X-6693Y476864D02*
X-9843D01*
G01X-6693D02*
X-9843D01*
G01X-12992Y476825D02*
X0D01*
G01Y475723D02*
X-12992D01*
G01X-9843Y475683D02*
X-6693D01*
G01X-9843D02*
X-6693D01*
G01X-4725Y475526D02*
X-4258D01*
G01X-4725D02*
X-4258D01*
G01X-3150Y475368D02*
X-2196D01*
G01X-3150D02*
X-2196D01*
G01X-4725Y496234D02*
X-6693Y496549D01*
G01X-4725Y496234D02*
X-6693Y496549D01*
G01X-4725Y492297D02*
X-6693Y492612D01*
G01X-4725Y492297D02*
X-6693Y492612D01*
G01X-4725Y488360D02*
X-6693Y488675D01*
G01X-4725Y488360D02*
X-6693Y488675D01*
G01X-4725Y484423D02*
X-6693Y484738D01*
G01X-4725Y484423D02*
X-6693Y484738D01*
G01X-4725Y480486D02*
X-6693Y480801D01*
G01X-4725Y480486D02*
X-6693Y480801D01*
G01X-4725Y476549D02*
X-6693Y476864D01*
G01X-4725Y476549D02*
X-6693Y476864D01*
G01X-3756Y483282D02*
Y481077D01*
G01Y479345D02*
Y477140D01*
G01Y487219D02*
Y485014D01*
G01Y491156D02*
Y488951D01*
G01Y495093D02*
Y492888D01*
G01X-4725Y496234D02*
Y497140D01*
G01Y492297D02*
Y493203D01*
G01Y494778D02*
Y495683D01*
G01Y488360D02*
Y489266D01*
G01Y490841D02*
Y491746D01*
G01Y482967D02*
Y483872D01*
G01Y484423D02*
Y485329D01*
G01Y486904D02*
Y487809D01*
G01Y479030D02*
Y479935D01*
G01Y480486D02*
Y481392D01*
G01Y476549D02*
Y477455D01*
G01D02*
Y476549D01*
G01Y479935D02*
Y479030D01*
G01Y481392D02*
Y480486D01*
G01Y483872D02*
Y482967D01*
G01Y485329D02*
Y484423D01*
G01Y487809D02*
Y486904D01*
G01Y493203D02*
Y492297D01*
G01Y489266D02*
Y488360D01*
G01Y491746D02*
Y490841D01*
G01Y497140D02*
Y496234D01*
G01Y495683D02*
Y494778D01*
G01X-6693Y477455D02*
Y476864D01*
G01Y477455D02*
Y476864D01*
G01Y479620D02*
Y479030D01*
G01Y481392D02*
Y480801D01*
G01Y479620D02*
Y479030D01*
G01Y481392D02*
Y480801D01*
G01Y483557D02*
Y482967D01*
G01Y485329D02*
Y484738D01*
G01Y487494D02*
Y486904D01*
G01Y483557D02*
Y482967D01*
G01Y485329D02*
Y484738D01*
G01Y487494D02*
Y486904D01*
G01Y489266D02*
Y488675D01*
G01Y491431D02*
Y490841D01*
G01Y489266D02*
Y488675D01*
G01Y491431D02*
Y490841D01*
G01Y493203D02*
Y492612D01*
G01Y495368D02*
Y494778D01*
G01Y493203D02*
Y492612D01*
G01Y495368D02*
Y494778D01*
G01X-10530Y483248D02*
Y481111D01*
G01Y479311D02*
Y477174D01*
G01Y483248D02*
Y481111D01*
G01Y479311D02*
Y477174D01*
G01Y487185D02*
Y485048D01*
G01Y487185D02*
Y485048D01*
G01Y491122D02*
Y488985D01*
G01Y491122D02*
Y488985D01*
G01Y495059D02*
Y492922D01*
G01Y495059D02*
Y492922D01*
G01X-11842Y492980D02*
Y495001D01*
G01Y489043D02*
Y491064D01*
G01Y485106D02*
Y487127D01*
G01Y481169D02*
Y483190D01*
G01Y477232D02*
Y479253D01*
G01D02*
Y477232D01*
G01Y483190D02*
Y481169D01*
G01Y487127D02*
Y485106D01*
G01Y491064D02*
Y489043D01*
G01Y495001D02*
Y492980D01*
G01X-12280Y492985D02*
Y494995D01*
G01Y489048D02*
Y491058D01*
G01Y485111D02*
Y487121D01*
G01Y481174D02*
Y483184D01*
G01Y477237D02*
Y479247D01*
G01D02*
Y477237D01*
G01Y483184D02*
Y481174D01*
G01Y487121D02*
Y485111D01*
G01Y491058D02*
Y489048D01*
G01Y494995D02*
Y492985D01*
G01X-12992Y475723D02*
Y475408D01*
G01Y477140D02*
Y476825D01*
G01Y479660D02*
Y479345D01*
G01Y481077D02*
Y480762D01*
G01Y483597D02*
Y483282D01*
G01Y487534D02*
Y487219D01*
G01Y485014D02*
Y484699D01*
G01Y491471D02*
Y491156D01*
G01Y488951D02*
Y488636D01*
G01Y495408D02*
Y495093D01*
G01Y492888D02*
Y492573D01*
G01X-23684Y493112D02*
Y494869D01*
G01Y489175D02*
Y490932D01*
G01Y485238D02*
Y486995D01*
G01Y477364D02*
Y479121D01*
G01Y481301D02*
Y483058D01*
G01D02*
Y481301D01*
G01Y479121D02*
Y477364D01*
G01Y486995D02*
Y485238D01*
G01Y490932D02*
Y489175D01*
G01Y494869D02*
Y493112D01*
G01X-4258Y492770D02*
X-3377Y492534D01*
G01X-4258Y492770D02*
X-3377Y492534D01*
G01X-4258Y488833D02*
X-3377Y488597D01*
G01X-4258Y488833D02*
X-3377Y488597D01*
G01X-4258Y484896D02*
X-3377Y484660D01*
G01X-4258Y484896D02*
X-3377Y484660D01*
G01X-4258Y480959D02*
X-3377Y480723D01*
G01X-4258Y480959D02*
X-3377Y480723D01*
G01X-4258Y477022D02*
X-3377Y476786D01*
G01X-4258Y477022D02*
X-3377Y476786D01*
G01X-3150Y495053D02*
X-3377Y495447D01*
G01X-3150Y495053D02*
X-3377Y495447D01*
G01X-3150Y491116D02*
X-3377Y491510D01*
G01X-3150Y491116D02*
X-3377Y491510D01*
G01X-3150Y487179D02*
X-3377Y487573D01*
G01X-3150Y487179D02*
X-3377Y487573D01*
G01X-3150Y483242D02*
X-3377Y483636D01*
G01X-3150Y483242D02*
X-3377Y483636D01*
G01X-3150Y479305D02*
X-3377Y479699D01*
G01X-3150Y479305D02*
X-3377Y479699D01*
G01X-3150Y475368D02*
X-3377Y475762D01*
G01X-3150Y475368D02*
X-3377Y475762D01*
G01X-10630Y492967D02*
X-9843Y492612D01*
G01X-10630Y492967D02*
X-9843Y492612D01*
G01X-10630Y489030D02*
X-9843Y488675D01*
G01X-10630Y489030D02*
X-9843Y488675D01*
G01X-10630Y485093D02*
X-9843Y484738D01*
G01X-10630Y485093D02*
X-9843Y484738D01*
G01X-10630Y481156D02*
X-9843Y480801D01*
G01X-10630Y481156D02*
X-9843Y480801D01*
G01X-10630Y477219D02*
X-9843Y476864D01*
G01X-10630Y477219D02*
X-9843Y476864D01*
G01X-10630Y498951D02*
X-9843Y499305D01*
G01D02*
X-10630Y498951D01*
G01Y502888D02*
X-9843Y503242D01*
G01D02*
X-10630Y502888D01*
G01Y506825D02*
X-9843Y507179D01*
G01D02*
X-10630Y506825D01*
G01Y510762D02*
X-9843Y511116D01*
G01D02*
X-10630Y510762D01*
G01Y514699D02*
X-9843Y515053D01*
G01D02*
X-10630Y514699D01*
G01X-3377Y496471D02*
X-3150Y496864D01*
G01X-3377Y496471D02*
X-3150Y496864D01*
G01X-3377Y500408D02*
X-3150Y500801D01*
G01X-3377Y500408D02*
X-3150Y500801D01*
G01X-3377Y504345D02*
X-3150Y504738D01*
G01X-3377Y504345D02*
X-3150Y504738D01*
G01X-3377Y508282D02*
X-3150Y508675D01*
G01X-3377Y508282D02*
X-3150Y508675D01*
G01X-3377Y512219D02*
X-3150Y512612D01*
G01X-3377Y512219D02*
X-3150Y512612D01*
G01X-3377Y516156D02*
X-3150Y516549D01*
G01X-3377Y516156D02*
X-3150Y516549D01*
G01X-3377Y515132D02*
X-4258Y514896D01*
G01X-3377Y515132D02*
X-4258Y514896D01*
G01X-3377Y511195D02*
X-4258Y510959D01*
G01X-3377Y511195D02*
X-4258Y510959D01*
G01X-3377Y507258D02*
X-4258Y507022D01*
G01X-3377Y507258D02*
X-4258Y507022D01*
G01X-3377Y503321D02*
X-4258Y503085D01*
G01X-3377Y503321D02*
X-4258Y503085D01*
G01X-3377Y499384D02*
X-4258Y499148D01*
G01X-3377Y499384D02*
X-4258Y499148D01*
G01X-6693Y515053D02*
X-4725Y515368D01*
G01X-6693Y515053D02*
X-4725Y515368D01*
G01X-6693Y511116D02*
X-4725Y511431D01*
G01X-6693Y511116D02*
X-4725Y511431D01*
G01X-6693Y507179D02*
X-4725Y507494D01*
G01X-6693Y507179D02*
X-4725Y507494D01*
G01X-6693Y503242D02*
X-4725Y503557D01*
G01X-6693Y503242D02*
X-4725Y503557D01*
G01X-6693Y499305D02*
X-4725Y499620D01*
G01X-6693Y499305D02*
X-4725Y499620D01*
G01Y516825D02*
X-6693D01*
G01X-4725D02*
X-6693D01*
G01X-2196Y516549D02*
X-3150D01*
G01X-2196D02*
X-3150D01*
G01X-4258Y516392D02*
X-4725D01*
G01X-4258D02*
X-4725D01*
G01X-6693Y516234D02*
X-9843D01*
G01X-6693D02*
X-9843D01*
G01X-12992Y516195D02*
X0D01*
G01Y515093D02*
X-12992D01*
G01X-9843Y515053D02*
X-6693D01*
G01X-9843D02*
X-6693D01*
G01X-4725Y514896D02*
X-4258D01*
G01X-4725D02*
X-4258D01*
G01X-3150Y514738D02*
X-2196D01*
G01X-3150D02*
X-2196D01*
G01X-4725Y514463D02*
X-6693D01*
G01X-4725D02*
X-6693D01*
G01X-4725Y512888D02*
X-6693D01*
G01X-4725D02*
X-6693D01*
G01X-2196Y512612D02*
X-3150D01*
G01X-2196D02*
X-3150D01*
G01X-4258Y512455D02*
X-4725D01*
G01X-4258D02*
X-4725D01*
G01X-6693Y512297D02*
X-9843D01*
G01X-6693D02*
X-9843D01*
G01X-12992Y512258D02*
X0D01*
G01Y511156D02*
X-12992D01*
G01X-9843Y511116D02*
X-6693D01*
G01X-9843D02*
X-6693D01*
G01X-4725Y510959D02*
X-4258D01*
G01X-4725D02*
X-4258D01*
G01X-3150Y510801D02*
X-2196D01*
G01X-3150D02*
X-2196D01*
G01X-4725Y510526D02*
X-6693D01*
G01X-4725D02*
X-6693D01*
G01X-4725Y508951D02*
X-6693D01*
G01X-4725D02*
X-6693D01*
G01X-2196Y508675D02*
X-3150D01*
G01X-2196D02*
X-3150D01*
G01X-4258Y508518D02*
X-4725D01*
G01X-4258D02*
X-4725D01*
G01X-6693Y508360D02*
X-9843D01*
G01X-6693D02*
X-9843D01*
G01X-12992Y508321D02*
X0D01*
G01Y507219D02*
X-12992D01*
G01X-9843Y507179D02*
X-6693D01*
G01X-9843D02*
X-6693D01*
G01X-4725Y507022D02*
X-4258D01*
G01X-4725D02*
X-4258D01*
G01X-3150Y506864D02*
X-2196D01*
G01X-3150D02*
X-2196D01*
G01X-4725Y506589D02*
X-6693D01*
G01X-4725D02*
X-6693D01*
G01X-4725Y505014D02*
X-6693D01*
G01X-4725D02*
X-6693D01*
G01X-2196Y504738D02*
X-3150D01*
G01X-2196D02*
X-3150D01*
G01X-4258Y504581D02*
X-4725D01*
G01X-4258D02*
X-4725D01*
G01X-6693Y504423D02*
X-9843D01*
G01X-6693D02*
X-9843D01*
G01X-12992Y504384D02*
X0D01*
G01Y503282D02*
X-12992D01*
G01X-9843Y503242D02*
X-6693D01*
G01X-9843D02*
X-6693D01*
G01X-4725Y503085D02*
X-4258D01*
G01X-4725D02*
X-4258D01*
G01X-3150Y502927D02*
X-2196D01*
G01X-3150D02*
X-2196D01*
G01X-4725Y502652D02*
X-6693D01*
G01X-4725D02*
X-6693D01*
G01X-4725Y501077D02*
X-6693D01*
G01X-4725D02*
X-6693D01*
G01X-2196Y500801D02*
X-3150D01*
G01X-2196D02*
X-3150D01*
G01X-4258Y500644D02*
X-4725D01*
G01X-4258D02*
X-4725D01*
G01X-6693Y500486D02*
X-9843D01*
G01X-6693D02*
X-9843D01*
G01X-12992Y500447D02*
X0D01*
G01Y499345D02*
X-12992D01*
G01X-9843Y499305D02*
X-6693D01*
G01X-9843D02*
X-6693D01*
G01X-4725Y499148D02*
X-4258D01*
G01X-4725D02*
X-4258D01*
G01X-3150Y498990D02*
X-2196D01*
G01X-3150D02*
X-2196D01*
G01X-4725Y498715D02*
X-6693D01*
G01X-4725D02*
X-6693D01*
G01X-4725Y497140D02*
X-6693D01*
G01X-4725D02*
X-6693D01*
G01X-2196Y496864D02*
X-3150D01*
G01X-2196D02*
X-3150D01*
G01X-4258Y496707D02*
X-4725D01*
G01X-4258D02*
X-4725D01*
G01X-6693Y496549D02*
X-9843D01*
G01X-6693D02*
X-9843D01*
G01X-12992Y496510D02*
X0D01*
G01X-4258Y516392D02*
X-3377Y516156D01*
G01X-4258Y516392D02*
X-3377Y516156D01*
G01X-4725Y515919D02*
X-6693Y516234D01*
G01X-4725Y515919D02*
X-6693Y516234D01*
G01X-4725Y511982D02*
X-6693Y512297D01*
G01X-4725Y511982D02*
X-6693Y512297D01*
G01X-4725Y508045D02*
X-6693Y508360D01*
G01X-4725Y508045D02*
X-6693Y508360D01*
G01X-4725Y504108D02*
X-6693Y504423D01*
G01X-4725Y504108D02*
X-6693Y504423D01*
G01X-4725Y500171D02*
X-6693Y500486D01*
G01X-4725Y500171D02*
X-6693Y500486D01*
G01X-3756Y499030D02*
Y496825D01*
G01Y502967D02*
Y500762D01*
G01Y506904D02*
Y504699D01*
G01Y510841D02*
Y508636D01*
G01Y514778D02*
Y512573D01*
G01Y518715D02*
Y516510D01*
G01X-4725Y515919D02*
Y516825D01*
G01Y511982D02*
Y512888D01*
G01Y514463D02*
Y515368D01*
G01Y506589D02*
Y507494D01*
G01Y508045D02*
Y508951D01*
G01Y510526D02*
Y511431D01*
G01Y502652D02*
Y503557D01*
G01Y504108D02*
Y505014D01*
G01Y498715D02*
Y499620D01*
G01Y500171D02*
Y501077D01*
G01D02*
Y500171D01*
G01Y499620D02*
Y498715D01*
G01Y505014D02*
Y504108D01*
G01Y503557D02*
Y502652D01*
G01Y508951D02*
Y508045D01*
G01Y511431D02*
Y510526D01*
G01Y507494D02*
Y506589D01*
G01Y512888D02*
Y511982D01*
G01Y515368D02*
Y514463D01*
G01Y516825D02*
Y515919D01*
G01X-6693Y497140D02*
Y496549D01*
G01Y497140D02*
Y496549D01*
G01Y501077D02*
Y500486D01*
G01Y499305D02*
Y498715D01*
G01Y499305D02*
Y498715D01*
G01Y501077D02*
Y500486D01*
G01Y505014D02*
Y504423D01*
G01Y503242D02*
Y502652D01*
G01Y503242D02*
Y502652D01*
G01Y505014D02*
Y504423D01*
G01Y508951D02*
Y508360D01*
G01Y511116D02*
Y510526D01*
G01Y507179D02*
Y506589D01*
G01Y507179D02*
Y506589D01*
G01Y508951D02*
Y508360D01*
G01Y511116D02*
Y510526D01*
G01Y512888D02*
Y512297D01*
G01Y515053D02*
Y514463D01*
G01Y512888D02*
Y512297D01*
G01Y515053D02*
Y514463D01*
G01Y516825D02*
Y516234D01*
G01Y516825D02*
Y516234D01*
G01X-10530Y498996D02*
Y496859D01*
G01Y498996D02*
Y496859D01*
G01Y506870D02*
Y504733D01*
G01Y502933D02*
Y500796D01*
G01Y506870D02*
Y504733D01*
G01Y502933D02*
Y500796D01*
G01Y510807D02*
Y508670D01*
G01Y510807D02*
Y508670D01*
G01Y514744D02*
Y512607D01*
G01Y514744D02*
Y512607D01*
G01Y518681D02*
Y516544D01*
G01Y518681D02*
Y516544D01*
G01X-11842Y516602D02*
Y518623D01*
G01Y512665D02*
Y514686D01*
G01Y508728D02*
Y510749D01*
G01Y504791D02*
Y506812D01*
G01Y500854D02*
Y502875D01*
G01Y496917D02*
Y498938D01*
G01D02*
Y496917D01*
G01Y502875D02*
Y500854D01*
G01Y506812D02*
Y504791D01*
G01Y510749D02*
Y508728D01*
G01Y514686D02*
Y512665D01*
G01Y518623D02*
Y516602D01*
G01X-12280Y516607D02*
Y518617D01*
G01Y512670D02*
Y514680D01*
G01Y508733D02*
Y510743D01*
G01Y504796D02*
Y506806D01*
G01Y500859D02*
Y502869D01*
G01Y496922D02*
Y498932D01*
G01D02*
Y496922D01*
G01Y506806D02*
Y504796D01*
G01Y502869D02*
Y500859D01*
G01Y510743D02*
Y508733D01*
G01Y514680D02*
Y512670D01*
G01Y518617D02*
Y516607D01*
G01X-12992Y496825D02*
Y496510D01*
G01Y499345D02*
Y499030D01*
G01Y500762D02*
Y500447D01*
G01Y503282D02*
Y502967D01*
G01Y504699D02*
Y504384D01*
G01Y507219D02*
Y506904D01*
G01Y511156D02*
Y510841D01*
G01Y508636D02*
Y508321D01*
G01Y515093D02*
Y514778D01*
G01Y512573D02*
Y512258D01*
G01Y516510D02*
Y516195D01*
G01X-23684Y516734D02*
Y518491D01*
G01Y512797D02*
Y514554D01*
G01Y508860D02*
Y510617D01*
G01Y500986D02*
Y502743D01*
G01Y504923D02*
Y506680D01*
G01Y497049D02*
Y498806D01*
G01D02*
Y497049D01*
G01Y506680D02*
Y504923D01*
G01Y502743D02*
Y500986D01*
G01Y510617D02*
Y508860D01*
G01Y514554D02*
Y512797D01*
G01Y518491D02*
Y516734D01*
G01X-10630Y516589D02*
X-9843Y516234D01*
G01X-10630Y516589D02*
X-9843Y516234D01*
G01X-10630Y512652D02*
X-9843Y512297D01*
G01X-10630Y512652D02*
X-9843Y512297D01*
G01X-10630Y508715D02*
X-9843Y508360D01*
G01X-10630Y508715D02*
X-9843Y508360D01*
G01X-10630Y504778D02*
X-9843Y504423D01*
G01X-10630Y504778D02*
X-9843Y504423D01*
G01X-10630Y500841D02*
X-9843Y500486D01*
G01X-10630Y500841D02*
X-9843Y500486D01*
G01X-10630Y496904D02*
X-9843Y496549D01*
G01X-10630Y496904D02*
X-9843Y496549D01*
G01X-4258Y512455D02*
X-3377Y512219D01*
G01X-4258Y512455D02*
X-3377Y512219D01*
G01X-4258Y508518D02*
X-3377Y508282D01*
G01X-4258Y508518D02*
X-3377Y508282D01*
G01X-4258Y504581D02*
X-3377Y504345D01*
G01X-4258Y504581D02*
X-3377Y504345D01*
G01X-4258Y500644D02*
X-3377Y500408D01*
G01X-4258Y500644D02*
X-3377Y500408D01*
G01X-4258Y496707D02*
X-3377Y496471D01*
G01X-4258Y496707D02*
X-3377Y496471D01*
G01X-3150Y514738D02*
X-3377Y515132D01*
G01X-3150Y514738D02*
X-3377Y515132D01*
G01X-3150Y510801D02*
X-3377Y511195D01*
G01X-3150Y510801D02*
X-3377Y511195D01*
G01X-3150Y506864D02*
X-3377Y507258D01*
G01X-3150Y506864D02*
X-3377Y507258D01*
G01X-3150Y502927D02*
X-3377Y503321D01*
G01X-3150Y502927D02*
X-3377Y503321D01*
G01X-3150Y498990D02*
X-3377Y499384D01*
G01X-3150Y498990D02*
X-3377Y499384D01*
G01X-10630Y518636D02*
X-9843Y518990D01*
G01D02*
X-10630Y518636D01*
G01Y522573D02*
X-9843Y522927D01*
G01D02*
X-10630Y522573D01*
G01Y526510D02*
X-9843Y526864D01*
G01D02*
X-10630Y526510D01*
G01Y530447D02*
X-9843Y530801D01*
G01D02*
X-10630Y530447D01*
G01Y534384D02*
X-9843Y534738D01*
G01D02*
X-10630Y534384D01*
G01Y538321D02*
X-9843Y538675D01*
G01D02*
X-10630Y538321D01*
G01X-3377Y520093D02*
X-3150Y520486D01*
G01X-3377Y520093D02*
X-3150Y520486D01*
G01X-3377Y524030D02*
X-3150Y524423D01*
G01X-3377Y524030D02*
X-3150Y524423D01*
G01X-3377Y527967D02*
X-3150Y528360D01*
G01X-3377Y527967D02*
X-3150Y528360D01*
G01X-3377Y531904D02*
X-3150Y532297D01*
G01X-3377Y531904D02*
X-3150Y532297D01*
G01X-3377Y535841D02*
X-3150Y536234D01*
G01X-3377Y535841D02*
X-3150Y536234D01*
G01X-3377Y538754D02*
X-4258Y538518D01*
G01X-3377Y538754D02*
X-4258Y538518D01*
G01X-3377Y534817D02*
X-4258Y534581D01*
G01X-3377Y534817D02*
X-4258Y534581D01*
G01X-3377Y530880D02*
X-4258Y530644D01*
G01X-3377Y530880D02*
X-4258Y530644D01*
G01X-3377Y526943D02*
X-4258Y526707D01*
G01X-3377Y526943D02*
X-4258Y526707D01*
G01X-3377Y523006D02*
X-4258Y522770D01*
G01X-3377Y523006D02*
X-4258Y522770D01*
G01X-3377Y519069D02*
X-4258Y518833D01*
G01X-3377Y519069D02*
X-4258Y518833D01*
G01X-6693Y534738D02*
X-4725Y535053D01*
G01X-6693Y534738D02*
X-4725Y535053D01*
G01X-6693Y530801D02*
X-4725Y531116D01*
G01X-6693Y530801D02*
X-4725Y531116D01*
G01X-6693Y526864D02*
X-4725Y527179D01*
G01X-6693Y526864D02*
X-4725Y527179D01*
G01X-6693Y522927D02*
X-4725Y523242D01*
G01X-6693Y522927D02*
X-4725Y523242D01*
G01X-6693Y518990D02*
X-4725Y519305D01*
G01X-6693Y518990D02*
X-4725Y519305D01*
G01Y538518D02*
X-4258D01*
G01X-4725D02*
X-4258D01*
G01X-3150Y538360D02*
X-2196D01*
G01X-3150D02*
X-2196D01*
G01X-4725Y538085D02*
X-6693D01*
G01X-4725D02*
X-6693D01*
G01X-4725Y536510D02*
X-6693D01*
G01X-4725D02*
X-6693D01*
G01X-2196Y536234D02*
X-3150D01*
G01X-2196D02*
X-3150D01*
G01X-4258Y536077D02*
X-4725D01*
G01X-4258D02*
X-4725D01*
G01X-6693Y535919D02*
X-9843D01*
G01X-6693D02*
X-9843D01*
G01X-12992Y535880D02*
X0D01*
G01Y534778D02*
X-12992D01*
G01X-9843Y534738D02*
X-6693D01*
G01X-9843D02*
X-6693D01*
G01X-4725Y534581D02*
X-4258D01*
G01X-4725D02*
X-4258D01*
G01X-3150Y534423D02*
X-2196D01*
G01X-3150D02*
X-2196D01*
G01X-4725Y534148D02*
X-6693D01*
G01X-4725D02*
X-6693D01*
G01X-4725Y532573D02*
X-6693D01*
G01X-4725D02*
X-6693D01*
G01X-2196Y532297D02*
X-3150D01*
G01X-2196D02*
X-3150D01*
G01X-4258Y532140D02*
X-4725D01*
G01X-4258D02*
X-4725D01*
G01X-6693Y531982D02*
X-9843D01*
G01X-6693D02*
X-9843D01*
G01X-12992Y531943D02*
X0D01*
G01Y530841D02*
X-12992D01*
G01X-9843Y530801D02*
X-6693D01*
G01X-9843D02*
X-6693D01*
G01X-4725Y530644D02*
X-4258D01*
G01X-4725D02*
X-4258D01*
G01X-3150Y530486D02*
X-2196D01*
G01X-3150D02*
X-2196D01*
G01X-4725Y530211D02*
X-6693D01*
G01X-4725D02*
X-6693D01*
G01X-4725Y528636D02*
X-6693D01*
G01X-4725D02*
X-6693D01*
G01X-2196Y528360D02*
X-3150D01*
G01X-2196D02*
X-3150D01*
G01X-4258Y528203D02*
X-4725D01*
G01X-4258D02*
X-4725D01*
G01X-6693Y528045D02*
X-9843D01*
G01X-6693D02*
X-9843D01*
G01X-12992Y528006D02*
X0D01*
G01Y526904D02*
X-12992D01*
G01X-9843Y526864D02*
X-6693D01*
G01X-9843D02*
X-6693D01*
G01X-4725Y526707D02*
X-4258D01*
G01X-4725D02*
X-4258D01*
G01X-3150Y526549D02*
X-2196D01*
G01X-3150D02*
X-2196D01*
G01X-4725Y526274D02*
X-6693D01*
G01X-4725D02*
X-6693D01*
G01X-4725Y524699D02*
X-6693D01*
G01X-4725D02*
X-6693D01*
G01X-2196Y524423D02*
X-3150D01*
G01X-2196D02*
X-3150D01*
G01X-4258Y524266D02*
X-4725D01*
G01X-4258D02*
X-4725D01*
G01X-6693Y524108D02*
X-9843D01*
G01X-6693D02*
X-9843D01*
G01X-12992Y524069D02*
X0D01*
G01Y522967D02*
X-12992D01*
G01X-9843Y522927D02*
X-6693D01*
G01X-9843D02*
X-6693D01*
G01X-4725Y522770D02*
X-4258D01*
G01X-4725D02*
X-4258D01*
G01X-3150Y522612D02*
X-2196D01*
G01X-3150D02*
X-2196D01*
G01X-4725Y522337D02*
X-6693D01*
G01X-4725D02*
X-6693D01*
G01X-4725Y520762D02*
X-6693D01*
G01X-4725D02*
X-6693D01*
G01X-2196Y520486D02*
X-3150D01*
G01X-2196D02*
X-3150D01*
G01X-4258Y520329D02*
X-4725D01*
G01X-4258D02*
X-4725D01*
G01X-6693Y520171D02*
X-9843D01*
G01X-6693D02*
X-9843D01*
G01X-12992Y520132D02*
X0D01*
G01Y519030D02*
X-12992D01*
G01X-9843Y518990D02*
X-6693D01*
G01X-9843D02*
X-6693D01*
G01X-4725Y518833D02*
X-4258D01*
G01X-4725D02*
X-4258D01*
G01X-3150Y518675D02*
X-2196D01*
G01X-3150D02*
X-2196D01*
G01X-4725Y518400D02*
X-6693D01*
G01X-4725D02*
X-6693D01*
G01X-4258Y536077D02*
X-3377Y535841D01*
G01X-4258Y536077D02*
X-3377Y535841D01*
G01X-4258Y532140D02*
X-3377Y531904D01*
G01X-4258Y532140D02*
X-3377Y531904D01*
G01X-4258Y528203D02*
X-3377Y527967D01*
G01X-4258Y528203D02*
X-3377Y527967D01*
G01X-4258Y524266D02*
X-3377Y524030D01*
G01X-4258Y524266D02*
X-3377Y524030D01*
G01X-4258Y520329D02*
X-3377Y520093D01*
G01X-4258Y520329D02*
X-3377Y520093D01*
G01X-4725Y535604D02*
X-6693Y535919D01*
G01X-4725Y535604D02*
X-6693Y535919D01*
G01X-4725Y531667D02*
X-6693Y531982D01*
G01X-4725Y531667D02*
X-6693Y531982D01*
G01X-4725Y527730D02*
X-6693Y528045D01*
G01X-4725Y527730D02*
X-6693Y528045D01*
G01X-4725Y523793D02*
X-6693Y524108D01*
G01X-4725Y523793D02*
X-6693Y524108D01*
G01X-4725Y519856D02*
X-6693Y520171D01*
G01X-4725Y519856D02*
X-6693Y520171D01*
G01X-3756Y522652D02*
Y520447D01*
G01Y526589D02*
Y524384D01*
G01Y534463D02*
Y532258D01*
G01Y530526D02*
Y528321D01*
G01Y538400D02*
Y536195D01*
G01X-4725Y535604D02*
Y536510D01*
G01Y538085D02*
Y538990D01*
G01Y534148D02*
Y535053D01*
G01Y530211D02*
Y531116D01*
G01Y531667D02*
Y532573D01*
G01Y526274D02*
Y527179D01*
G01Y527730D02*
Y528636D01*
G01Y522337D02*
Y523242D01*
G01Y523793D02*
Y524699D01*
G01Y518400D02*
Y519305D01*
G01Y519856D02*
Y520762D01*
G01D02*
Y519856D01*
G01Y519305D02*
Y518400D01*
G01Y524699D02*
Y523793D01*
G01Y523242D02*
Y522337D01*
G01Y528636D02*
Y527730D01*
G01Y527179D02*
Y526274D01*
G01Y532573D02*
Y531667D01*
G01Y531116D02*
Y530211D01*
G01Y535053D02*
Y534148D01*
G01Y536510D02*
Y535604D01*
G01Y538990D02*
Y538085D01*
G01X-6693Y520762D02*
Y520171D01*
G01Y518990D02*
Y518400D01*
G01Y518990D02*
Y518400D01*
G01Y520762D02*
Y520171D01*
G01Y524699D02*
Y524108D01*
G01Y522927D02*
Y522337D01*
G01Y522927D02*
Y522337D01*
G01Y524699D02*
Y524108D01*
G01Y528636D02*
Y528045D01*
G01Y526864D02*
Y526274D01*
G01Y526864D02*
Y526274D01*
G01Y528636D02*
Y528045D01*
G01Y532573D02*
Y531982D01*
G01Y534738D02*
Y534148D01*
G01Y530801D02*
Y530211D01*
G01Y530801D02*
Y530211D01*
G01Y532573D02*
Y531982D01*
G01Y534738D02*
Y534148D01*
G01Y536510D02*
Y535919D01*
G01Y538675D02*
Y538085D01*
G01Y536510D02*
Y535919D01*
G01Y538675D02*
Y538085D01*
G01X-10530Y522618D02*
Y520481D01*
G01Y522618D02*
Y520481D01*
G01Y526555D02*
Y524418D01*
G01Y526555D02*
Y524418D01*
G01Y534429D02*
Y532292D01*
G01Y530492D02*
Y528355D01*
G01Y534429D02*
Y532292D01*
G01Y530492D02*
Y528355D01*
G01Y538366D02*
Y536229D01*
G01Y538366D02*
Y536229D01*
G01X-11842Y536287D02*
Y538308D01*
G01Y532350D02*
Y534371D01*
G01Y528413D02*
Y530434D01*
G01Y524476D02*
Y526497D01*
G01Y520539D02*
Y522560D01*
G01D02*
Y520539D01*
G01Y526497D02*
Y524476D01*
G01Y530434D02*
Y528413D01*
G01Y534371D02*
Y532350D01*
G01Y538308D02*
Y536287D01*
G01X-12280Y536292D02*
Y538303D01*
G01Y532355D02*
Y534366D01*
G01Y528418D02*
Y530428D01*
G01Y524481D02*
Y526491D01*
G01Y520544D02*
Y522554D01*
G01D02*
Y520544D01*
G01Y526491D02*
Y524481D01*
G01Y534366D02*
Y532355D01*
G01Y530428D02*
Y528418D01*
G01Y538303D02*
Y536292D01*
G01X-12992Y519030D02*
Y518715D01*
G01Y520447D02*
Y520132D01*
G01Y522967D02*
Y522652D01*
G01Y524384D02*
Y524069D01*
G01Y526904D02*
Y526589D01*
G01Y528321D02*
Y528006D01*
G01Y530841D02*
Y530526D01*
G01Y534778D02*
Y534463D01*
G01Y532258D02*
Y531943D01*
G01Y538715D02*
Y538400D01*
G01Y536195D02*
Y535880D01*
G01X-23684Y536419D02*
Y538176D01*
G01Y532482D02*
Y534239D01*
G01Y524608D02*
Y526365D01*
G01Y528545D02*
Y530302D01*
G01Y520671D02*
Y522428D01*
G01D02*
Y520671D01*
G01Y530302D02*
Y528545D01*
G01Y526365D02*
Y524608D01*
G01Y534239D02*
Y532482D01*
G01Y538176D02*
Y536419D01*
G01X-10630Y536274D02*
X-9843Y535919D01*
G01X-10630Y536274D02*
X-9843Y535919D01*
G01X-10630Y532337D02*
X-9843Y531982D01*
G01X-10630Y532337D02*
X-9843Y531982D01*
G01X-10630Y528400D02*
X-9843Y528045D01*
G01X-10630Y528400D02*
X-9843Y528045D01*
G01X-10630Y524463D02*
X-9843Y524108D01*
G01X-10630Y524463D02*
X-9843Y524108D01*
G01X-10630Y520526D02*
X-9843Y520171D01*
G01X-10630Y520526D02*
X-9843Y520171D01*
G01X-3150Y538360D02*
X-3377Y538754D01*
G01X-3150Y538360D02*
X-3377Y538754D01*
G01X-3150Y534423D02*
X-3377Y534817D01*
G01X-3150Y534423D02*
X-3377Y534817D01*
G01X-3150Y530486D02*
X-3377Y530880D01*
G01X-3150Y530486D02*
X-3377Y530880D01*
G01X-3150Y526549D02*
X-3377Y526943D01*
G01X-3150Y526549D02*
X-3377Y526943D01*
G01X-3150Y522612D02*
X-3377Y523006D01*
G01X-3150Y522612D02*
X-3377Y523006D01*
G01X-3150Y518675D02*
X-3377Y519069D01*
G01X-3150Y518675D02*
X-3377Y519069D01*
G01X-10630Y542258D02*
X-9843Y542612D01*
G01D02*
X-10630Y542258D01*
G01Y546195D02*
X-9843Y546549D01*
G01D02*
X-10630Y546195D01*
G01Y550132D02*
X-9843Y550486D01*
G01D02*
X-10630Y550132D01*
G01Y554069D02*
X-9843Y554423D01*
G01D02*
X-10630Y554069D01*
G01Y558006D02*
X-9843Y558360D01*
G01D02*
X-10630Y558006D01*
G01X-3377Y558439D02*
X-4258Y558203D01*
G01X-3377Y558439D02*
X-4258Y558203D01*
G01X-3377Y554502D02*
X-4258Y554266D01*
G01X-3377Y554502D02*
X-4258Y554266D01*
G01X-3377Y539778D02*
X-3150Y540171D01*
G01X-3377Y539778D02*
X-3150Y540171D01*
G01X-3377Y543715D02*
X-3150Y544108D01*
G01X-3377Y543715D02*
X-3150Y544108D01*
G01X-3377Y547652D02*
X-3150Y548045D01*
G01X-3377Y547652D02*
X-3150Y548045D01*
G01X-3377Y551589D02*
X-3150Y551982D01*
G01X-3377Y551589D02*
X-3150Y551982D01*
G01X-3377Y555526D02*
X-3150Y555919D01*
G01X-3377Y555526D02*
X-3150Y555919D01*
G01X-3377Y559463D02*
X-3150Y559856D01*
G01X-3377Y559463D02*
X-3150Y559856D01*
G01X-6693Y558360D02*
X-4725Y558675D01*
G01X-6693Y558360D02*
X-4725Y558675D01*
G01X-6693Y554423D02*
X-4725Y554738D01*
G01X-6693Y554423D02*
X-4725Y554738D01*
G01X-6693Y550486D02*
X-4725Y550801D01*
G01X-6693Y550486D02*
X-4725Y550801D01*
G01X-6693Y546549D02*
X-4725Y546864D01*
G01X-6693Y546549D02*
X-4725Y546864D01*
G01X-6693Y542612D02*
X-4725Y542927D01*
G01X-6693Y542612D02*
X-4725Y542927D01*
G01X-6693Y538675D02*
X-4725Y538990D01*
G01X-6693Y538675D02*
X-4725Y538990D01*
G01X-3377Y550565D02*
X-4258Y550329D01*
G01X-3377Y550565D02*
X-4258Y550329D01*
G01X-3377Y546628D02*
X-4258Y546392D01*
G01X-3377Y546628D02*
X-4258Y546392D01*
G01X-3377Y542691D02*
X-4258Y542455D01*
G01X-3377Y542691D02*
X-4258Y542455D01*
G01Y559699D02*
X-4725D01*
G01X-4258D02*
X-4725D01*
G01X-6693Y559541D02*
X-9843D01*
G01X-6693D02*
X-9843D01*
G01X-12992Y559502D02*
X0D01*
G01Y558400D02*
X-12992D01*
G01X-9843Y558360D02*
X-6693D01*
G01X-9843D02*
X-6693D01*
G01X-4725Y558203D02*
X-4258D01*
G01X-4725D02*
X-4258D01*
G01X-3150Y558045D02*
X-2196D01*
G01X-3150D02*
X-2196D01*
G01X-4725Y557770D02*
X-6693D01*
G01X-4725D02*
X-6693D01*
G01X-4725Y556195D02*
X-6693D01*
G01X-4725D02*
X-6693D01*
G01X-2196Y555919D02*
X-3150D01*
G01X-2196D02*
X-3150D01*
G01X-4258Y555762D02*
X-4725D01*
G01X-4258D02*
X-4725D01*
G01X-6693Y555604D02*
X-9843D01*
G01X-6693D02*
X-9843D01*
G01X-12992Y555565D02*
X0D01*
G01Y554463D02*
X-12992D01*
G01X-9843Y554423D02*
X-6693D01*
G01X-9843D02*
X-6693D01*
G01X-4725Y554266D02*
X-4258D01*
G01X-4725D02*
X-4258D01*
G01X-3150Y554108D02*
X-2196D01*
G01X-3150D02*
X-2196D01*
G01X-4725Y553833D02*
X-6693D01*
G01X-4725D02*
X-6693D01*
G01X-4725Y552258D02*
X-6693D01*
G01X-4725D02*
X-6693D01*
G01X-2196Y551982D02*
X-3150D01*
G01X-2196D02*
X-3150D01*
G01X-4258Y551825D02*
X-4725D01*
G01X-4258D02*
X-4725D01*
G01X-6693Y551667D02*
X-9843D01*
G01X-6693D02*
X-9843D01*
G01X-12992Y551628D02*
X0D01*
G01Y550526D02*
X-12992D01*
G01X-9843Y550486D02*
X-6693D01*
G01X-9843D02*
X-6693D01*
G01X-4725Y550329D02*
X-4258D01*
G01X-4725D02*
X-4258D01*
G01X-3150Y550171D02*
X-2196D01*
G01X-3150D02*
X-2196D01*
G01X-4725Y549896D02*
X-6693D01*
G01X-4725D02*
X-6693D01*
G01X-4725Y559227D02*
X-6693Y559541D01*
G01X-4725Y559227D02*
X-6693Y559541D01*
G01X-4725Y555290D02*
X-6693Y555604D01*
G01X-4725Y555290D02*
X-6693Y555604D01*
G01X-4725Y551353D02*
X-6693Y551667D01*
G01X-4725Y551353D02*
X-6693Y551667D01*
G01X-4725Y548321D02*
X-6693D01*
G01X-4725D02*
X-6693D01*
G01X-2196Y548045D02*
X-3150D01*
G01X-2196D02*
X-3150D01*
G01X-4258Y547888D02*
X-4725D01*
G01X-4258D02*
X-4725D01*
G01X-6693Y547730D02*
X-9843D01*
G01X-6693D02*
X-9843D01*
G01X-12992Y547691D02*
X0D01*
G01Y546589D02*
X-12992D01*
G01X-9843Y546549D02*
X-6693D01*
G01X-9843D02*
X-6693D01*
G01X-4725Y546392D02*
X-4258D01*
G01X-4725D02*
X-4258D01*
G01X-3150Y546234D02*
X-2196D01*
G01X-3150D02*
X-2196D01*
G01X-4725Y545959D02*
X-6693D01*
G01X-4725D02*
X-6693D01*
G01X-4725Y544384D02*
X-6693D01*
G01X-4725D02*
X-6693D01*
G01X-2196Y544108D02*
X-3150D01*
G01X-2196D02*
X-3150D01*
G01X-4258Y543951D02*
X-4725D01*
G01X-4258D02*
X-4725D01*
G01X-6693Y543793D02*
X-9843D01*
G01X-6693D02*
X-9843D01*
G01X-12992Y543754D02*
X0D01*
G01Y542652D02*
X-12992D01*
G01X-9843Y542612D02*
X-6693D01*
G01X-9843D02*
X-6693D01*
G01X-4725Y542455D02*
X-4258D01*
G01X-4725D02*
X-4258D01*
G01X-3150Y542297D02*
X-2196D01*
G01X-3150D02*
X-2196D01*
G01X-4725Y542022D02*
X-6693D01*
G01X-4725D02*
X-6693D01*
G01X-4725Y540447D02*
X-6693D01*
G01X-4725D02*
X-6693D01*
G01X-2196Y540171D02*
X-3150D01*
G01X-2196D02*
X-3150D01*
G01X-4258Y540014D02*
X-4725D01*
G01X-4258D02*
X-4725D01*
G01X-6693Y539856D02*
X-9843D01*
G01X-6693D02*
X-9843D01*
G01X-12992Y539817D02*
X0D01*
G01Y538715D02*
X-12992D01*
G01X-9843Y538675D02*
X-6693D01*
G01X-9843D02*
X-6693D01*
G01X-4258Y559699D02*
X-3377Y559463D01*
G01X-4258Y559699D02*
X-3377Y559463D01*
G01X-4258Y555762D02*
X-3377Y555526D01*
G01X-4258Y555762D02*
X-3377Y555526D01*
G01X-4258Y551825D02*
X-3377Y551589D01*
G01X-4258Y551825D02*
X-3377Y551589D01*
G01X-4258Y547888D02*
X-3377Y547652D01*
G01X-4258Y547888D02*
X-3377Y547652D01*
G01X-4258Y543951D02*
X-3377Y543715D01*
G01X-4258Y543951D02*
X-3377Y543715D01*
G01X-4258Y540014D02*
X-3377Y539778D01*
G01X-4258Y540014D02*
X-3377Y539778D01*
G01X-4725Y547416D02*
X-6693Y547730D01*
G01X-4725Y547416D02*
X-6693Y547730D01*
G01X-4725Y543478D02*
X-6693Y543793D01*
G01X-4725Y543478D02*
X-6693Y543793D01*
G01X-4725Y539541D02*
X-6693Y539856D01*
G01X-4725Y539541D02*
X-6693Y539856D01*
G01X-3756Y542337D02*
Y540132D01*
G01Y546274D02*
Y544069D01*
G01Y550211D02*
Y548006D01*
G01Y558085D02*
Y555880D01*
G01Y554148D02*
Y551943D01*
G01X-4725Y557770D02*
Y558675D01*
G01Y559227D02*
Y560132D01*
G01Y553833D02*
Y554738D01*
G01Y555290D02*
Y556195D01*
G01Y549896D02*
Y550801D01*
G01Y551353D02*
Y552258D01*
G01Y543478D02*
Y544384D01*
G01Y545959D02*
Y546864D01*
G01Y547416D02*
Y548321D01*
G01Y539541D02*
Y540447D01*
G01Y542022D02*
Y542927D01*
G01Y540447D02*
Y539541D01*
G01Y542927D02*
Y542022D01*
G01Y544384D02*
Y543478D01*
G01Y546864D02*
Y545959D01*
G01Y548321D02*
Y547416D01*
G01Y550801D02*
Y549896D01*
G01Y552258D02*
Y551353D01*
G01Y554738D02*
Y553833D01*
G01Y556195D02*
Y555290D01*
G01Y558675D02*
Y557770D01*
G01Y560132D02*
Y559227D01*
G01X-6693Y540447D02*
Y539856D01*
G01Y542612D02*
Y542022D01*
G01Y540447D02*
Y539856D01*
G01Y542612D02*
Y542022D01*
G01Y544384D02*
Y543793D01*
G01Y546549D02*
Y545959D01*
G01Y548321D02*
Y547730D01*
G01Y544384D02*
Y543793D01*
G01Y546549D02*
Y545959D01*
G01Y548321D02*
Y547730D01*
G01Y550486D02*
Y549896D01*
G01Y552258D02*
Y551667D01*
G01Y550486D02*
Y549896D01*
G01Y552258D02*
Y551667D01*
G01Y554423D02*
Y553833D01*
G01Y556195D02*
Y555604D01*
G01Y558360D02*
Y557770D01*
G01Y554423D02*
Y553833D01*
G01Y556195D02*
Y555604D01*
G01Y558360D02*
Y557770D01*
G01Y560132D02*
Y559541D01*
G01Y560132D02*
Y559541D01*
G01X-10530Y542303D02*
Y540166D01*
G01Y542303D02*
Y540166D01*
G01Y546240D02*
Y544103D01*
G01Y546240D02*
Y544103D01*
G01Y550177D02*
Y548040D01*
G01Y550177D02*
Y548040D01*
G01Y558051D02*
Y555914D01*
G01Y554114D02*
Y551977D01*
G01Y558051D02*
Y555914D01*
G01Y554114D02*
Y551977D01*
G01X-11842Y555972D02*
Y557993D01*
G01Y552035D02*
Y554056D01*
G01Y548098D02*
Y550119D01*
G01Y544161D02*
Y546182D01*
G01Y540224D02*
Y542245D01*
G01D02*
Y540224D01*
G01Y546182D02*
Y544161D01*
G01Y550119D02*
Y548098D01*
G01Y554056D02*
Y552035D01*
G01Y557993D02*
Y555972D01*
G01X-12280Y555977D02*
Y557988D01*
G01Y552040D02*
Y554051D01*
G01Y548103D02*
Y550114D01*
G01Y544166D02*
Y546177D01*
G01Y540229D02*
Y542240D01*
G01D02*
Y540229D01*
G01Y546177D02*
Y544166D01*
G01Y550114D02*
Y548103D01*
G01Y554051D02*
Y552040D01*
G01Y557988D02*
Y555977D01*
G01X-12992Y542652D02*
Y542337D01*
G01Y540132D02*
Y539817D01*
G01Y544069D02*
Y543754D01*
G01Y546589D02*
Y546274D01*
G01Y548006D02*
Y547691D01*
G01Y550526D02*
Y550211D01*
G01Y551943D02*
Y551628D01*
G01Y554463D02*
Y554148D01*
G01Y558400D02*
Y558085D01*
G01Y555880D02*
Y555565D01*
G01Y559817D02*
Y559502D01*
G01X-23684Y552167D02*
Y553924D01*
G01Y556104D02*
Y557861D01*
G01Y548230D02*
Y549987D01*
G01Y544293D02*
Y546050D01*
G01Y540356D02*
Y542113D01*
G01D02*
Y540356D01*
G01Y546050D02*
Y544293D01*
G01Y549987D02*
Y548230D01*
G01Y557861D02*
Y556104D01*
G01Y553924D02*
Y552167D01*
G01X-3150Y558045D02*
X-3377Y558439D01*
G01X-3150Y558045D02*
X-3377Y558439D01*
G01X-3150Y554108D02*
X-3377Y554502D01*
G01X-3150Y554108D02*
X-3377Y554502D01*
G01X-10630Y559896D02*
X-9843Y559541D01*
G01X-10630Y559896D02*
X-9843Y559541D01*
G01X-10630Y555959D02*
X-9843Y555604D01*
G01X-10630Y555959D02*
X-9843Y555604D01*
G01X-10630Y552022D02*
X-9843Y551667D01*
G01X-10630Y552022D02*
X-9843Y551667D01*
G01X-10630Y548085D02*
X-9843Y547730D01*
G01X-10630Y548085D02*
X-9843Y547730D01*
G01X-10630Y544148D02*
X-9843Y543793D01*
G01X-10630Y544148D02*
X-9843Y543793D01*
G01X-10630Y540211D02*
X-9843Y539856D01*
G01X-10630Y540211D02*
X-9843Y539856D01*
G01X-3150Y550171D02*
X-3377Y550565D01*
G01X-3150Y550171D02*
X-3377Y550565D01*
G01X-3150Y546234D02*
X-3377Y546628D01*
G01X-3150Y546234D02*
X-3377Y546628D01*
G01X-3150Y542297D02*
X-3377Y542691D01*
G01X-3150Y542297D02*
X-3377Y542691D01*
G01X-10630Y561943D02*
X-9843Y562297D01*
G01D02*
X-10630Y561943D01*
G01Y565880D02*
X-9843Y566234D01*
G01D02*
X-10630Y565880D01*
G01Y569817D02*
X-9843Y570171D01*
G01D02*
X-10630Y569817D01*
G01Y573754D02*
X-9843Y574108D01*
G01D02*
X-10630Y573754D01*
G01Y577691D02*
X-9843Y578045D01*
G01D02*
X-10630Y577691D01*
G01X-3377Y578124D02*
X-4258Y577888D01*
G01X-3377Y578124D02*
X-4258Y577888D01*
G01X-3377Y574187D02*
X-4258Y573951D01*
G01X-3377Y574187D02*
X-4258Y573951D01*
G01X-3377Y570250D02*
X-4258Y570014D01*
G01X-3377Y570250D02*
X-4258Y570014D01*
G01X-3377Y566313D02*
X-4258Y566077D01*
G01X-3377Y566313D02*
X-4258Y566077D01*
G01X-3377Y562376D02*
X-4258Y562140D01*
G01X-3377Y562376D02*
X-4258Y562140D01*
G01X-3377Y563400D02*
X-3150Y563793D01*
G01X-3377Y563400D02*
X-3150Y563793D01*
G01X-3377Y567337D02*
X-3150Y567730D01*
G01X-3377Y567337D02*
X-3150Y567730D01*
G01X-3377Y571274D02*
X-3150Y571667D01*
G01X-3377Y571274D02*
X-3150Y571667D01*
G01X-3377Y575211D02*
X-3150Y575604D01*
G01X-3377Y575211D02*
X-3150Y575604D01*
G01X-3377Y579148D02*
X-3150Y579541D01*
G01X-3377Y579148D02*
X-3150Y579541D01*
G01X-6693Y578045D02*
X-4725Y578360D01*
G01X-6693Y578045D02*
X-4725Y578360D01*
G01X-6693Y574108D02*
X-4725Y574423D01*
G01X-6693Y574108D02*
X-4725Y574423D01*
G01X-6693Y570171D02*
X-4725Y570486D01*
G01X-6693Y570171D02*
X-4725Y570486D01*
G01X-6693Y566234D02*
X-4725Y566549D01*
G01X-6693Y566234D02*
X-4725Y566549D01*
G01X-6693Y562297D02*
X-4725Y562612D01*
G01X-6693Y562297D02*
X-4725Y562612D01*
G01Y579817D02*
X-6693D01*
G01X-4725D02*
X-6693D01*
G01X-2196Y579541D02*
X-3150D01*
G01X-2196D02*
X-3150D01*
G01X-4258Y579384D02*
X-4725D01*
G01X-4258D02*
X-4725D01*
G01X-6693Y579227D02*
X-9843D01*
G01X-6693D02*
X-9843D01*
G01X-12992Y579187D02*
X0D01*
G01Y578085D02*
X-12992D01*
G01X-9843Y578045D02*
X-6693D01*
G01X-9843D02*
X-6693D01*
G01X-4725Y577888D02*
X-4258D01*
G01X-4725D02*
X-4258D01*
G01X-3150Y577730D02*
X-2196D01*
G01X-3150D02*
X-2196D01*
G01X-4725Y577455D02*
X-6693D01*
G01X-4725D02*
X-6693D01*
G01X-4725Y575880D02*
X-6693D01*
G01X-4725D02*
X-6693D01*
G01X-2196Y575604D02*
X-3150D01*
G01X-2196D02*
X-3150D01*
G01X-4258Y575447D02*
X-4725D01*
G01X-4258D02*
X-4725D01*
G01X-6693Y575290D02*
X-9843D01*
G01X-6693D02*
X-9843D01*
G01X-12992Y575250D02*
X0D01*
G01Y574148D02*
X-12992D01*
G01X-9843Y574108D02*
X-6693D01*
G01X-9843D02*
X-6693D01*
G01X-4725Y573951D02*
X-4258D01*
G01X-4725D02*
X-4258D01*
G01X-3150Y573793D02*
X-2196D01*
G01X-3150D02*
X-2196D01*
G01X-4725Y573518D02*
X-6693D01*
G01X-4725D02*
X-6693D01*
G01X-4725Y571943D02*
X-6693D01*
G01X-4725D02*
X-6693D01*
G01X-2196Y571667D02*
X-3150D01*
G01X-2196D02*
X-3150D01*
G01X-4258Y571510D02*
X-4725D01*
G01X-4258D02*
X-4725D01*
G01X-6693Y571353D02*
X-9843D01*
G01X-6693D02*
X-9843D01*
G01X-12992Y571313D02*
X0D01*
G01Y570211D02*
X-12992D01*
G01X-9843Y570171D02*
X-6693D01*
G01X-9843D02*
X-6693D01*
G01X-4725Y570014D02*
X-4258D01*
G01X-4725D02*
X-4258D01*
G01X-3150Y569856D02*
X-2196D01*
G01X-3150D02*
X-2196D01*
G01X-4725Y569581D02*
X-6693D01*
G01X-4725D02*
X-6693D01*
G01X-4725Y568006D02*
X-6693D01*
G01X-4725D02*
X-6693D01*
G01X-2196Y567730D02*
X-3150D01*
G01X-2196D02*
X-3150D01*
G01X-4258Y567573D02*
X-4725D01*
G01X-4258D02*
X-4725D01*
G01X-6693Y567416D02*
X-9843D01*
G01X-6693D02*
X-9843D01*
G01X-12992Y567376D02*
X0D01*
G01Y566274D02*
X-12992D01*
G01X-9843Y566234D02*
X-6693D01*
G01X-9843D02*
X-6693D01*
G01X-4725Y566077D02*
X-4258D01*
G01X-4725D02*
X-4258D01*
G01X-3150Y565919D02*
X-2196D01*
G01X-3150D02*
X-2196D01*
G01X-4725Y565644D02*
X-6693D01*
G01X-4725D02*
X-6693D01*
G01X-4725Y564069D02*
X-6693D01*
G01X-4725D02*
X-6693D01*
G01X-2196Y563793D02*
X-3150D01*
G01X-2196D02*
X-3150D01*
G01X-4258Y563636D02*
X-4725D01*
G01X-4258D02*
X-4725D01*
G01X-6693Y563478D02*
X-9843D01*
G01X-6693D02*
X-9843D01*
G01X-12992Y563439D02*
X0D01*
G01Y562337D02*
X-12992D01*
G01X-9843Y562297D02*
X-6693D01*
G01X-9843D02*
X-6693D01*
G01X-4725Y562140D02*
X-4258D01*
G01X-4725D02*
X-4258D01*
G01X-3150Y561982D02*
X-2196D01*
G01X-3150D02*
X-2196D01*
G01X-4725Y561707D02*
X-6693D01*
G01X-4725D02*
X-6693D01*
G01X-4725Y560132D02*
X-6693D01*
G01X-4725D02*
X-6693D01*
G01X-2196Y559856D02*
X-3150D01*
G01X-2196D02*
X-3150D01*
G01X-4725Y578912D02*
X-6693Y579227D01*
G01X-4725Y578912D02*
X-6693Y579227D01*
G01X-4725Y574975D02*
X-6693Y575290D01*
G01X-4725Y574975D02*
X-6693Y575290D01*
G01X-4725Y571038D02*
X-6693Y571353D01*
G01X-4725Y571038D02*
X-6693Y571353D01*
G01X-4725Y567101D02*
X-6693Y567416D01*
G01X-4725Y567101D02*
X-6693Y567416D01*
G01X-4725Y563164D02*
X-6693Y563478D01*
G01X-4725Y563164D02*
X-6693Y563478D01*
G01X-10630Y579581D02*
X-9843Y579227D01*
G01X-10630Y579581D02*
X-9843Y579227D01*
G01X-4258Y579384D02*
X-3377Y579148D01*
G01X-4258Y579384D02*
X-3377Y579148D01*
G01X-4258Y575447D02*
X-3377Y575211D01*
G01X-4258Y575447D02*
X-3377Y575211D01*
G01X-4258Y571510D02*
X-3377Y571274D01*
G01X-4258Y571510D02*
X-3377Y571274D01*
G01X-4258Y567573D02*
X-3377Y567337D01*
G01X-4258Y567573D02*
X-3377Y567337D01*
G01X-4258Y563636D02*
X-3377Y563400D01*
G01X-4258Y563636D02*
X-3377Y563400D01*
G01X-3756Y562022D02*
Y559817D01*
G01Y565959D02*
Y563754D01*
G01Y569896D02*
Y567691D01*
G01Y573833D02*
Y571628D01*
G01Y581707D02*
Y579502D01*
G01Y577770D02*
Y575565D01*
G01X-4725Y578912D02*
Y579817D01*
G01Y577455D02*
Y578360D01*
G01Y574975D02*
Y575880D01*
G01Y573518D02*
Y574423D01*
G01Y567101D02*
Y568006D01*
G01Y569581D02*
Y570486D01*
G01Y571038D02*
Y571943D01*
G01Y563164D02*
Y564069D01*
G01Y565644D02*
Y566549D01*
G01Y561707D02*
Y562612D01*
G01D02*
Y561707D01*
G01Y564069D02*
Y563164D01*
G01Y566549D02*
Y565644D01*
G01Y568006D02*
Y567101D01*
G01Y570486D02*
Y569581D01*
G01Y571943D02*
Y571038D01*
G01Y575880D02*
Y574975D01*
G01Y574423D02*
Y573518D01*
G01Y579817D02*
Y578912D01*
G01Y578360D02*
Y577455D01*
G01X-6693Y562297D02*
Y561707D01*
G01Y562297D02*
Y561707D01*
G01Y564069D02*
Y563478D01*
G01Y566234D02*
Y565644D01*
G01Y564069D02*
Y563478D01*
G01Y566234D02*
Y565644D01*
G01Y568006D02*
Y567416D01*
G01Y570171D02*
Y569581D01*
G01Y571943D02*
Y571353D01*
G01Y568006D02*
Y567416D01*
G01Y570171D02*
Y569581D01*
G01Y571943D02*
Y571353D01*
G01Y575880D02*
Y575290D01*
G01Y574108D02*
Y573518D01*
G01Y575880D02*
Y575290D01*
G01Y574108D02*
Y573518D01*
G01Y579817D02*
Y579227D01*
G01Y578045D02*
Y577455D01*
G01Y579817D02*
Y579227D01*
G01Y578045D02*
Y577455D01*
G01X-10530Y561988D02*
Y559851D01*
G01Y561988D02*
Y559851D01*
G01Y565925D02*
Y563788D01*
G01Y565925D02*
Y563788D01*
G01Y569862D02*
Y567725D01*
G01Y569862D02*
Y567725D01*
G01Y573799D02*
Y571662D01*
G01Y573799D02*
Y571662D01*
G01Y581673D02*
Y579536D01*
G01Y577736D02*
Y575599D01*
G01Y581673D02*
Y579536D01*
G01Y577736D02*
Y575599D01*
G01X-11842Y579594D02*
Y581615D01*
G01Y575657D02*
Y577678D01*
G01Y571720D02*
Y573741D01*
G01Y567783D02*
Y569804D01*
G01Y563846D02*
Y565867D01*
G01Y559909D02*
Y561930D01*
G01D02*
Y559909D01*
G01Y565867D02*
Y563846D01*
G01Y569804D02*
Y567783D01*
G01Y573741D02*
Y571720D01*
G01Y581615D02*
Y579594D01*
G01Y577678D02*
Y575657D01*
G01X-12280Y579599D02*
Y581610D01*
G01Y575662D02*
Y577673D01*
G01Y571725D02*
Y573736D01*
G01Y567788D02*
Y569799D01*
G01Y563851D02*
Y565862D01*
G01Y559914D02*
Y561925D01*
G01D02*
Y559914D01*
G01Y565862D02*
Y563851D01*
G01Y569799D02*
Y567788D01*
G01Y573736D02*
Y571725D01*
G01Y581610D02*
Y579599D01*
G01Y577673D02*
Y575662D01*
G01X-12992Y562337D02*
Y562022D01*
G01Y566274D02*
Y565959D01*
G01Y563754D02*
Y563439D01*
G01Y567691D02*
Y567376D01*
G01Y570211D02*
Y569896D01*
G01Y571628D02*
Y571313D01*
G01Y574148D02*
Y573833D01*
G01Y575565D02*
Y575250D01*
G01Y578085D02*
Y577770D01*
G01Y579502D02*
Y579187D01*
G01X-23684Y579727D02*
Y581483D01*
G01Y575790D02*
Y577546D01*
G01Y571853D02*
Y573609D01*
G01Y567916D02*
Y569672D01*
G01Y563978D02*
Y565735D01*
G01Y560041D02*
Y561798D01*
G01D02*
Y560041D01*
G01Y565735D02*
Y563978D01*
G01Y569672D02*
Y567916D01*
G01Y573609D02*
Y571853D01*
G01Y581483D02*
Y579727D01*
G01Y577546D02*
Y575790D01*
G01X-3150Y577730D02*
X-3377Y578124D01*
G01X-3150Y577730D02*
X-3377Y578124D01*
G01X-3150Y573793D02*
X-3377Y574187D01*
G01X-3150Y573793D02*
X-3377Y574187D01*
G01X-3150Y569856D02*
X-3377Y570250D01*
G01X-3150Y569856D02*
X-3377Y570250D01*
G01X-3150Y565919D02*
X-3377Y566313D01*
G01X-3150Y565919D02*
X-3377Y566313D01*
G01X-3150Y561982D02*
X-3377Y562376D01*
G01X-3150Y561982D02*
X-3377Y562376D01*
G01X-10630Y575644D02*
X-9843Y575290D01*
G01X-10630Y575644D02*
X-9843Y575290D01*
G01X-10630Y571707D02*
X-9843Y571353D01*
G01X-10630Y571707D02*
X-9843Y571353D01*
G01X-10630Y567770D02*
X-9843Y567416D01*
G01X-10630Y567770D02*
X-9843Y567416D01*
G01X-10630Y563833D02*
X-9843Y563478D01*
G01X-10630Y563833D02*
X-9843Y563478D01*
G01X-10630Y581628D02*
X-9843Y581982D01*
G01D02*
X-10630Y581628D01*
G01Y585565D02*
X-9843Y585919D01*
G01D02*
X-10630Y585565D01*
G01Y589502D02*
X-9843Y589856D01*
G01D02*
X-10630Y589502D01*
G01Y593439D02*
X-9843Y593793D01*
G01D02*
X-10630Y593439D01*
G01Y597376D02*
X-9843Y597730D01*
G01D02*
X-10630Y597376D01*
G01Y601313D02*
X-9843Y601667D01*
G01D02*
X-10630Y601313D01*
G01X-3377Y601746D02*
X-4258Y601510D01*
G01X-3377Y601746D02*
X-4258Y601510D01*
G01X-3377Y597809D02*
X-4258Y597573D01*
G01X-3377Y597809D02*
X-4258Y597573D01*
G01X-3377Y593872D02*
X-4258Y593636D01*
G01X-3377Y593872D02*
X-4258Y593636D01*
G01X-3377Y589935D02*
X-4258Y589699D01*
G01X-3377Y589935D02*
X-4258Y589699D01*
G01X-3377Y585998D02*
X-4258Y585762D01*
G01X-3377Y585998D02*
X-4258Y585762D01*
G01X-3377Y582061D02*
X-4258Y581825D01*
G01X-3377Y582061D02*
X-4258Y581825D01*
G01X-3377Y583085D02*
X-3150Y583478D01*
G01X-3377Y583085D02*
X-3150Y583478D01*
G01X-3377Y587022D02*
X-3150Y587416D01*
G01X-3377Y587022D02*
X-3150Y587416D01*
G01X-3377Y590959D02*
X-3150Y591353D01*
G01X-3377Y590959D02*
X-3150Y591353D01*
G01X-3377Y594896D02*
X-3150Y595290D01*
G01X-3377Y594896D02*
X-3150Y595290D01*
G01X-3377Y598833D02*
X-3150Y599227D01*
G01X-3377Y598833D02*
X-3150Y599227D01*
G01X-6693Y601667D02*
X-4725Y601982D01*
G01X-6693Y601667D02*
X-4725Y601982D01*
G01X-6693Y597730D02*
X-4725Y598045D01*
G01X-6693Y597730D02*
X-4725Y598045D01*
G01X-6693Y593793D02*
X-4725Y594108D01*
G01X-6693Y593793D02*
X-4725Y594108D01*
G01X-6693Y589856D02*
X-4725Y590171D01*
G01X-6693Y589856D02*
X-4725Y590171D01*
G01X-6693Y585919D02*
X-4725Y586234D01*
G01X-6693Y585919D02*
X-4725Y586234D01*
G01X-6693Y581982D02*
X-4725Y582297D01*
G01X-6693Y581982D02*
X-4725Y582297D01*
G01X0Y601707D02*
X-12992D01*
G01X-9843Y601667D02*
X-6693D01*
G01X-9843D02*
X-6693D01*
G01X-4725Y601510D02*
X-4258D01*
G01X-4725D02*
X-4258D01*
G01X-3150Y601353D02*
X-2196D01*
G01X-3150D02*
X-2196D01*
G01X-4725Y601077D02*
X-6693D01*
G01X-4725D02*
X-6693D01*
G01X-4725Y599502D02*
X-6693D01*
G01X-4725D02*
X-6693D01*
G01X-2196Y599227D02*
X-3150D01*
G01X-2196D02*
X-3150D01*
G01X-4258Y599069D02*
X-4725D01*
G01X-4258D02*
X-4725D01*
G01X-6693Y598912D02*
X-9843D01*
G01X-6693D02*
X-9843D01*
G01X-12992Y598872D02*
X0D01*
G01Y597770D02*
X-12992D01*
G01X-9843Y597730D02*
X-6693D01*
G01X-9843D02*
X-6693D01*
G01X-4725Y597573D02*
X-4258D01*
G01X-4725D02*
X-4258D01*
G01X-3150Y597416D02*
X-2196D01*
G01X-3150D02*
X-2196D01*
G01X-4725Y597140D02*
X-6693D01*
G01X-4725D02*
X-6693D01*
G01X-4725Y595565D02*
X-6693D01*
G01X-4725D02*
X-6693D01*
G01X-2196Y595290D02*
X-3150D01*
G01X-2196D02*
X-3150D01*
G01X-4258Y595132D02*
X-4725D01*
G01X-4258D02*
X-4725D01*
G01X-6693Y594975D02*
X-9843D01*
G01X-6693D02*
X-9843D01*
G01X-12992Y594935D02*
X0D01*
G01Y593833D02*
X-12992D01*
G01X-9843Y593793D02*
X-6693D01*
G01X-9843D02*
X-6693D01*
G01X-4725Y593636D02*
X-4258D01*
G01X-4725D02*
X-4258D01*
G01X-3150Y593478D02*
X-2196D01*
G01X-3150D02*
X-2196D01*
G01X-4725Y593203D02*
X-6693D01*
G01X-4725D02*
X-6693D01*
G01X-4725Y591628D02*
X-6693D01*
G01X-4725D02*
X-6693D01*
G01X-2196Y591353D02*
X-3150D01*
G01X-2196D02*
X-3150D01*
G01X-4258Y591195D02*
X-4725D01*
G01X-4258D02*
X-4725D01*
G01X-6693Y591038D02*
X-9843D01*
G01X-6693D02*
X-9843D01*
G01X-12992Y590998D02*
X0D01*
G01Y589896D02*
X-12992D01*
G01X-9843Y589856D02*
X-6693D01*
G01X-9843D02*
X-6693D01*
G01X-4725Y589699D02*
X-4258D01*
G01X-4725D02*
X-4258D01*
G01X-3150Y589541D02*
X-2196D01*
G01X-3150D02*
X-2196D01*
G01X-4725Y589266D02*
X-6693D01*
G01X-4725D02*
X-6693D01*
G01X-4725Y587691D02*
X-6693D01*
G01X-4725D02*
X-6693D01*
G01X-2196Y587416D02*
X-3150D01*
G01X-2196D02*
X-3150D01*
G01X-4258Y587258D02*
X-4725D01*
G01X-4258D02*
X-4725D01*
G01X-6693Y587101D02*
X-9843D01*
G01X-6693D02*
X-9843D01*
G01X-12992Y587061D02*
X0D01*
G01Y585959D02*
X-12992D01*
G01X-9843Y585919D02*
X-6693D01*
G01X-9843D02*
X-6693D01*
G01X-4725Y585762D02*
X-4258D01*
G01X-4725D02*
X-4258D01*
G01X-3150Y585604D02*
X-2196D01*
G01X-3150D02*
X-2196D01*
G01X-4725Y585329D02*
X-6693D01*
G01X-4725D02*
X-6693D01*
G01X-4725Y583754D02*
X-6693D01*
G01X-4725D02*
X-6693D01*
G01X-2196Y583478D02*
X-3150D01*
G01X-2196D02*
X-3150D01*
G01X-4258Y583321D02*
X-4725D01*
G01X-4258D02*
X-4725D01*
G01X-6693Y583164D02*
X-9843D01*
G01X-6693D02*
X-9843D01*
G01X-12992Y583124D02*
X0D01*
G01Y582022D02*
X-12992D01*
G01X-9843Y581982D02*
X-6693D01*
G01X-9843D02*
X-6693D01*
G01X-4725Y581825D02*
X-4258D01*
G01X-4725D02*
X-4258D01*
G01X-3150Y581667D02*
X-2196D01*
G01X-3150D02*
X-2196D01*
G01X-4725Y581392D02*
X-6693D01*
G01X-4725D02*
X-6693D01*
G01X-4258Y599069D02*
X-3377Y598833D01*
G01X-4258Y599069D02*
X-3377Y598833D01*
G01X-4725Y598597D02*
X-6693Y598912D01*
G01X-4725Y598597D02*
X-6693Y598912D01*
G01X-4725Y594660D02*
X-6693Y594975D01*
G01X-4725Y594660D02*
X-6693Y594975D01*
G01X-4725Y590723D02*
X-6693Y591038D01*
G01X-4725Y590723D02*
X-6693Y591038D01*
G01X-4725Y586786D02*
X-6693Y587101D01*
G01X-4725Y586786D02*
X-6693Y587101D01*
G01X-4725Y582849D02*
X-6693Y583164D01*
G01X-4725Y582849D02*
X-6693Y583164D01*
G01X-10630Y599266D02*
X-9843Y598912D01*
G01X-10630Y599266D02*
X-9843Y598912D01*
G01X-10630Y595329D02*
X-9843Y594975D01*
G01X-10630Y595329D02*
X-9843Y594975D01*
G01X-10630Y591392D02*
X-9843Y591038D01*
G01X-10630Y591392D02*
X-9843Y591038D01*
G01X-10630Y587455D02*
X-9843Y587101D01*
G01X-10630Y587455D02*
X-9843Y587101D01*
G01X-10630Y583518D02*
X-9843Y583164D01*
G01X-10630Y583518D02*
X-9843Y583164D01*
G01X-4258Y595132D02*
X-3377Y594896D01*
G01X-4258Y595132D02*
X-3377Y594896D01*
G01X-4258Y591195D02*
X-3377Y590959D01*
G01X-4258Y591195D02*
X-3377Y590959D01*
G01X-4258Y587258D02*
X-3377Y587022D01*
G01X-4258Y587258D02*
X-3377Y587022D01*
G01X-4258Y583321D02*
X-3377Y583085D01*
G01X-4258Y583321D02*
X-3377Y583085D01*
G01X-3756Y585644D02*
Y583439D01*
G01Y589581D02*
Y587376D01*
G01Y593518D02*
Y591313D01*
G01Y597455D02*
Y595250D01*
G01Y601392D02*
Y599187D01*
G01X-4725Y601077D02*
Y601982D01*
G01Y597140D02*
Y598045D01*
G01Y598597D02*
Y599502D01*
G01Y590723D02*
Y591628D01*
G01Y593203D02*
Y594108D01*
G01Y594660D02*
Y595565D01*
G01Y586786D02*
Y587691D01*
G01Y589266D02*
Y590171D01*
G01Y581392D02*
Y582297D01*
G01Y582849D02*
Y583754D01*
G01Y585329D02*
Y586234D01*
G01Y582297D02*
Y581392D01*
G01Y583754D02*
Y582849D01*
G01Y586234D02*
Y585329D01*
G01Y587691D02*
Y586786D01*
G01Y590171D02*
Y589266D01*
G01Y591628D02*
Y590723D01*
G01Y594108D02*
Y593203D01*
G01Y595565D02*
Y594660D01*
G01Y598045D02*
Y597140D01*
G01Y599502D02*
Y598597D01*
G01Y601982D02*
Y601077D01*
G01X-6693Y581982D02*
Y581392D01*
G01Y583754D02*
Y583164D01*
G01Y585919D02*
Y585329D01*
G01Y581982D02*
Y581392D01*
G01Y583754D02*
Y583164D01*
G01Y585919D02*
Y585329D01*
G01Y587691D02*
Y587101D01*
G01Y589856D02*
Y589266D01*
G01Y587691D02*
Y587101D01*
G01Y589856D02*
Y589266D01*
G01Y591628D02*
Y591038D01*
G01Y593793D02*
Y593203D01*
G01Y595565D02*
Y594975D01*
G01Y591628D02*
Y591038D01*
G01Y593793D02*
Y593203D01*
G01Y595565D02*
Y594975D01*
G01Y597730D02*
Y597140D01*
G01Y599502D02*
Y598912D01*
G01Y597730D02*
Y597140D01*
G01Y599502D02*
Y598912D01*
G01Y601667D02*
Y601077D01*
G01Y601667D02*
Y601077D01*
G01X-10530Y585610D02*
Y583473D01*
G01Y585610D02*
Y583473D01*
G01Y589547D02*
Y587410D01*
G01Y589547D02*
Y587410D01*
G01Y593484D02*
Y591347D01*
G01Y593484D02*
Y591347D01*
G01Y597421D02*
Y595284D01*
G01Y597421D02*
Y595284D01*
G01Y601358D02*
Y599221D01*
G01Y601358D02*
Y599221D01*
G01X-11842Y599279D02*
Y601300D01*
G01Y595342D02*
Y597363D01*
G01Y591405D02*
Y593426D01*
G01Y587468D02*
Y589489D01*
G01Y583531D02*
Y585552D01*
G01D02*
Y583531D01*
G01Y589489D02*
Y587468D01*
G01Y593426D02*
Y591405D01*
G01Y597363D02*
Y595342D01*
G01Y601300D02*
Y599279D01*
G01X-12280Y599284D02*
Y601295D01*
G01Y595347D02*
Y597358D01*
G01Y591410D02*
Y593421D01*
G01Y587473D02*
Y589484D01*
G01Y583536D02*
Y585547D01*
G01D02*
Y583536D01*
G01Y589484D02*
Y587473D01*
G01Y593421D02*
Y591410D01*
G01Y597358D02*
Y595347D01*
G01Y601295D02*
Y599284D01*
G01X-12992Y582022D02*
Y581707D01*
G01Y585959D02*
Y585644D01*
G01Y583439D02*
Y583124D01*
G01Y589896D02*
Y589581D01*
G01Y587376D02*
Y587061D01*
G01Y593833D02*
Y593518D01*
G01Y591313D02*
Y590998D01*
G01Y595250D02*
Y594935D01*
G01Y597770D02*
Y597455D01*
G01Y599187D02*
Y598872D01*
G01Y601707D02*
Y601392D01*
G01X-23684Y599412D02*
Y601168D01*
G01Y595475D02*
Y597231D01*
G01Y591538D02*
Y593294D01*
G01Y587601D02*
Y589357D01*
G01Y583664D02*
Y585420D01*
G01D02*
Y583664D01*
G01Y589357D02*
Y587601D01*
G01Y593294D02*
Y591538D01*
G01Y597231D02*
Y595475D01*
G01Y601168D02*
Y599412D01*
G01X-3150Y601353D02*
X-3377Y601746D01*
G01X-3150Y601353D02*
X-3377Y601746D01*
G01X-3150Y597416D02*
X-3377Y597809D01*
G01X-3150Y597416D02*
X-3377Y597809D01*
G01X-3150Y593478D02*
X-3377Y593872D01*
G01X-3150Y593478D02*
X-3377Y593872D01*
G01X-3150Y589541D02*
X-3377Y589935D01*
G01X-3150Y589541D02*
X-3377Y589935D01*
G01X-3150Y585604D02*
X-3377Y585998D01*
G01X-3150Y585604D02*
X-3377Y585998D01*
G01X-3150Y581667D02*
X-3377Y582061D01*
G01X-3150Y581667D02*
X-3377Y582061D01*
G01X-10630Y605250D02*
X-9843Y605604D01*
G01D02*
X-10630Y605250D01*
G01Y609187D02*
X-9843Y609541D01*
G01D02*
X-10630Y609187D01*
G01Y613124D02*
X-9843Y613478D01*
G01D02*
X-10630Y613124D01*
G01Y617061D02*
X-9843Y617416D01*
G01D02*
X-10630Y617061D01*
G01Y620998D02*
X-9843Y621353D01*
G01D02*
X-10630Y620998D01*
G01X-6693Y621353D02*
X-4725Y621667D01*
G01X-6693Y621353D02*
X-4725Y621667D01*
G01X-6693Y617416D02*
X-4725Y617730D01*
G01X-6693Y617416D02*
X-4725Y617730D01*
G01X-3377Y621431D02*
X-4258Y621195D01*
G01X-3377Y621431D02*
X-4258Y621195D01*
G01X-3377Y617494D02*
X-4258Y617258D01*
G01X-3377Y617494D02*
X-4258Y617258D01*
G01X-3377Y613557D02*
X-4258Y613321D01*
G01X-3377Y613557D02*
X-4258Y613321D01*
G01X-3377Y609620D02*
X-4258Y609384D01*
G01X-3377Y609620D02*
X-4258Y609384D01*
G01X-3377Y605683D02*
X-4258Y605447D01*
G01X-3377Y605683D02*
X-4258Y605447D01*
G01X-3377Y602770D02*
X-3150Y603164D01*
G01X-3377Y602770D02*
X-3150Y603164D01*
G01X-3377Y606707D02*
X-3150Y607101D01*
G01X-3377Y606707D02*
X-3150Y607101D01*
G01X-3377Y610644D02*
X-3150Y611038D01*
G01X-3377Y610644D02*
X-3150Y611038D01*
G01X-3377Y614581D02*
X-3150Y614975D01*
G01X-3377Y614581D02*
X-3150Y614975D01*
G01X-3377Y618518D02*
X-3150Y618912D01*
G01X-3377Y618518D02*
X-3150Y618912D01*
G01X-3377Y622455D02*
X-3150Y622849D01*
G01X-3377Y622455D02*
X-3150Y622849D01*
G01X-6693Y613478D02*
X-4725Y613793D01*
G01X-6693Y613478D02*
X-4725Y613793D01*
G01X-6693Y609541D02*
X-4725Y609856D01*
G01X-6693Y609541D02*
X-4725Y609856D01*
G01X-6693Y605604D02*
X-4725Y605919D01*
G01X-6693Y605604D02*
X-4725Y605919D01*
G01Y623124D02*
X-6693D01*
G01X-4725D02*
X-6693D01*
G01X-2196Y622849D02*
X-3150D01*
G01X-2196D02*
X-3150D01*
G01X-4258Y622691D02*
X-4725D01*
G01X-4258D02*
X-4725D01*
G01X-6693Y622534D02*
X-9843D01*
G01X-6693D02*
X-9843D01*
G01X-12992Y622494D02*
X0D01*
G01Y621392D02*
X-12992D01*
G01X-9843Y621353D02*
X-6693D01*
G01X-9843D02*
X-6693D01*
G01X-4725Y621195D02*
X-4258D01*
G01X-4725D02*
X-4258D01*
G01X-3150Y621038D02*
X-2196D01*
G01X-3150D02*
X-2196D01*
G01X-4725Y620762D02*
X-6693D01*
G01X-4725D02*
X-6693D01*
G01X-4725Y619187D02*
X-6693D01*
G01X-4725D02*
X-6693D01*
G01X-2196Y618912D02*
X-3150D01*
G01X-2196D02*
X-3150D01*
G01X-4258Y618754D02*
X-4725D01*
G01X-4258D02*
X-4725D01*
G01X-6693Y618597D02*
X-9843D01*
G01X-6693D02*
X-9843D01*
G01X-12992Y618557D02*
X0D01*
G01Y617455D02*
X-12992D01*
G01X-9843Y617416D02*
X-6693D01*
G01X-9843D02*
X-6693D01*
G01X-4725Y617258D02*
X-4258D01*
G01X-4725D02*
X-4258D01*
G01X-3150Y617101D02*
X-2196D01*
G01X-3150D02*
X-2196D01*
G01X-4725Y616825D02*
X-6693D01*
G01X-4725D02*
X-6693D01*
G01X-4725Y615250D02*
X-6693D01*
G01X-4725D02*
X-6693D01*
G01X-2196Y614975D02*
X-3150D01*
G01X-2196D02*
X-3150D01*
G01X-4258Y614817D02*
X-4725D01*
G01X-4258D02*
X-4725D01*
G01X-6693Y614660D02*
X-9843D01*
G01X-6693D02*
X-9843D01*
G01X-12992Y614620D02*
X0D01*
G01Y613518D02*
X-12992D01*
G01X-9843Y613478D02*
X-6693D01*
G01X-9843D02*
X-6693D01*
G01X-4725Y613321D02*
X-4258D01*
G01X-4725D02*
X-4258D01*
G01X-3150Y613164D02*
X-2196D01*
G01X-3150D02*
X-2196D01*
G01X-4725Y612888D02*
X-6693D01*
G01X-4725D02*
X-6693D01*
G01X-4725Y611313D02*
X-6693D01*
G01X-4725D02*
X-6693D01*
G01X-2196Y611038D02*
X-3150D01*
G01X-2196D02*
X-3150D01*
G01X-4258Y610880D02*
X-4725D01*
G01X-4258D02*
X-4725D01*
G01X-6693Y610723D02*
X-9843D01*
G01X-6693D02*
X-9843D01*
G01X-12992Y610683D02*
X0D01*
G01Y609581D02*
X-12992D01*
G01X-9843Y609541D02*
X-6693D01*
G01X-9843D02*
X-6693D01*
G01X-4725Y609384D02*
X-4258D01*
G01X-4725D02*
X-4258D01*
G01X-3150Y609227D02*
X-2196D01*
G01X-3150D02*
X-2196D01*
G01X-4725Y608951D02*
X-6693D01*
G01X-4725D02*
X-6693D01*
G01X-4725Y607376D02*
X-6693D01*
G01X-4725D02*
X-6693D01*
G01X-2196Y607101D02*
X-3150D01*
G01X-2196D02*
X-3150D01*
G01X-4258Y606943D02*
X-4725D01*
G01X-4258D02*
X-4725D01*
G01X-6693Y606786D02*
X-9843D01*
G01X-6693D02*
X-9843D01*
G01X-12992Y606746D02*
X0D01*
G01Y605644D02*
X-12992D01*
G01X-9843Y605604D02*
X-6693D01*
G01X-9843D02*
X-6693D01*
G01X-4725Y605447D02*
X-4258D01*
G01X-4725D02*
X-4258D01*
G01X-3150Y605290D02*
X-2196D01*
G01X-3150D02*
X-2196D01*
G01X-4725Y605014D02*
X-6693D01*
G01X-4725D02*
X-6693D01*
G01X-4725Y603439D02*
X-6693D01*
G01X-4725D02*
X-6693D01*
G01X-2196Y603164D02*
X-3150D01*
G01X-2196D02*
X-3150D01*
G01X-4258Y603006D02*
X-4725D01*
G01X-4258D02*
X-4725D01*
G01X-6693Y602849D02*
X-9843D01*
G01X-6693D02*
X-9843D01*
G01X-12992Y602809D02*
X0D01*
G01X-4258Y622691D02*
X-3377Y622455D01*
G01X-4258Y622691D02*
X-3377Y622455D01*
G01X-4258Y618754D02*
X-3377Y618518D01*
G01X-4258Y618754D02*
X-3377Y618518D01*
G01X-4258Y614817D02*
X-3377Y614581D01*
G01X-4258Y614817D02*
X-3377Y614581D01*
G01X-4258Y610880D02*
X-3377Y610644D01*
G01X-4258Y610880D02*
X-3377Y610644D01*
G01X-4258Y606943D02*
X-3377Y606707D01*
G01X-4258Y606943D02*
X-3377Y606707D01*
G01X-4258Y603006D02*
X-3377Y602770D01*
G01X-4258Y603006D02*
X-3377Y602770D01*
G01X-4725Y622219D02*
X-6693Y622534D01*
G01X-4725Y622219D02*
X-6693Y622534D01*
G01X-4725Y618282D02*
X-6693Y618597D01*
G01X-4725Y618282D02*
X-6693Y618597D01*
G01X-4725Y614345D02*
X-6693Y614660D01*
G01X-4725Y614345D02*
X-6693Y614660D01*
G01X-4725Y610408D02*
X-6693Y610723D01*
G01X-4725Y610408D02*
X-6693Y610723D01*
G01X-4725Y606471D02*
X-6693Y606786D01*
G01X-4725Y606471D02*
X-6693Y606786D01*
G01X-4725Y602534D02*
X-6693Y602849D01*
G01X-4725Y602534D02*
X-6693Y602849D01*
G01X-10630Y622888D02*
X-9843Y622534D01*
G01X-10630Y622888D02*
X-9843Y622534D01*
G01X-10630Y618951D02*
X-9843Y618597D01*
G01X-10630Y618951D02*
X-9843Y618597D01*
G01X-10630Y615014D02*
X-9843Y614660D01*
G01X-10630Y615014D02*
X-9843Y614660D01*
G01X-10630Y611077D02*
X-9843Y610723D01*
G01X-10630Y611077D02*
X-9843Y610723D01*
G01X-10630Y607140D02*
X-9843Y606786D01*
G01X-10630Y607140D02*
X-9843Y606786D01*
G01X-10630Y603203D02*
X-9843Y602849D01*
G01X-10630Y603203D02*
X-9843Y602849D01*
G01X-3756Y605329D02*
Y603124D01*
G01Y609266D02*
Y607061D01*
G01Y613203D02*
Y610998D01*
G01Y617140D02*
Y614935D01*
G01Y621077D02*
Y618872D01*
G01Y625014D02*
Y622809D01*
G01X-4725Y620762D02*
Y621667D01*
G01Y622219D02*
Y623124D01*
G01Y614345D02*
Y615250D01*
G01Y616825D02*
Y617730D01*
G01Y618282D02*
Y619187D01*
G01Y610408D02*
Y611313D01*
G01Y612888D02*
Y613793D01*
G01Y605014D02*
Y605919D01*
G01Y606471D02*
Y607376D01*
G01Y608951D02*
Y609856D01*
G01Y602534D02*
Y603439D01*
G01D02*
Y602534D01*
G01Y605919D02*
Y605014D01*
G01Y607376D02*
Y606471D01*
G01Y609856D02*
Y608951D01*
G01Y611313D02*
Y610408D01*
G01Y613793D02*
Y612888D01*
G01Y615250D02*
Y614345D01*
G01Y617730D02*
Y616825D01*
G01Y619187D02*
Y618282D01*
G01Y621667D02*
Y620762D01*
G01Y623124D02*
Y622219D01*
G01X-6693Y603439D02*
Y602849D01*
G01Y603439D02*
Y602849D01*
G01Y605604D02*
Y605014D01*
G01Y607376D02*
Y606786D01*
G01Y609541D02*
Y608951D01*
G01Y605604D02*
Y605014D01*
G01Y607376D02*
Y606786D01*
G01Y609541D02*
Y608951D01*
G01Y611313D02*
Y610723D01*
G01Y613478D02*
Y612888D01*
G01Y611313D02*
Y610723D01*
G01Y613478D02*
Y612888D01*
G01Y615250D02*
Y614660D01*
G01Y617416D02*
Y616825D01*
G01Y619187D02*
Y618597D01*
G01Y615250D02*
Y614660D01*
G01Y617416D02*
Y616825D01*
G01Y619187D02*
Y618597D01*
G01Y621353D02*
Y620762D01*
G01Y623124D02*
Y622534D01*
G01Y621353D02*
Y620762D01*
G01Y623124D02*
Y622534D01*
G01X-10530Y609232D02*
Y607095D01*
G01Y605295D02*
Y603158D01*
G01Y609232D02*
Y607095D01*
G01Y605295D02*
Y603158D01*
G01Y613169D02*
Y611032D01*
G01Y613169D02*
Y611032D01*
G01Y617106D02*
Y614969D01*
G01Y617106D02*
Y614969D01*
G01Y621043D02*
Y618906D01*
G01Y621043D02*
Y618906D01*
G01Y624980D02*
Y622843D01*
G01Y624980D02*
Y622843D01*
G01X-11842Y622901D02*
Y624922D01*
G01Y618964D02*
Y620985D01*
G01Y615027D02*
Y617048D01*
G01Y611090D02*
Y613111D01*
G01Y607153D02*
Y609174D01*
G01Y603216D02*
Y605237D01*
G01D02*
Y603216D01*
G01Y609174D02*
Y607153D01*
G01Y613111D02*
Y611090D01*
G01Y617048D02*
Y615027D01*
G01Y620985D02*
Y618964D01*
G01Y624922D02*
Y622901D01*
G01X-12280Y622906D02*
Y624917D01*
G01Y618969D02*
Y620980D01*
G01Y615032D02*
Y617043D01*
G01Y611095D02*
Y613106D01*
G01Y607158D02*
Y609169D01*
G01Y603221D02*
Y605232D01*
G01D02*
Y603221D01*
G01Y609169D02*
Y607158D01*
G01Y613106D02*
Y611095D01*
G01Y617043D02*
Y615032D01*
G01Y620980D02*
Y618969D01*
G01Y624917D02*
Y622906D01*
G01X-12992Y603124D02*
Y602809D01*
G01Y605644D02*
Y605329D01*
G01Y609581D02*
Y609266D01*
G01Y607061D02*
Y606746D01*
G01Y613518D02*
Y613203D01*
G01Y610998D02*
Y610683D01*
G01Y617455D02*
Y617140D01*
G01Y614935D02*
Y614620D01*
G01Y618872D02*
Y618557D01*
G01Y621392D02*
Y621077D01*
G01Y622809D02*
Y622494D01*
G01X-23684Y623034D02*
Y624790D01*
G01Y619097D02*
Y620853D01*
G01Y615160D02*
Y616916D01*
G01Y611223D02*
Y612979D01*
G01Y607286D02*
Y609042D01*
G01Y603349D02*
Y605105D01*
G01D02*
Y603349D01*
G01Y609042D02*
Y607286D01*
G01Y612979D02*
Y611223D01*
G01Y616916D02*
Y615160D01*
G01Y620853D02*
Y619097D01*
G01Y624790D02*
Y623034D01*
G01X-3150Y621038D02*
X-3377Y621431D01*
G01X-3150Y621038D02*
X-3377Y621431D01*
G01X-3150Y617101D02*
X-3377Y617494D01*
G01X-3150Y617101D02*
X-3377Y617494D01*
G01X-3150Y613164D02*
X-3377Y613557D01*
G01X-3150Y613164D02*
X-3377Y613557D01*
G01X-3150Y609227D02*
X-3377Y609620D01*
G01X-3150Y609227D02*
X-3377Y609620D01*
G01X-3150Y605290D02*
X-3377Y605683D01*
G01X-3150Y605290D02*
X-3377Y605683D01*
G01X-10630Y624935D02*
X-9843Y625290D01*
G01D02*
X-10630Y624935D01*
G01Y628872D02*
X-9843Y629227D01*
G01D02*
X-10630Y628872D01*
G01Y632809D02*
X-9843Y633164D01*
G01D02*
X-10630Y632809D01*
G01Y636746D02*
X-9843Y637101D01*
G01D02*
X-10630Y636746D01*
G01Y640683D02*
X-9843Y641038D01*
G01D02*
X-10630Y640683D01*
G01X-3377Y641116D02*
X-4258Y640880D01*
G01X-3377Y641116D02*
X-4258Y640880D01*
G01X-3377Y637179D02*
X-4258Y636943D01*
G01X-3377Y637179D02*
X-4258Y636943D01*
G01X-3377Y633242D02*
X-4258Y633006D01*
G01X-3377Y633242D02*
X-4258Y633006D01*
G01X-6693Y641038D02*
X-4725Y641353D01*
G01X-6693Y641038D02*
X-4725Y641353D01*
G01X-6693Y637101D02*
X-4725Y637416D01*
G01X-6693Y637101D02*
X-4725Y637416D01*
G01X-6693Y633164D02*
X-4725Y633478D01*
G01X-6693Y633164D02*
X-4725Y633478D01*
G01X-6693Y629227D02*
X-4725Y629541D01*
G01X-6693Y629227D02*
X-4725Y629541D01*
G01X-6693Y625290D02*
X-4725Y625604D01*
G01X-6693Y625290D02*
X-4725Y625604D01*
G01X-3377Y629305D02*
X-4258Y629069D01*
G01X-3377Y629305D02*
X-4258Y629069D01*
G01X-3377Y625368D02*
X-4258Y625132D01*
G01X-3377Y625368D02*
X-4258Y625132D01*
G01X-3377Y626392D02*
X-3150Y626786D01*
G01X-3377Y626392D02*
X-3150Y626786D01*
G01X-3377Y630329D02*
X-3150Y630723D01*
G01X-3377Y630329D02*
X-3150Y630723D01*
G01X-3377Y634266D02*
X-3150Y634660D01*
G01X-3377Y634266D02*
X-3150Y634660D01*
G01X-3377Y638203D02*
X-3150Y638597D01*
G01X-3377Y638203D02*
X-3150Y638597D01*
G01X-3377Y642140D02*
X-3150Y642534D01*
G01X-3377Y642140D02*
X-3150Y642534D01*
G01X-4725Y642809D02*
X-6693D01*
G01X-4725D02*
X-6693D01*
G01X-2196Y642534D02*
X-3150D01*
G01X-2196D02*
X-3150D01*
G01X-4258Y642376D02*
X-4725D01*
G01X-4258D02*
X-4725D01*
G01X-6693Y642219D02*
X-9843D01*
G01X-6693D02*
X-9843D01*
G01X-12992Y642179D02*
X0D01*
G01Y641077D02*
X-12992D01*
G01X-9843Y641038D02*
X-6693D01*
G01X-9843D02*
X-6693D01*
G01X-4725Y640880D02*
X-4258D01*
G01X-4725D02*
X-4258D01*
G01X-3150Y640723D02*
X-2196D01*
G01X-3150D02*
X-2196D01*
G01X-4725Y640447D02*
X-6693D01*
G01X-4725D02*
X-6693D01*
G01X-4725Y638872D02*
X-6693D01*
G01X-4725D02*
X-6693D01*
G01X-2196Y638597D02*
X-3150D01*
G01X-2196D02*
X-3150D01*
G01X-4258Y638439D02*
X-4725D01*
G01X-4258D02*
X-4725D01*
G01X-6693Y638282D02*
X-9843D01*
G01X-6693D02*
X-9843D01*
G01X-12992Y638242D02*
X0D01*
G01Y637140D02*
X-12992D01*
G01X-9843Y637101D02*
X-6693D01*
G01X-9843D02*
X-6693D01*
G01X-4725Y636943D02*
X-4258D01*
G01X-4725D02*
X-4258D01*
G01X-3150Y636786D02*
X-2196D01*
G01X-3150D02*
X-2196D01*
G01X-4725Y636510D02*
X-6693D01*
G01X-4725D02*
X-6693D01*
G01X-4725Y634935D02*
X-6693D01*
G01X-4725D02*
X-6693D01*
G01X-2196Y634660D02*
X-3150D01*
G01X-2196D02*
X-3150D01*
G01X-4258Y634502D02*
X-4725D01*
G01X-4258D02*
X-4725D01*
G01X-6693Y634345D02*
X-9843D01*
G01X-6693D02*
X-9843D01*
G01X-12992Y634305D02*
X0D01*
G01Y633203D02*
X-12992D01*
G01X-9843Y633164D02*
X-6693D01*
G01X-9843D02*
X-6693D01*
G01X-4725Y633006D02*
X-4258D01*
G01X-4725D02*
X-4258D01*
G01X-3150Y632849D02*
X-2196D01*
G01X-3150D02*
X-2196D01*
G01X-4725Y632573D02*
X-6693D01*
G01X-4725D02*
X-6693D01*
G01X-4725Y630998D02*
X-6693D01*
G01X-4725D02*
X-6693D01*
G01X-2196Y630723D02*
X-3150D01*
G01X-2196D02*
X-3150D01*
G01X-4258Y630565D02*
X-4725D01*
G01X-4258D02*
X-4725D01*
G01X-6693Y630408D02*
X-9843D01*
G01X-6693D02*
X-9843D01*
G01X-12992Y630368D02*
X0D01*
G01Y629266D02*
X-12992D01*
G01X-9843Y629227D02*
X-6693D01*
G01X-9843D02*
X-6693D01*
G01X-4725Y629069D02*
X-4258D01*
G01X-4725D02*
X-4258D01*
G01X-3150Y628912D02*
X-2196D01*
G01X-3150D02*
X-2196D01*
G01X-4725Y628636D02*
X-6693D01*
G01X-4725D02*
X-6693D01*
G01X-4725Y627061D02*
X-6693D01*
G01X-4725D02*
X-6693D01*
G01X-2196Y626786D02*
X-3150D01*
G01X-2196D02*
X-3150D01*
G01X-4258Y626628D02*
X-4725D01*
G01X-4258D02*
X-4725D01*
G01X-6693Y626471D02*
X-9843D01*
G01X-6693D02*
X-9843D01*
G01X-12992Y626431D02*
X0D01*
G01X-4725Y641904D02*
X-6693Y642219D01*
G01X-4725Y641904D02*
X-6693Y642219D01*
G01X-4725Y637967D02*
X-6693Y638282D01*
G01X-4725Y637967D02*
X-6693Y638282D01*
G01X-4725Y634030D02*
X-6693Y634345D01*
G01X-4725Y634030D02*
X-6693Y634345D01*
G01X-4725Y630093D02*
X-6693Y630408D01*
G01X-4725Y630093D02*
X-6693Y630408D01*
G01X0Y625329D02*
X-12992D01*
G01X-9843Y625290D02*
X-6693D01*
G01X-9843D02*
X-6693D01*
G01X-4725Y625132D02*
X-4258D01*
G01X-4725D02*
X-4258D01*
G01X-3150Y624975D02*
X-2196D01*
G01X-3150D02*
X-2196D01*
G01X-4725Y624699D02*
X-6693D01*
G01X-4725D02*
X-6693D01*
G01X-4258Y642376D02*
X-3377Y642140D01*
G01X-4258Y642376D02*
X-3377Y642140D01*
G01X-4258Y638439D02*
X-3377Y638203D01*
G01X-4258Y638439D02*
X-3377Y638203D01*
G01X-4258Y634502D02*
X-3377Y634266D01*
G01X-4258Y634502D02*
X-3377Y634266D01*
G01X-4258Y630565D02*
X-3377Y630329D01*
G01X-4258Y630565D02*
X-3377Y630329D01*
G01X-4258Y626628D02*
X-3377Y626392D01*
G01X-4258Y626628D02*
X-3377Y626392D01*
G01X-4725Y626156D02*
X-6693Y626471D01*
G01X-4725Y626156D02*
X-6693Y626471D01*
G01X-10630Y642573D02*
X-9843Y642219D01*
G01X-10630Y642573D02*
X-9843Y642219D01*
G01X-10630Y638636D02*
X-9843Y638282D01*
G01X-10630Y638636D02*
X-9843Y638282D01*
G01X-10630Y634699D02*
X-9843Y634345D01*
G01X-10630Y634699D02*
X-9843Y634345D01*
G01X-10630Y630762D02*
X-9843Y630408D01*
G01X-10630Y630762D02*
X-9843Y630408D01*
G01X-10630Y626825D02*
X-9843Y626471D01*
G01X-10630Y626825D02*
X-9843Y626471D01*
G01X-3756Y632888D02*
Y630683D01*
G01Y628951D02*
Y626746D01*
G01Y636825D02*
Y634620D01*
G01Y640762D02*
Y638557D01*
G01Y644699D02*
Y642494D01*
G01X-4725Y641904D02*
Y642809D01*
G01Y637967D02*
Y638872D01*
G01Y640447D02*
Y641353D01*
G01Y632573D02*
Y633478D01*
G01Y634030D02*
Y634935D01*
G01Y636510D02*
Y637416D01*
G01Y628636D02*
Y629541D01*
G01Y630093D02*
Y630998D01*
G01Y624699D02*
Y625604D01*
G01Y626156D02*
Y627061D01*
G01Y625604D02*
Y624699D01*
G01Y627061D02*
Y626156D01*
G01Y629541D02*
Y628636D01*
G01Y630998D02*
Y630093D01*
G01Y633478D02*
Y632573D01*
G01Y634935D02*
Y634030D01*
G01Y637416D02*
Y636510D01*
G01Y638872D02*
Y637967D01*
G01Y641353D02*
Y640447D01*
G01Y642809D02*
Y641904D01*
G01X-6693Y625290D02*
Y624699D01*
G01Y627061D02*
Y626471D01*
G01Y625290D02*
Y624699D01*
G01Y627061D02*
Y626471D01*
G01Y629227D02*
Y628636D01*
G01Y630998D02*
Y630408D01*
G01Y633164D02*
Y632573D01*
G01Y629227D02*
Y628636D01*
G01Y630998D02*
Y630408D01*
G01Y633164D02*
Y632573D01*
G01Y634935D02*
Y634345D01*
G01Y637101D02*
Y636510D01*
G01Y634935D02*
Y634345D01*
G01Y637101D02*
Y636510D01*
G01Y638872D02*
Y638282D01*
G01Y641038D02*
Y640447D01*
G01Y638872D02*
Y638282D01*
G01Y641038D02*
Y640447D01*
G01Y642809D02*
Y642219D01*
G01Y642809D02*
Y642219D01*
G01X-10530Y632854D02*
Y630717D01*
G01Y628917D02*
Y626780D01*
G01Y632854D02*
Y630717D01*
G01Y628917D02*
Y626780D01*
G01Y636791D02*
Y634654D01*
G01Y636791D02*
Y634654D01*
G01Y640728D02*
Y638591D01*
G01Y640728D02*
Y638591D01*
G01Y644666D02*
Y642528D01*
G01Y644666D02*
Y642528D01*
G01X-11842Y642586D02*
Y644607D01*
G01Y638649D02*
Y640670D01*
G01Y634712D02*
Y636733D01*
G01Y630775D02*
Y632796D01*
G01Y626838D02*
Y628859D01*
G01D02*
Y626838D01*
G01Y632796D02*
Y630775D01*
G01Y636733D02*
Y634712D01*
G01Y640670D02*
Y638649D01*
G01Y644607D02*
Y642586D01*
G01X-12280Y642591D02*
Y644602D01*
G01Y638654D02*
Y640665D01*
G01Y634717D02*
Y636728D01*
G01Y630780D02*
Y632791D01*
G01Y626843D02*
Y628854D01*
G01D02*
Y626843D01*
G01Y632791D02*
Y630780D01*
G01Y636728D02*
Y634717D01*
G01Y640665D02*
Y638654D01*
G01Y644602D02*
Y642591D01*
G01X-12992Y625329D02*
Y625014D01*
G01Y626746D02*
Y626431D01*
G01Y629266D02*
Y628951D01*
G01Y633203D02*
Y632888D01*
G01Y630683D02*
Y630368D01*
G01Y637140D02*
Y636825D01*
G01Y634620D02*
Y634305D01*
G01Y641077D02*
Y640762D01*
G01Y638557D02*
Y638242D01*
G01Y642494D02*
Y642179D01*
G01X-23684Y642719D02*
Y644475D01*
G01Y638782D02*
Y640538D01*
G01Y634845D02*
Y636601D01*
G01Y626971D02*
Y628727D01*
G01Y630908D02*
Y632664D01*
G01D02*
Y630908D01*
G01Y628727D02*
Y626971D01*
G01Y636601D02*
Y634845D01*
G01Y640538D02*
Y638782D01*
G01Y644475D02*
Y642719D01*
G01X-3150Y640723D02*
X-3377Y641116D01*
G01X-3150Y640723D02*
X-3377Y641116D01*
G01X-3150Y636786D02*
X-3377Y637179D01*
G01X-3150Y636786D02*
X-3377Y637179D01*
G01X-3150Y632849D02*
X-3377Y633242D01*
G01X-3150Y632849D02*
X-3377Y633242D01*
G01X-3150Y628912D02*
X-3377Y629305D01*
G01X-3150Y628912D02*
X-3377Y629305D01*
G01X-3150Y624975D02*
X-3377Y625368D01*
G01X-3150Y624975D02*
X-3377Y625368D01*
G01X-10630Y644620D02*
X-9843Y644975D01*
G01D02*
X-10630Y644620D01*
G01Y648557D02*
X-9843Y648912D01*
G01D02*
X-10630Y648557D01*
G01Y652494D02*
X-9843Y652849D01*
G01D02*
X-10630Y652494D01*
G01Y656431D02*
X-9843Y656786D01*
G01D02*
X-10630Y656431D01*
G01Y660368D02*
X-9843Y660723D01*
G01D02*
X-10630Y660368D01*
G01Y664305D02*
X-9843Y664660D01*
G01D02*
X-10630Y664305D01*
G01X-3377Y664738D02*
X-4258Y664502D01*
G01X-3377Y664738D02*
X-4258Y664502D01*
G01X-3377Y660801D02*
X-4258Y660565D01*
G01X-3377Y660801D02*
X-4258Y660565D01*
G01X-3377Y656864D02*
X-4258Y656628D01*
G01X-3377Y656864D02*
X-4258Y656628D01*
G01X-3377Y652927D02*
X-4258Y652691D01*
G01X-3377Y652927D02*
X-4258Y652691D01*
G01X-3377Y648990D02*
X-4258Y648754D01*
G01X-3377Y648990D02*
X-4258Y648754D01*
G01X-3377Y645053D02*
X-4258Y644817D01*
G01X-3377Y645053D02*
X-4258Y644817D01*
G01X-6693Y664660D02*
X-4725Y664975D01*
G01X-6693Y664660D02*
X-4725Y664975D01*
G01X-6693Y660723D02*
X-4725Y661038D01*
G01X-6693Y660723D02*
X-4725Y661038D01*
G01X-6693Y656786D02*
X-4725Y657101D01*
G01X-6693Y656786D02*
X-4725Y657101D01*
G01X-6693Y652849D02*
X-4725Y653164D01*
G01X-6693Y652849D02*
X-4725Y653164D01*
G01X-6693Y648912D02*
X-4725Y649227D01*
G01X-6693Y648912D02*
X-4725Y649227D01*
G01X-6693Y644975D02*
X-4725Y645290D01*
G01X-6693Y644975D02*
X-4725Y645290D01*
G01X-3377Y646077D02*
X-3150Y646471D01*
G01X-3377Y646077D02*
X-3150Y646471D01*
G01X-3377Y650014D02*
X-3150Y650408D01*
G01X-3377Y650014D02*
X-3150Y650408D01*
G01X-3377Y653951D02*
X-3150Y654345D01*
G01X-3377Y653951D02*
X-3150Y654345D01*
G01X-3377Y657888D02*
X-3150Y658282D01*
G01X-3377Y657888D02*
X-3150Y658282D01*
G01X-3377Y661825D02*
X-3150Y662219D01*
G01X-3377Y661825D02*
X-3150Y662219D01*
G01X0Y664699D02*
X-12992D01*
G01X-9843Y664660D02*
X-6693D01*
G01X-9843D02*
X-6693D01*
G01X-4725Y664502D02*
X-4258D01*
G01X-4725D02*
X-4258D01*
G01X-3150Y664345D02*
X-2196D01*
G01X-3150D02*
X-2196D01*
G01X-4725Y664069D02*
X-6693D01*
G01X-4725D02*
X-6693D01*
G01X-4725Y662494D02*
X-6693D01*
G01X-4725D02*
X-6693D01*
G01X-2196Y662219D02*
X-3150D01*
G01X-2196D02*
X-3150D01*
G01X-4258Y662061D02*
X-4725D01*
G01X-4258D02*
X-4725D01*
G01X-6693Y661904D02*
X-9843D01*
G01X-6693D02*
X-9843D01*
G01X-12992Y661864D02*
X0D01*
G01Y660762D02*
X-12992D01*
G01X-9843Y660723D02*
X-6693D01*
G01X-9843D02*
X-6693D01*
G01X-4725Y660565D02*
X-4258D01*
G01X-4725D02*
X-4258D01*
G01X-3150Y660408D02*
X-2196D01*
G01X-3150D02*
X-2196D01*
G01X-4725Y660132D02*
X-6693D01*
G01X-4725D02*
X-6693D01*
G01X-4725Y658557D02*
X-6693D01*
G01X-4725D02*
X-6693D01*
G01X-2196Y658282D02*
X-3150D01*
G01X-2196D02*
X-3150D01*
G01X-4258Y658124D02*
X-4725D01*
G01X-4258D02*
X-4725D01*
G01X-6693Y657967D02*
X-9843D01*
G01X-6693D02*
X-9843D01*
G01X-12992Y657927D02*
X0D01*
G01Y656825D02*
X-12992D01*
G01X-9843Y656786D02*
X-6693D01*
G01X-9843D02*
X-6693D01*
G01X-4725Y656628D02*
X-4258D01*
G01X-4725D02*
X-4258D01*
G01X-3150Y656471D02*
X-2196D01*
G01X-3150D02*
X-2196D01*
G01X-4725Y656195D02*
X-6693D01*
G01X-4725D02*
X-6693D01*
G01X-4725Y654620D02*
X-6693D01*
G01X-4725D02*
X-6693D01*
G01X-2196Y654345D02*
X-3150D01*
G01X-2196D02*
X-3150D01*
G01X-4258Y654187D02*
X-4725D01*
G01X-4258D02*
X-4725D01*
G01X-6693Y654030D02*
X-9843D01*
G01X-6693D02*
X-9843D01*
G01X-12992Y653990D02*
X0D01*
G01Y652888D02*
X-12992D01*
G01X-9843Y652849D02*
X-6693D01*
G01X-9843D02*
X-6693D01*
G01X-4725Y652691D02*
X-4258D01*
G01X-4725D02*
X-4258D01*
G01X-3150Y652534D02*
X-2196D01*
G01X-3150D02*
X-2196D01*
G01X-4725Y652258D02*
X-6693D01*
G01X-4725D02*
X-6693D01*
G01X-4725Y650683D02*
X-6693D01*
G01X-4725D02*
X-6693D01*
G01X-2196Y650408D02*
X-3150D01*
G01X-2196D02*
X-3150D01*
G01X-4258Y650250D02*
X-4725D01*
G01X-4258D02*
X-4725D01*
G01X-6693Y650093D02*
X-9843D01*
G01X-6693D02*
X-9843D01*
G01X-12992Y650053D02*
X0D01*
G01Y648951D02*
X-12992D01*
G01X-9843Y648912D02*
X-6693D01*
G01X-9843D02*
X-6693D01*
G01X-4725Y648754D02*
X-4258D01*
G01X-4725D02*
X-4258D01*
G01X-3150Y648597D02*
X-2196D01*
G01X-3150D02*
X-2196D01*
G01X-4725Y648321D02*
X-6693D01*
G01X-4725D02*
X-6693D01*
G01X-4725Y646746D02*
X-6693D01*
G01X-4725D02*
X-6693D01*
G01X-2196Y646471D02*
X-3150D01*
G01X-2196D02*
X-3150D01*
G01X-4258Y646313D02*
X-4725D01*
G01X-4258D02*
X-4725D01*
G01X-6693Y646156D02*
X-9843D01*
G01X-6693D02*
X-9843D01*
G01X-12992Y646116D02*
X0D01*
G01Y645014D02*
X-12992D01*
G01X-9843Y644975D02*
X-6693D01*
G01X-9843D02*
X-6693D01*
G01X-4725Y644817D02*
X-4258D01*
G01X-4725D02*
X-4258D01*
G01X-3150Y644660D02*
X-2196D01*
G01X-3150D02*
X-2196D01*
G01X-4725Y644384D02*
X-6693D01*
G01X-4725D02*
X-6693D01*
G01X-4725Y661589D02*
X-6693Y661904D01*
G01X-4725Y661589D02*
X-6693Y661904D01*
G01X-4725Y657652D02*
X-6693Y657967D01*
G01X-4725Y657652D02*
X-6693Y657967D01*
G01X-4725Y653715D02*
X-6693Y654030D01*
G01X-4725Y653715D02*
X-6693Y654030D01*
G01X-4725Y649778D02*
X-6693Y650093D01*
G01X-4725Y649778D02*
X-6693Y650093D01*
G01X-4725Y645841D02*
X-6693Y646156D01*
G01X-4725Y645841D02*
X-6693Y646156D01*
G01X-10630Y662258D02*
X-9843Y661904D01*
G01X-10630Y662258D02*
X-9843Y661904D01*
G01X-4258Y662061D02*
X-3377Y661825D01*
G01X-4258Y662061D02*
X-3377Y661825D01*
G01X-4258Y658124D02*
X-3377Y657888D01*
G01X-4258Y658124D02*
X-3377Y657888D01*
G01X-4258Y654187D02*
X-3377Y653951D01*
G01X-4258Y654187D02*
X-3377Y653951D01*
G01X-4258Y650250D02*
X-3377Y650014D01*
G01X-4258Y650250D02*
X-3377Y650014D01*
G01X-4258Y646313D02*
X-3377Y646077D01*
G01X-4258Y646313D02*
X-3377Y646077D01*
G01X-10630Y658321D02*
X-9843Y657967D01*
G01X-10630Y658321D02*
X-9843Y657967D01*
G01X-10630Y654384D02*
X-9843Y654030D01*
G01X-10630Y654384D02*
X-9843Y654030D01*
G01X-10630Y650447D02*
X-9843Y650093D01*
G01X-10630Y650447D02*
X-9843Y650093D01*
G01X-10630Y646510D02*
X-9843Y646156D01*
G01X-10630Y646510D02*
X-9843Y646156D01*
G01X-3756Y648636D02*
Y646431D01*
G01Y656510D02*
Y654305D01*
G01Y652573D02*
Y650368D01*
G01Y660447D02*
Y658242D01*
G01Y664384D02*
Y662179D01*
G01X-4725Y661589D02*
Y662494D01*
G01Y664069D02*
Y664975D01*
G01Y657652D02*
Y658557D01*
G01Y660132D02*
Y661038D01*
G01Y656195D02*
Y657101D01*
G01Y652258D02*
Y653164D01*
G01Y653715D02*
Y654620D01*
G01Y648321D02*
Y649227D01*
G01Y649778D02*
Y650683D01*
G01Y644384D02*
Y645290D01*
G01Y645841D02*
Y646746D01*
G01Y645290D02*
Y644384D01*
G01Y646746D02*
Y645841D01*
G01Y649227D02*
Y648321D01*
G01Y650683D02*
Y649778D01*
G01Y653164D02*
Y652258D01*
G01Y654620D02*
Y653715D01*
G01Y657101D02*
Y656195D01*
G01Y658557D02*
Y657652D01*
G01Y661038D02*
Y660132D01*
G01Y662494D02*
Y661589D01*
G01Y664975D02*
Y664069D01*
G01X-6693Y644975D02*
Y644384D01*
G01Y646746D02*
Y646156D01*
G01Y644975D02*
Y644384D01*
G01Y646746D02*
Y646156D01*
G01Y648912D02*
Y648321D01*
G01Y650683D02*
Y650093D01*
G01Y648912D02*
Y648321D01*
G01Y650683D02*
Y650093D01*
G01Y652849D02*
Y652258D01*
G01Y654620D02*
Y654030D01*
G01Y652849D02*
Y652258D01*
G01Y654620D02*
Y654030D01*
G01Y658557D02*
Y657967D01*
G01Y660723D02*
Y660132D01*
G01Y656786D02*
Y656195D01*
G01Y658557D02*
Y657967D01*
G01Y660723D02*
Y660132D01*
G01Y656786D02*
Y656195D01*
G01Y662494D02*
Y661904D01*
G01Y664660D02*
Y664069D01*
G01Y662494D02*
Y661904D01*
G01Y664660D02*
Y664069D01*
G01X-10530Y648603D02*
Y646465D01*
G01Y648603D02*
Y646465D01*
G01Y656477D02*
Y654339D01*
G01Y652540D02*
Y650402D01*
G01Y656477D02*
Y654339D01*
G01Y652540D02*
Y650402D01*
G01Y660414D02*
Y658276D01*
G01Y660414D02*
Y658276D01*
G01Y664351D02*
Y662213D01*
G01Y664351D02*
Y662213D01*
G01X-11842Y662271D02*
Y664292D01*
G01Y658334D02*
Y660355D01*
G01Y654397D02*
Y656418D01*
G01Y650460D02*
Y652481D01*
G01Y646523D02*
Y648544D01*
G01D02*
Y646523D01*
G01Y652481D02*
Y650460D01*
G01Y656418D02*
Y654397D01*
G01Y660355D02*
Y658334D01*
G01Y664292D02*
Y662271D01*
G01X-12280Y662277D02*
Y664287D01*
G01Y658340D02*
Y660350D01*
G01Y654403D02*
Y656413D01*
G01Y650466D02*
Y652476D01*
G01Y646528D02*
Y648539D01*
G01D02*
Y646528D01*
G01Y652476D02*
Y650466D01*
G01Y656413D02*
Y654403D01*
G01Y660350D02*
Y658340D01*
G01Y664287D02*
Y662277D01*
G01X-12992Y645014D02*
Y644699D01*
G01Y646431D02*
Y646116D01*
G01Y648951D02*
Y648636D01*
G01Y650368D02*
Y650053D01*
G01Y652888D02*
Y652573D01*
G01Y654305D02*
Y653990D01*
G01Y656825D02*
Y656510D01*
G01Y660762D02*
Y660447D01*
G01Y658242D02*
Y657927D01*
G01Y664699D02*
Y664384D01*
G01Y662179D02*
Y661864D01*
G01X-23684Y662404D02*
Y664160D01*
G01Y658467D02*
Y660223D01*
G01Y650593D02*
Y652349D01*
G01Y654530D02*
Y656286D01*
G01Y646656D02*
Y648412D01*
G01D02*
Y646656D01*
G01Y656286D02*
Y654530D01*
G01Y652349D02*
Y650593D01*
G01Y660223D02*
Y658467D01*
G01Y664160D02*
Y662404D01*
G01X-3150Y664345D02*
X-3377Y664738D01*
G01X-3150Y664345D02*
X-3377Y664738D01*
G01X-3150Y660408D02*
X-3377Y660801D01*
G01X-3150Y660408D02*
X-3377Y660801D01*
G01X-3150Y656471D02*
X-3377Y656864D01*
G01X-3150Y656471D02*
X-3377Y656864D01*
G01X-3150Y652534D02*
X-3377Y652927D01*
G01X-3150Y652534D02*
X-3377Y652927D01*
G01X-3150Y648597D02*
X-3377Y648990D01*
G01X-3150Y648597D02*
X-3377Y648990D01*
G01X-3150Y644660D02*
X-3377Y645053D01*
G01X-3150Y644660D02*
X-3377Y645053D01*
G01X-10630Y668242D02*
X-9843Y668597D01*
G01D02*
X-10630Y668242D01*
G01Y672179D02*
X-9843Y672534D01*
G01D02*
X-10630Y672179D01*
G01Y676116D02*
X-9843Y676471D01*
G01D02*
X-10630Y676116D01*
G01Y680053D02*
X-9843Y680408D01*
G01D02*
X-10630Y680053D01*
G01Y683990D02*
X-9843Y684345D01*
G01D02*
X-10630Y683990D01*
G01X-3377Y684423D02*
X-4258Y684187D01*
G01X-3377Y684423D02*
X-4258Y684187D01*
G01X-3377Y680486D02*
X-4258Y680250D01*
G01X-3377Y680486D02*
X-4258Y680250D01*
G01X-3377Y676549D02*
X-4258Y676313D01*
G01X-3377Y676549D02*
X-4258Y676313D01*
G01X-3377Y672612D02*
X-4258Y672376D01*
G01X-3377Y672612D02*
X-4258Y672376D01*
G01X-3377Y668675D02*
X-4258Y668439D01*
G01X-3377Y668675D02*
X-4258Y668439D01*
G01X-6693Y684345D02*
X-4725Y684660D01*
G01X-6693Y684345D02*
X-4725Y684660D01*
G01X-6693Y680408D02*
X-4725Y680723D01*
G01X-6693Y680408D02*
X-4725Y680723D01*
G01X-6693Y676471D02*
X-4725Y676786D01*
G01X-6693Y676471D02*
X-4725Y676786D01*
G01X-6693Y672534D02*
X-4725Y672849D01*
G01X-6693Y672534D02*
X-4725Y672849D01*
G01X-6693Y668597D02*
X-4725Y668912D01*
G01X-6693Y668597D02*
X-4725Y668912D01*
G01X-3377Y665762D02*
X-3150Y666156D01*
G01X-3377Y665762D02*
X-3150Y666156D01*
G01X-3377Y669699D02*
X-3150Y670093D01*
G01X-3377Y669699D02*
X-3150Y670093D01*
G01X-3377Y673636D02*
X-3150Y674030D01*
G01X-3377Y673636D02*
X-3150Y674030D01*
G01X-3377Y677573D02*
X-3150Y677967D01*
G01X-3377Y677573D02*
X-3150Y677967D01*
G01X-4725Y686116D02*
X-6693D01*
G01X-4725D02*
X-6693D01*
G01X-2196Y685841D02*
X-3150D01*
G01X-2196D02*
X-3150D01*
G01X-4258Y685683D02*
X-4725D01*
G01X-4258D02*
X-4725D01*
G01X-6693Y685526D02*
X-9843D01*
G01X-6693D02*
X-9843D01*
G01X-12992Y685486D02*
X0D01*
G01Y684384D02*
X-12992D01*
G01X-9843Y684345D02*
X-6693D01*
G01X-9843D02*
X-6693D01*
G01X-4725Y684187D02*
X-4258D01*
G01X-4725D02*
X-4258D01*
G01X-3150Y684030D02*
X-2196D01*
G01X-3150D02*
X-2196D01*
G01X-4725Y683754D02*
X-6693D01*
G01X-4725D02*
X-6693D01*
G01X-4725Y682179D02*
X-6693D01*
G01X-4725D02*
X-6693D01*
G01X-2196Y681904D02*
X-3150D01*
G01X-2196D02*
X-3150D01*
G01X-4258Y681746D02*
X-4725D01*
G01X-4258D02*
X-4725D01*
G01X-6693Y681589D02*
X-9843D01*
G01X-6693D02*
X-9843D01*
G01X-12992Y681549D02*
X0D01*
G01Y680447D02*
X-12992D01*
G01X-9843Y680408D02*
X-6693D01*
G01X-9843D02*
X-6693D01*
G01X-4725Y680250D02*
X-4258D01*
G01X-4725D02*
X-4258D01*
G01X-3150Y680093D02*
X-2196D01*
G01X-3150D02*
X-2196D01*
G01X-4725Y679817D02*
X-6693D01*
G01X-4725D02*
X-6693D01*
G01X-4725Y678242D02*
X-6693D01*
G01X-4725D02*
X-6693D01*
G01X-2196Y677967D02*
X-3150D01*
G01X-2196D02*
X-3150D01*
G01X-4258Y677809D02*
X-4725D01*
G01X-4258D02*
X-4725D01*
G01X-6693Y677652D02*
X-9843D01*
G01X-6693D02*
X-9843D01*
G01X-12992Y677612D02*
X0D01*
G01Y676510D02*
X-12992D01*
G01X-9843Y676471D02*
X-6693D01*
G01X-9843D02*
X-6693D01*
G01X-4725Y676313D02*
X-4258D01*
G01X-4725D02*
X-4258D01*
G01X-3150Y676156D02*
X-2196D01*
G01X-3150D02*
X-2196D01*
G01X-4725Y675880D02*
X-6693D01*
G01X-4725D02*
X-6693D01*
G01X-4725Y674305D02*
X-6693D01*
G01X-4725D02*
X-6693D01*
G01X-2196Y674030D02*
X-3150D01*
G01X-2196D02*
X-3150D01*
G01X-4258Y673872D02*
X-4725D01*
G01X-4258D02*
X-4725D01*
G01X-6693Y673715D02*
X-9843D01*
G01X-6693D02*
X-9843D01*
G01X-12992Y673675D02*
X0D01*
G01Y672573D02*
X-12992D01*
G01X-9843Y672534D02*
X-6693D01*
G01X-9843D02*
X-6693D01*
G01X-4725Y672376D02*
X-4258D01*
G01X-4725D02*
X-4258D01*
G01X-3150Y672219D02*
X-2196D01*
G01X-3150D02*
X-2196D01*
G01X-4725Y671943D02*
X-6693D01*
G01X-4725D02*
X-6693D01*
G01X-4725Y670368D02*
X-6693D01*
G01X-4725D02*
X-6693D01*
G01X-2196Y670093D02*
X-3150D01*
G01X-2196D02*
X-3150D01*
G01X-4258Y669935D02*
X-4725D01*
G01X-4258D02*
X-4725D01*
G01X-6693Y669778D02*
X-9843D01*
G01X-6693D02*
X-9843D01*
G01X-12992Y669738D02*
X0D01*
G01Y668636D02*
X-12992D01*
G01X-9843Y668597D02*
X-6693D01*
G01X-9843D02*
X-6693D01*
G01X-4725Y668439D02*
X-4258D01*
G01X-4725D02*
X-4258D01*
G01X-3150Y668282D02*
X-2196D01*
G01X-3150D02*
X-2196D01*
G01X-4725Y668006D02*
X-6693D01*
G01X-4725D02*
X-6693D01*
G01X-4725Y666431D02*
X-6693D01*
G01X-4725D02*
X-6693D01*
G01X-2196Y666156D02*
X-3150D01*
G01X-2196D02*
X-3150D01*
G01X-4258Y665998D02*
X-4725D01*
G01X-4258D02*
X-4725D01*
G01X-6693Y665841D02*
X-9843D01*
G01X-6693D02*
X-9843D01*
G01X-12992Y665801D02*
X0D01*
G01X-3377Y681510D02*
X-3150Y681904D01*
G01X-3377Y681510D02*
X-3150Y681904D01*
G01X-3377Y685447D02*
X-3150Y685841D01*
G01X-3377Y685447D02*
X-3150Y685841D01*
G01X-4258Y685683D02*
X-3377Y685447D01*
G01X-4258Y685683D02*
X-3377Y685447D01*
G01X-4258Y681746D02*
X-3377Y681510D01*
G01X-4258Y681746D02*
X-3377Y681510D01*
G01X-4258Y677809D02*
X-3377Y677573D01*
G01X-4258Y677809D02*
X-3377Y677573D01*
G01X-4725Y685211D02*
X-6693Y685526D01*
G01X-4725Y685211D02*
X-6693Y685526D01*
G01X-4725Y681274D02*
X-6693Y681589D01*
G01X-4725Y681274D02*
X-6693Y681589D01*
G01X-4725Y677337D02*
X-6693Y677652D01*
G01X-4725Y677337D02*
X-6693Y677652D01*
G01X-4725Y673400D02*
X-6693Y673715D01*
G01X-4725Y673400D02*
X-6693Y673715D01*
G01X-4725Y669463D02*
X-6693Y669778D01*
G01X-4725Y669463D02*
X-6693Y669778D01*
G01X-4725Y665526D02*
X-6693Y665841D01*
G01X-4725Y665526D02*
X-6693Y665841D01*
G01X-10630Y685880D02*
X-9843Y685526D01*
G01X-10630Y685880D02*
X-9843Y685526D01*
G01X-10630Y681943D02*
X-9843Y681589D01*
G01X-10630Y681943D02*
X-9843Y681589D01*
G01X-10630Y678006D02*
X-9843Y677652D01*
G01X-10630Y678006D02*
X-9843Y677652D01*
G01X-10630Y674069D02*
X-9843Y673715D01*
G01X-10630Y674069D02*
X-9843Y673715D01*
G01X-10630Y670132D02*
X-9843Y669778D01*
G01X-10630Y670132D02*
X-9843Y669778D01*
G01X-10630Y666195D02*
X-9843Y665841D01*
G01X-10630Y666195D02*
X-9843Y665841D01*
G01X-4258Y673872D02*
X-3377Y673636D01*
G01X-4258Y673872D02*
X-3377Y673636D01*
G01X-4258Y669935D02*
X-3377Y669699D01*
G01X-4258Y669935D02*
X-3377Y669699D01*
G01X-4258Y665998D02*
X-3377Y665762D01*
G01X-4258Y665998D02*
X-3377Y665762D01*
G01X-3756Y668321D02*
Y666116D01*
G01Y672258D02*
Y670053D01*
G01Y676195D02*
Y673990D01*
G01Y684069D02*
Y681864D01*
G01Y680132D02*
Y677927D01*
G01Y688006D02*
Y685801D01*
G01X-4725Y685211D02*
Y686116D01*
G01Y679817D02*
Y680723D01*
G01Y681274D02*
Y682179D01*
G01Y683754D02*
Y684660D01*
G01Y675880D02*
Y676786D01*
G01Y677337D02*
Y678242D01*
G01Y671943D02*
Y672849D01*
G01Y673400D02*
Y674305D01*
G01Y665526D02*
Y666431D01*
G01Y668006D02*
Y668912D01*
G01Y669463D02*
Y670368D01*
G01Y666431D02*
Y665526D01*
G01Y668912D02*
Y668006D01*
G01Y670368D02*
Y669463D01*
G01Y672849D02*
Y671943D01*
G01Y674305D02*
Y673400D01*
G01Y676786D02*
Y675880D01*
G01Y678242D02*
Y677337D01*
G01Y680723D02*
Y679817D01*
G01Y682179D02*
Y681274D01*
G01Y684660D02*
Y683754D01*
G01Y686116D02*
Y685211D01*
G01X-6693Y666431D02*
Y665841D01*
G01Y668597D02*
Y668006D01*
G01Y670368D02*
Y669778D01*
G01Y666431D02*
Y665841D01*
G01Y668597D02*
Y668006D01*
G01Y670368D02*
Y669778D01*
G01Y672534D02*
Y671943D01*
G01Y674305D02*
Y673715D01*
G01Y672534D02*
Y671943D01*
G01Y674305D02*
Y673715D01*
G01Y676471D02*
Y675880D01*
G01Y678242D02*
Y677652D01*
G01Y676471D02*
Y675880D01*
G01Y678242D02*
Y677652D01*
G01Y680408D02*
Y679817D01*
G01Y682179D02*
Y681589D01*
G01Y684345D02*
Y683754D01*
G01Y680408D02*
Y679817D01*
G01Y682179D02*
Y681589D01*
G01Y684345D02*
Y683754D01*
G01Y686116D02*
Y685526D01*
G01Y686116D02*
Y685526D01*
G01X-10530Y668288D02*
Y666150D01*
G01Y668288D02*
Y666150D01*
G01Y672225D02*
Y670087D01*
G01Y672225D02*
Y670087D01*
G01Y680099D02*
Y677961D01*
G01Y676162D02*
Y674024D01*
G01Y680099D02*
Y677961D01*
G01Y676162D02*
Y674024D01*
G01Y684036D02*
Y681898D01*
G01Y684036D02*
Y681898D01*
G01Y687973D02*
Y685835D01*
G01Y687973D02*
Y685835D01*
G01X-11842Y685893D02*
Y687914D01*
G01Y681956D02*
Y683977D01*
G01Y678019D02*
Y680040D01*
G01Y674082D02*
Y676103D01*
G01Y670145D02*
Y672166D01*
G01Y666208D02*
Y668229D01*
G01D02*
Y666208D01*
G01Y672166D02*
Y670145D01*
G01Y676103D02*
Y674082D01*
G01Y680040D02*
Y678019D01*
G01Y683977D02*
Y681956D01*
G01Y687914D02*
Y685893D01*
G01X-12280Y685899D02*
Y687909D01*
G01Y681962D02*
Y683972D01*
G01Y678025D02*
Y680035D01*
G01Y674088D02*
Y676098D01*
G01Y670151D02*
Y672161D01*
G01Y666214D02*
Y668224D01*
G01D02*
Y666214D01*
G01Y672161D02*
Y670151D01*
G01Y676098D02*
Y674088D01*
G01Y680035D02*
Y678025D01*
G01Y683972D02*
Y681962D01*
G01Y687909D02*
Y685899D01*
G01X-12992Y668636D02*
Y668321D01*
G01Y666116D02*
Y665801D01*
G01Y670053D02*
Y669738D01*
G01Y672573D02*
Y672258D01*
G01Y673990D02*
Y673675D01*
G01Y676510D02*
Y676195D01*
G01Y677927D02*
Y677612D01*
G01Y680447D02*
Y680132D01*
G01Y684384D02*
Y684069D01*
G01Y681864D02*
Y681549D01*
G01Y685801D02*
Y685486D01*
G01X-23684Y686026D02*
Y687782D01*
G01Y682089D02*
Y683845D01*
G01Y674215D02*
Y675971D01*
G01Y678152D02*
Y679908D01*
G01Y670278D02*
Y672034D01*
G01Y666341D02*
Y668097D01*
G01D02*
Y666341D01*
G01Y672034D02*
Y670278D01*
G01Y679908D02*
Y678152D01*
G01Y675971D02*
Y674215D01*
G01Y683845D02*
Y682089D01*
G01Y687782D02*
Y686026D01*
G01X-3150Y684030D02*
X-3377Y684423D01*
G01X-3150Y684030D02*
X-3377Y684423D01*
G01X-3150Y680093D02*
X-3377Y680486D01*
G01X-3150Y680093D02*
X-3377Y680486D01*
G01X-3150Y676156D02*
X-3377Y676549D01*
G01X-3150Y676156D02*
X-3377Y676549D01*
G01X-3150Y672219D02*
X-3377Y672612D01*
G01X-3150Y672219D02*
X-3377Y672612D01*
G01X-3150Y668282D02*
X-3377Y668675D01*
G01X-3150Y668282D02*
X-3377Y668675D01*
G01X-10630Y687927D02*
X-9843Y688282D01*
G01D02*
X-10630Y687927D01*
G01Y691864D02*
X-9843Y692219D01*
G01D02*
X-10630Y691864D01*
G01Y695801D02*
X-9843Y696156D01*
G01D02*
X-10630Y695801D01*
G01Y699738D02*
X-9843Y700093D01*
G01D02*
X-10630Y699738D01*
G01X-6693Y700093D02*
X-4725Y700408D01*
G01X-6693Y700093D02*
X-4725Y700408D01*
G01X-6693Y696156D02*
X-4725Y696471D01*
G01X-6693Y696156D02*
X-4725Y696471D01*
G01X-6693Y692219D02*
X-4725Y692534D01*
G01X-6693Y692219D02*
X-4725Y692534D01*
G01X-3377Y700171D02*
X-4258Y699935D01*
G01X-3377Y700171D02*
X-4258Y699935D01*
G01X-3377Y696234D02*
X-4258Y695998D01*
G01X-3377Y696234D02*
X-4258Y695998D01*
G01X-3377Y692297D02*
X-4258Y692061D01*
G01X-3377Y692297D02*
X-4258Y692061D01*
G01X-3377Y688360D02*
X-4258Y688124D01*
G01X-3377Y688360D02*
X-4258Y688124D01*
G01X-6693Y688282D02*
X-4725Y688597D01*
G01X-6693Y688282D02*
X-4725Y688597D01*
G01X0Y700132D02*
X-12992D01*
G01X-9843Y700093D02*
X-6693D01*
G01X-9843D02*
X-6693D01*
G01X-4725Y699935D02*
X-4258D01*
G01X-4725D02*
X-4258D01*
G01X-3150Y699778D02*
X-2196D01*
G01X-3150D02*
X-2196D01*
G01X-4725Y699502D02*
X-6693D01*
G01X-4725D02*
X-6693D01*
G01X-4725Y697927D02*
X-6693D01*
G01X-4725D02*
X-6693D01*
G01X-2196Y697652D02*
X-3150D01*
G01X-2196D02*
X-3150D01*
G01X-4258Y697494D02*
X-4725D01*
G01X-4258D02*
X-4725D01*
G01X-6693Y697337D02*
X-9843D01*
G01X-6693D02*
X-9843D01*
G01X-12992Y697297D02*
X0D01*
G01Y696195D02*
X-12992D01*
G01X-9843Y696156D02*
X-6693D01*
G01X-9843D02*
X-6693D01*
G01X-4725Y695998D02*
X-4258D01*
G01X-4725D02*
X-4258D01*
G01X-3150Y695841D02*
X-2196D01*
G01X-3150D02*
X-2196D01*
G01X-4725Y695565D02*
X-6693D01*
G01X-4725D02*
X-6693D01*
G01X-4725Y693990D02*
X-6693D01*
G01X-4725D02*
X-6693D01*
G01X-2196Y693715D02*
X-3150D01*
G01X-2196D02*
X-3150D01*
G01X-4258Y693557D02*
X-4725D01*
G01X-4258D02*
X-4725D01*
G01X-6693Y693400D02*
X-9843D01*
G01X-6693D02*
X-9843D01*
G01X-12992Y693360D02*
X0D01*
G01Y692258D02*
X-12992D01*
G01X-9843Y692219D02*
X-6693D01*
G01X-9843D02*
X-6693D01*
G01X-4725Y692061D02*
X-4258D01*
G01X-4725D02*
X-4258D01*
G01X-3150Y691904D02*
X-2196D01*
G01X-3150D02*
X-2196D01*
G01X-4725Y691628D02*
X-6693D01*
G01X-4725D02*
X-6693D01*
G01X-4725Y690053D02*
X-6693D01*
G01X-4725D02*
X-6693D01*
G01X-2196Y689778D02*
X-3150D01*
G01X-2196D02*
X-3150D01*
G01X-4258Y689620D02*
X-4725D01*
G01X-4258D02*
X-4725D01*
G01X-6693Y689463D02*
X-9843D01*
G01X-6693D02*
X-9843D01*
G01X-12992Y689423D02*
X0D01*
G01Y688321D02*
X-12992D01*
G01X-9843Y688282D02*
X-6693D01*
G01X-9843D02*
X-6693D01*
G01X-4725Y688124D02*
X-4258D01*
G01X-4725D02*
X-4258D01*
G01X-3150Y687967D02*
X-2196D01*
G01X-3150D02*
X-2196D01*
G01X-4725Y687691D02*
X-6693D01*
G01X-4725D02*
X-6693D01*
G01X-3377Y689384D02*
X-3150Y689778D01*
G01X-3377Y689384D02*
X-3150Y689778D01*
G01X-3377Y693321D02*
X-3150Y693715D01*
G01X-3377Y693321D02*
X-3150Y693715D01*
G01X-3377Y697258D02*
X-3150Y697652D01*
G01X-3377Y697258D02*
X-3150Y697652D01*
G01X-4258Y697494D02*
X-3377Y697258D01*
G01X-4258Y697494D02*
X-3377Y697258D01*
G01X-4258Y693557D02*
X-3377Y693321D01*
G01X-4258Y693557D02*
X-3377Y693321D01*
G01X-4258Y689620D02*
X-3377Y689384D01*
G01X-4258Y689620D02*
X-3377Y689384D01*
G01X-4725Y697022D02*
X-6693Y697337D01*
G01X-4725Y697022D02*
X-6693Y697337D01*
G01X-4725Y693085D02*
X-6693Y693400D01*
G01X-4725Y693085D02*
X-6693Y693400D01*
G01X-4725Y689148D02*
X-6693Y689463D01*
G01X-4725Y689148D02*
X-6693Y689463D01*
G01X-10630Y697691D02*
X-9843Y697337D01*
G01X-10630Y697691D02*
X-9843Y697337D01*
G01X-10630Y693754D02*
X-9843Y693400D01*
G01X-10630Y693754D02*
X-9843Y693400D01*
G01X-10630Y689817D02*
X-9843Y689463D01*
G01X-10630Y689817D02*
X-9843Y689463D01*
G01X-3756Y691943D02*
Y689738D01*
G01Y695880D02*
Y693675D01*
G01Y699817D02*
Y697612D01*
G01X-4725Y699502D02*
Y700408D01*
G01Y695565D02*
Y696471D01*
G01Y697022D02*
Y697927D01*
G01Y689148D02*
Y690053D01*
G01Y691628D02*
Y692534D01*
G01Y693085D02*
Y693990D01*
G01Y687691D02*
Y688597D01*
G01D02*
Y687691D01*
G01Y690053D02*
Y689148D01*
G01Y692534D02*
Y691628D01*
G01Y693990D02*
Y693085D01*
G01Y696471D02*
Y695565D01*
G01Y697927D02*
Y697022D01*
G01Y700408D02*
Y699502D01*
G01X-6693Y688282D02*
Y687691D01*
G01Y688282D02*
Y687691D01*
G01Y690053D02*
Y689463D01*
G01Y692219D02*
Y691628D01*
G01Y693990D02*
Y693400D01*
G01Y690053D02*
Y689463D01*
G01Y692219D02*
Y691628D01*
G01Y693990D02*
Y693400D01*
G01Y696156D02*
Y695565D01*
G01Y697927D02*
Y697337D01*
G01Y696156D02*
Y695565D01*
G01Y697927D02*
Y697337D01*
G01Y700093D02*
Y699502D01*
G01Y700093D02*
Y699502D01*
G01X-10530Y691910D02*
Y689772D01*
G01Y691910D02*
Y689772D01*
G01Y695847D02*
Y693709D01*
G01Y695847D02*
Y693709D01*
G01Y699784D02*
Y697646D01*
G01Y699784D02*
Y697646D01*
G01X-11842Y697704D02*
Y699725D01*
G01Y693767D02*
Y695788D01*
G01Y689830D02*
Y691851D01*
G01D02*
Y689830D01*
G01Y695788D02*
Y693767D01*
G01Y699725D02*
Y697704D01*
G01X-12280Y697710D02*
Y699720D01*
G01Y693773D02*
Y695783D01*
G01Y689836D02*
Y691846D01*
G01D02*
Y689836D01*
G01Y695783D02*
Y693773D01*
G01Y699720D02*
Y697710D01*
G01X-12992Y688321D02*
Y688006D01*
G01Y692258D02*
Y691943D01*
G01Y689738D02*
Y689423D01*
G01Y693675D02*
Y693360D01*
G01Y697612D02*
Y697297D01*
G01Y696195D02*
Y695880D01*
G01Y700132D02*
Y699817D01*
G01X-23684Y697837D02*
Y699593D01*
G01Y693900D02*
Y695656D01*
G01Y689963D02*
Y691719D01*
G01D02*
Y689963D01*
G01Y695656D02*
Y693900D01*
G01Y699593D02*
Y697837D01*
G01X-3150Y699778D02*
X-3377Y700171D01*
G01X-3150Y699778D02*
X-3377Y700171D01*
G01X-3150Y695841D02*
X-3377Y696234D01*
G01X-3150Y695841D02*
X-3377Y696234D01*
G01X-3150Y691904D02*
X-3377Y692297D01*
G01X-3150Y691904D02*
X-3377Y692297D01*
G01X-3150Y687967D02*
X-3377Y688360D01*
G01X-3150Y687967D02*
X-3377Y688360D01*
G01X-9055Y722051D02*
X9842Y721648D01*
G01Y713774D02*
X-9055Y712603D01*
G01Y710624D02*
Y729916D01*
G01X24803D02*
X-9055D01*
G01X9842Y758669D02*
X-9055Y757882D01*
G01Y767331D02*
X9842Y766543D01*
G01X-9055Y750402D02*
X24803D01*
G01X-9055D02*
Y769693D01*
G01X-3466Y790697D02*
X-4258Y790485D01*
G01X-10630Y782414D02*
X-9843Y782768D01*
G01X-10630Y786351D02*
X-9843Y786705D01*
G01X-10630Y790288D02*
X-9843Y790642D01*
G01X-6350Y790697D02*
X-6693Y790642D01*
G01X-6350Y786760D02*
X-6693Y786705D01*
G01X-6350Y782823D02*
X-6693Y782768D01*
G01X-3466Y786760D02*
X-4258Y786548D01*
G01X-3466Y782823D02*
X-4258Y782611D01*
G01X-3150Y792138D02*
X-2196D01*
G01X-4725Y791981D02*
X-4258D01*
G01X-9843Y791823D02*
X-6693D01*
G01X-12992Y791799D02*
X0D01*
G01Y790697D02*
X-12992D01*
G01X-6693Y790642D02*
X-9843D01*
G01X-4258Y790485D02*
X-4725D01*
G01X-3150Y790327D02*
X-2196D01*
G01X-4725Y790052D02*
X-6693D01*
G01X-4725Y788477D02*
X-6693D01*
G01X-3150Y788201D02*
X-2196D01*
G01X-4725Y788044D02*
X-4258D01*
G01X-9843Y787886D02*
X-6693D01*
G01X-12992Y787862D02*
X0D01*
G01Y786760D02*
X-12992D01*
G01X-6693Y786705D02*
X-9843D01*
G01X-4258Y786548D02*
X-4725D01*
G01X-3150Y786390D02*
X-2196D01*
G01X-4725Y786115D02*
X-6693D01*
G01X-4725Y784540D02*
X-6693D01*
G01X-3150Y784264D02*
X-2196D01*
G01X-4725Y784107D02*
X-4258D01*
G01X-9843Y783949D02*
X-6693D01*
G01X-12992Y783925D02*
X0D01*
G01Y782823D02*
X-12992D01*
G01X-6693Y782768D02*
X-9843D01*
G01X-4258Y782611D02*
X-4725D01*
G01X-3150Y782453D02*
X-2196D01*
G01X-4725Y782178D02*
X-6693D01*
G01X-4725Y780603D02*
X-6693D01*
G01X-3150Y780327D02*
X-2196D01*
G01X-4725Y780170D02*
X-4258D01*
G01X-9843Y780012D02*
X-6693D01*
G01X-12992Y779988D02*
X0D01*
G01X-6544Y791799D02*
X-6693Y791823D01*
G01X-6544Y787862D02*
X-6693Y787886D01*
G01X-6544Y783925D02*
X-6693Y783949D01*
G01X-4258Y791981D02*
X-3582Y791799D01*
G01X-4258Y788044D02*
X-3582Y787862D01*
G01X-4258Y784107D02*
X-3582Y783925D01*
G01X-4258Y780170D02*
X-3582Y779988D01*
G01X-6544D02*
X-6693Y780012D01*
G01X-3345Y779988D02*
X-3150Y780327D01*
G01X-3345Y783925D02*
X-3150Y784264D01*
G01X-3345Y787862D02*
X-3150Y788201D01*
G01X-3345Y791799D02*
X-3150Y792138D01*
G01X-10630Y792178D02*
X-9843Y791823D01*
G01X-10630Y788241D02*
X-9843Y787886D01*
G01X-10630Y784304D02*
X-9843Y783949D01*
G01X-10630Y780367D02*
X-9843Y780012D01*
G01X-3150Y790327D02*
X-3363Y790697D01*
G01X-3150Y786390D02*
X-3363Y786760D01*
G01X-3150Y782453D02*
X-3363Y782823D01*
G01X-3756Y782508D02*
Y780303D01*
G01Y786445D02*
Y784240D01*
G01Y790382D02*
Y788177D01*
G01Y794319D02*
Y792114D01*
G01X-4725Y791799D02*
Y792414D01*
G01Y790052D02*
Y790697D01*
G01Y787862D02*
Y788477D01*
G01Y783925D02*
Y784540D01*
G01Y786115D02*
Y786760D01*
G01Y779988D02*
Y780603D01*
G01Y782178D02*
Y782823D01*
G01X-6037Y780303D02*
Y779988D01*
G01Y782823D02*
Y782508D01*
G01Y784240D02*
Y783925D01*
G01Y786760D02*
Y786445D01*
G01Y792114D02*
Y791799D01*
G01Y790697D02*
Y790382D01*
G01Y788177D02*
Y787862D01*
G01X-6693Y782768D02*
Y782178D01*
G01Y780603D02*
Y780012D01*
G01Y786705D02*
Y786115D01*
G01Y784540D02*
Y783949D01*
G01Y792414D02*
Y791823D01*
G01Y788477D02*
Y787886D01*
G01Y790642D02*
Y790052D01*
G01X-9607Y777567D02*
Y823374D01*
G01X-10530Y782459D02*
Y780322D01*
G01Y786396D02*
Y784259D01*
G01Y790333D02*
Y788196D01*
G01Y794270D02*
Y792133D01*
G01X-11966Y782399D02*
Y780382D01*
G01Y786336D02*
Y784319D01*
G01Y790273D02*
Y788256D01*
G01Y794210D02*
Y792193D01*
G01X-12445Y782394D02*
Y780387D01*
G01Y786331D02*
Y784324D01*
G01Y790268D02*
Y788261D01*
G01Y794205D02*
Y792198D01*
G01X-12992Y780303D02*
Y779988D01*
G01Y782823D02*
Y782508D01*
G01Y784240D02*
Y783925D01*
G01Y786760D02*
Y786445D01*
G01Y792114D02*
Y791799D01*
G01Y790697D02*
Y790382D01*
G01Y788177D02*
Y787862D01*
G01X-23518Y782270D02*
Y780510D01*
G01Y786207D02*
Y784447D01*
G01Y790144D02*
Y788384D01*
G01Y794081D02*
Y792321D01*
G01X-3466Y810382D02*
X-4258Y810170D01*
G01X-3466Y806445D02*
X-4258Y806233D01*
G01X-3466Y802508D02*
X-4258Y802296D01*
G01X-3466Y798571D02*
X-4258Y798359D01*
G01X-3466Y794634D02*
X-4258Y794422D01*
G01X-10630Y794225D02*
X-9843Y794579D01*
G01X-10630Y798162D02*
X-9843Y798516D01*
G01X-10630Y802099D02*
X-9843Y802453D01*
G01X-10630Y806036D02*
X-9843Y806390D01*
G01X-10630Y809973D02*
X-9843Y810327D01*
G01X-6350Y810382D02*
X-6693Y810327D01*
G01X-6350Y806445D02*
X-6693Y806390D01*
G01X-6350Y802508D02*
X-6693Y802453D01*
G01X-6350Y798571D02*
X-6693Y798516D01*
G01X-6350Y794634D02*
X-6693Y794579D01*
G01X-4725Y812099D02*
X-6693D01*
G01X-3150Y811823D02*
X-2196D01*
G01X-4725Y811666D02*
X-4258D01*
G01X-9843Y811508D02*
X-6693D01*
G01X-12992Y811484D02*
X0D01*
G01Y810382D02*
X-12992D01*
G01X-6693Y810327D02*
X-9843D01*
G01X-4258Y810170D02*
X-4725D01*
G01X-3150Y810012D02*
X-2196D01*
G01X-4725Y809737D02*
X-6693D01*
G01X-4725Y808162D02*
X-6693D01*
G01X-3150Y807886D02*
X-2196D01*
G01X-4725Y807729D02*
X-4258D01*
G01X-9843Y807571D02*
X-6693D01*
G01X-12992Y807547D02*
X0D01*
G01Y806445D02*
X-12992D01*
G01X-6693Y806390D02*
X-9843D01*
G01X-4258Y806233D02*
X-4725D01*
G01X-3150Y806075D02*
X-2196D01*
G01X-4725Y805800D02*
X-6693D01*
G01X-4725Y804225D02*
X-6693D01*
G01X-3150Y803949D02*
X-2196D01*
G01X-4725Y803792D02*
X-4258D01*
G01X-9843Y803634D02*
X-6693D01*
G01X-12992Y803610D02*
X0D01*
G01Y802508D02*
X-12992D01*
G01X-6693Y802453D02*
X-9843D01*
G01X-4258Y802296D02*
X-4725D01*
G01X-3150Y802138D02*
X-2196D01*
G01X-4725Y801863D02*
X-6693D01*
G01X-4725Y800288D02*
X-6693D01*
G01X-3150Y800012D02*
X-2196D01*
G01X-4725Y799855D02*
X-4258D01*
G01X-9843Y799697D02*
X-6693D01*
G01X-12992Y799673D02*
X0D01*
G01Y798571D02*
X-12992D01*
G01X-6693Y798516D02*
X-9843D01*
G01X-4258Y798359D02*
X-4725D01*
G01X-3150Y798201D02*
X-2196D01*
G01X-4725Y797926D02*
X-6693D01*
G01X-4725Y796351D02*
X-6693D01*
G01X-3150Y796075D02*
X-2196D01*
G01X-4725Y795918D02*
X-4258D01*
G01X-9843Y795760D02*
X-6693D01*
G01X-12992Y795736D02*
X0D01*
G01Y794634D02*
X-12992D01*
G01X-6693Y794579D02*
X-9843D01*
G01X-4258Y794422D02*
X-4725D01*
G01X-3150Y794264D02*
X-2196D01*
G01X-4725Y793989D02*
X-6693D01*
G01X-4725Y792414D02*
X-6693D01*
G01X-6544Y811484D02*
X-6693Y811508D01*
G01X-6544Y807547D02*
X-6693Y807571D01*
G01X-6544Y803610D02*
X-6693Y803634D01*
G01X-6544Y799673D02*
X-6693Y799697D01*
G01X-6544Y795736D02*
X-6693Y795760D01*
G01X-4258Y811666D02*
X-3582Y811484D01*
G01X-4258Y807729D02*
X-3582Y807547D01*
G01X-4258Y803792D02*
X-3582Y803610D01*
G01X-4258Y799855D02*
X-3582Y799673D01*
G01X-4258Y795918D02*
X-3582Y795736D01*
G01X-3345D02*
X-3150Y796075D01*
G01X-3345Y799673D02*
X-3150Y800012D01*
G01X-3345Y803610D02*
X-3150Y803949D01*
G01X-3345Y807547D02*
X-3150Y807886D01*
G01X-3345Y811484D02*
X-3150Y811823D01*
G01X-10630Y811863D02*
X-9843Y811508D01*
G01X-10630Y807926D02*
X-9843Y807571D01*
G01X-10630Y803989D02*
X-9843Y803634D01*
G01X-10630Y800052D02*
X-9843Y799697D01*
G01X-10630Y796115D02*
X-9843Y795760D01*
G01X-3150Y810012D02*
X-3363Y810382D01*
G01X-3150Y806075D02*
X-3363Y806445D01*
G01X-3150Y802138D02*
X-3363Y802508D01*
G01X-3150Y798201D02*
X-3363Y798571D01*
G01X-3150Y794264D02*
X-3363Y794634D01*
G01X-3756Y798256D02*
Y796051D01*
G01Y802193D02*
Y799988D01*
G01Y806130D02*
Y803925D01*
G01Y810067D02*
Y807862D01*
G01Y814004D02*
Y811799D01*
G01X-4725Y811484D02*
Y812099D01*
G01Y809737D02*
Y810382D01*
G01Y807547D02*
Y808162D01*
G01Y805800D02*
Y806445D01*
G01Y803610D02*
Y804225D01*
G01Y801863D02*
Y802508D01*
G01Y799673D02*
Y800288D01*
G01Y797926D02*
Y798571D01*
G01Y795736D02*
Y796351D01*
G01Y793989D02*
Y794634D01*
G01X-6037Y796051D02*
Y795736D01*
G01Y794634D02*
Y794319D01*
G01Y799988D02*
Y799673D01*
G01Y798571D02*
Y798256D01*
G01Y806445D02*
Y806130D01*
G01Y803925D02*
Y803610D01*
G01Y802508D02*
Y802193D01*
G01Y810382D02*
Y810067D01*
G01Y807862D02*
Y807547D01*
G01Y811799D02*
Y811484D01*
G01X-6693Y796351D02*
Y795760D01*
G01Y794579D02*
Y793989D01*
G01Y800288D02*
Y799697D01*
G01Y798516D02*
Y797926D01*
G01Y804225D02*
Y803634D01*
G01Y806390D02*
Y805800D01*
G01Y802453D02*
Y801863D01*
G01Y808162D02*
Y807571D01*
G01Y810327D02*
Y809737D01*
G01Y812099D02*
Y811508D01*
G01X-10530Y798207D02*
Y796070D01*
G01Y802144D02*
Y800007D01*
G01Y806081D02*
Y803944D01*
G01Y810018D02*
Y807881D01*
G01Y813955D02*
Y811818D01*
G01X-11966Y798147D02*
Y796130D01*
G01Y802084D02*
Y800067D01*
G01Y806021D02*
Y804004D01*
G01Y809958D02*
Y807941D01*
G01Y813895D02*
Y811878D01*
G01X-12445Y798142D02*
Y796135D01*
G01Y802079D02*
Y800072D01*
G01Y806016D02*
Y804009D01*
G01Y809953D02*
Y807946D01*
G01Y813890D02*
Y811883D01*
G01X-12992Y796051D02*
Y795736D01*
G01Y794634D02*
Y794319D01*
G01Y799988D02*
Y799673D01*
G01Y798571D02*
Y798256D01*
G01Y806445D02*
Y806130D01*
G01Y803925D02*
Y803610D01*
G01Y802508D02*
Y802193D01*
G01Y810382D02*
Y810067D01*
G01Y807862D02*
Y807547D01*
G01Y811799D02*
Y811484D01*
G01X-23518Y798018D02*
Y796258D01*
G01Y805892D02*
Y804132D01*
G01Y801955D02*
Y800195D01*
G01Y809829D02*
Y808069D01*
G01Y813766D02*
Y812006D01*
G01X-3466Y834004D02*
X-4258Y833792D01*
G01X-3466Y822193D02*
X-4258Y821981D01*
G01X-3466Y818256D02*
X-4258Y818044D01*
G01X-3466Y814319D02*
X-4258Y814107D01*
G01X-10630Y813910D02*
X-9843Y814264D01*
G01X-10630Y817847D02*
X-9843Y818201D01*
G01X-10630Y821784D02*
X-9843Y822138D01*
G01X-6350Y834004D02*
X-6693Y833949D01*
G01X-6350Y822193D02*
X-6693Y822138D01*
G01X-6350Y818256D02*
X-6693Y818201D01*
G01X-6350Y814319D02*
X-6693Y814264D01*
G01X-10630Y833595D02*
X-9843Y833949D01*
G01X0Y834004D02*
X-12992D01*
G01X-6693Y833949D02*
X-9843D01*
G01X-4258Y833792D02*
X-4725D01*
G01X-3150Y833634D02*
X-2196D01*
G01X-4725Y833359D02*
X-6693D01*
G01X-4725Y831784D02*
X-6693D01*
G01X-3150Y831508D02*
X-2196D01*
G01X-4725Y831351D02*
X-4258D01*
G01X-9843Y831193D02*
X-6693D01*
G01X-12992Y831169D02*
X0D01*
G01Y822193D02*
X-12992D01*
G01X-6693Y822138D02*
X-9843D01*
G01X-4258Y821981D02*
X-4725D01*
G01X-3150Y821823D02*
X-2196D01*
G01X-4725Y821548D02*
X-6693D01*
G01X-4725Y819973D02*
X-6693D01*
G01X-3150Y819697D02*
X-2196D01*
G01X-4725Y819540D02*
X-4258D01*
G01X-9843Y819382D02*
X-6693D01*
G01X-12992Y819358D02*
X0D01*
G01Y818256D02*
X-12992D01*
G01X-6693Y818201D02*
X-9843D01*
G01X-4258Y818044D02*
X-4725D01*
G01X-3150Y817886D02*
X-2196D01*
G01X-4725Y817611D02*
X-6693D01*
G01X-4725Y816036D02*
X-6693D01*
G01X-3150Y815760D02*
X-2196D01*
G01X-4725Y815603D02*
X-4258D01*
G01X-9843Y815445D02*
X-6693D01*
G01X-12992Y815421D02*
X0D01*
G01Y814319D02*
X-12992D01*
G01X-6693Y814264D02*
X-9843D01*
G01X-4258Y814107D02*
X-4725D01*
G01X-3150Y813949D02*
X-2196D01*
G01X-4725Y813674D02*
X-6693D01*
G01X-6544Y831169D02*
X-6693Y831193D01*
G01X-6544Y819358D02*
X-6693Y819382D01*
G01X-6544Y815421D02*
X-6693Y815445D01*
G01X-10630Y831548D02*
X-9843Y831193D01*
G01X-4258Y831351D02*
X-3582Y831169D01*
G01X-4258Y819540D02*
X-3582Y819358D01*
G01X-4258Y815603D02*
X-3582Y815421D01*
G01X-3345D02*
X-3150Y815760D01*
G01X-3345Y819358D02*
X-3150Y819697D01*
G01X-10630Y819737D02*
X-9843Y819382D01*
G01X-10630Y815800D02*
X-9843Y815445D01*
G01X-3345Y831169D02*
X-3150Y831508D01*
G01Y833634D02*
X-3363Y834004D01*
G01X-3150Y821823D02*
X-3363Y822193D01*
G01X-3150Y817886D02*
X-3363Y818256D01*
G01X-3150Y813949D02*
X-3363Y814319D01*
G01X-3756Y817941D02*
Y815736D01*
G01Y821878D02*
Y819673D01*
G01Y833689D02*
Y831484D01*
G01X-4725Y833359D02*
Y834004D01*
G01Y831169D02*
Y831784D01*
G01Y821548D02*
Y822193D01*
G01Y817611D02*
Y818256D01*
G01Y819358D02*
Y819973D01*
G01Y813674D02*
Y814319D01*
G01Y815421D02*
Y816036D01*
G01X-6037Y814319D02*
Y814004D01*
G01Y815736D02*
Y815421D01*
G01Y818256D02*
Y817941D01*
G01Y819673D02*
Y819358D01*
G01Y822193D02*
Y821878D01*
G01Y834004D02*
Y833689D01*
G01Y831484D02*
Y831169D01*
G01X-6693Y814264D02*
Y813674D01*
G01Y818201D02*
Y817611D01*
G01Y816036D02*
Y815445D01*
G01Y819973D02*
Y819382D01*
G01Y822138D02*
Y821548D01*
G01Y831784D02*
Y831193D01*
G01Y833949D02*
Y833359D01*
G01X-9607Y830185D02*
Y860303D01*
G01X-10530Y817892D02*
Y815755D01*
G01Y821829D02*
Y819692D01*
G01Y833640D02*
Y831503D01*
G01X-11966Y817832D02*
Y815815D01*
G01Y821769D02*
Y819752D01*
G01Y833580D02*
Y831563D01*
G01X-12445Y817827D02*
Y815820D01*
G01Y821764D02*
Y819757D01*
G01Y833575D02*
Y831568D01*
G01X-12992Y814319D02*
Y814004D01*
G01Y815736D02*
Y815421D01*
G01Y818256D02*
Y817941D01*
G01Y819673D02*
Y819358D01*
G01Y822193D02*
Y821878D01*
G01Y831484D02*
Y831169D01*
G01Y834004D02*
Y833689D01*
G01X-23518Y817703D02*
Y815943D01*
G01Y821640D02*
Y819880D01*
G01Y833451D02*
Y831691D01*
G01X-6350Y853689D02*
X-6693Y853634D01*
G01X-6350Y849752D02*
X-6693Y849697D01*
G01X-6350Y845815D02*
X-6693Y845760D01*
G01X-3466Y853689D02*
X-4258Y853477D01*
G01X-3466Y849752D02*
X-4258Y849540D01*
G01X-3466Y845815D02*
X-4258Y845603D01*
G01X-3466Y841878D02*
X-4258Y841666D01*
G01X-3466Y837941D02*
X-4258Y837729D01*
G01X-4725Y855406D02*
X-6693D01*
G01X-3150Y855130D02*
X-2196D01*
G01X-4258Y854973D02*
X-4725D01*
G01X-6693Y854816D02*
X-9843D01*
G01X-12992Y854791D02*
X0D01*
G01X-6350Y841878D02*
X-6693Y841823D01*
G01X-6350Y837941D02*
X-6693Y837886D01*
G01X-9843D02*
X-10630Y837532D01*
G01Y841469D02*
X-9843Y841823D01*
G01X-10630Y845406D02*
X-9843Y845760D01*
G01X-10630Y849343D02*
X-9843Y849697D01*
G01X-10630Y853280D02*
X-9843Y853634D01*
G01X0Y853689D02*
X-12992D01*
G01X-6693Y853634D02*
X-9843D01*
G01X-4258Y853477D02*
X-4725D01*
G01X-3150Y853319D02*
X-2196D01*
G01X-4725Y853044D02*
X-6693D01*
G01X-4725Y851469D02*
X-6693D01*
G01X-3150Y851193D02*
X-2196D01*
G01X-4725Y851036D02*
X-4258D01*
G01X-9843Y850878D02*
X-6693D01*
G01X-12992Y850854D02*
X0D01*
G01Y849752D02*
X-12992D01*
G01X-6693Y849697D02*
X-9843D01*
G01X-4258Y849540D02*
X-4725D01*
G01X-3150Y849382D02*
X-2196D01*
G01X-4725Y849107D02*
X-6693D01*
G01X-4725Y847532D02*
X-6693D01*
G01X-3150Y847256D02*
X-2196D01*
G01X-4725Y847099D02*
X-4258D01*
G01X-9843Y846941D02*
X-6693D01*
G01X-12992Y846917D02*
X0D01*
G01Y845815D02*
X-12992D01*
G01X-6693Y845760D02*
X-9843D01*
G01X-4258Y845603D02*
X-4725D01*
G01X-3150Y845445D02*
X-2196D01*
G01X-4725Y845170D02*
X-6693D01*
G01X-4725Y843595D02*
X-6693D01*
G01X-3150Y843319D02*
X-2196D01*
G01X-4725Y843162D02*
X-4258D01*
G01X-9843Y843004D02*
X-6693D01*
G01X-12992Y842980D02*
X0D01*
G01Y841878D02*
X-12992D01*
G01X-6693Y841823D02*
X-9843D01*
G01X-4258Y841666D02*
X-4725D01*
G01X-3150Y841508D02*
X-2196D01*
G01X-4725Y841233D02*
X-6693D01*
G01X-4725Y839658D02*
X-6693D01*
G01X-3150Y839382D02*
X-2196D01*
G01X-4725Y839225D02*
X-4258D01*
G01X-9843Y839067D02*
X-6693D01*
G01X-12992Y839043D02*
X0D01*
G01Y837941D02*
X-12992D01*
G01X-6693Y837886D02*
X-9843D01*
G01X-4258Y837729D02*
X-4725D01*
G01X-3150Y837571D02*
X-2196D01*
G01X-4725Y837296D02*
X-6693D01*
G01X-4725Y835721D02*
X-6693D01*
G01X-3150Y835445D02*
X-2196D01*
G01X-4725Y835288D02*
X-4258D01*
G01X-9843Y835130D02*
X-6693D01*
G01X-12992Y835106D02*
X0D01*
G01X-4258Y854973D02*
X-3582Y854791D01*
G01X-4258Y851036D02*
X-3582Y850854D01*
G01X-4258Y847099D02*
X-3582Y846917D01*
G01X-4258Y843162D02*
X-3582Y842980D01*
G01X-4258Y839225D02*
X-3582Y839043D01*
G01X-4258Y835288D02*
X-3582Y835106D01*
G01X-6544Y854791D02*
X-6693Y854816D01*
G01X-6544Y850854D02*
X-6693Y850878D01*
G01X-6544Y846917D02*
X-6693Y846941D01*
G01X-6544Y842980D02*
X-6693Y843004D01*
G01X-6544Y839043D02*
X-6693Y839067D01*
G01X-6544Y835106D02*
X-6693Y835130D01*
G01X-10630Y855170D02*
X-9843Y854816D01*
G01X-10630Y851233D02*
X-9843Y850878D01*
G01X-10630Y847296D02*
X-9843Y846941D01*
G01X-10630Y843359D02*
X-9843Y843004D01*
G01X-10630Y839422D02*
X-9843Y839067D01*
G01X-10630Y835485D02*
X-9843Y835130D01*
G01X-3345Y835106D02*
X-3150Y835445D01*
G01X-3345Y839043D02*
X-3150Y839382D01*
G01X-3345Y842980D02*
X-3150Y843319D01*
G01X-3345Y846917D02*
X-3150Y847256D01*
G01X-3345Y850854D02*
X-3150Y851193D01*
G01X-3345Y854791D02*
X-3150Y855130D01*
G01Y853319D02*
X-3363Y853689D01*
G01X-3150Y849382D02*
X-3363Y849752D01*
G01X-3150Y845445D02*
X-3363Y845815D01*
G01X-3150Y841508D02*
X-3363Y841878D01*
G01X-3150Y837571D02*
X-3363Y837941D01*
G01X-3756Y837626D02*
Y835421D01*
G01Y841563D02*
Y839358D01*
G01Y845500D02*
Y843295D01*
G01Y849437D02*
Y847232D01*
G01Y853374D02*
Y851169D01*
G01Y857311D02*
Y855106D01*
G01X-4725Y853044D02*
Y853689D01*
G01Y854791D02*
Y855406D01*
G01Y849107D02*
Y849752D01*
G01Y850854D02*
Y851469D01*
G01Y845170D02*
Y845815D01*
G01Y846917D02*
Y847532D01*
G01Y841233D02*
Y841878D01*
G01Y842980D02*
Y843595D01*
G01Y839043D02*
Y839658D01*
G01Y837296D02*
Y837941D01*
G01Y835106D02*
Y835721D01*
G01X-6037Y837941D02*
Y837626D01*
G01Y835421D02*
Y835106D01*
G01Y841878D02*
Y841563D01*
G01Y839358D02*
Y839043D01*
G01Y843295D02*
Y842980D01*
G01Y845815D02*
Y845500D01*
G01Y847232D02*
Y846917D01*
G01Y849752D02*
Y849437D01*
G01Y851169D02*
Y850854D01*
G01Y853689D02*
Y853374D01*
G01Y855106D02*
Y854791D01*
G01X-6693Y835721D02*
Y835130D01*
G01Y837886D02*
Y837296D01*
G01Y839658D02*
Y839067D01*
G01Y841823D02*
Y841233D01*
G01Y843595D02*
Y843004D01*
G01Y845760D02*
Y845170D01*
G01Y847532D02*
Y846941D01*
G01Y849697D02*
Y849107D01*
G01Y851469D02*
Y850878D01*
G01Y853634D02*
Y853044D01*
G01Y855406D02*
Y854816D01*
G01X-10530Y837577D02*
Y835440D01*
G01Y845451D02*
Y843314D01*
G01Y841514D02*
Y839377D01*
G01Y849388D02*
Y847251D01*
G01Y853325D02*
Y851188D01*
G01Y857262D02*
Y855125D01*
G01X-11966Y837517D02*
Y835500D01*
G01Y841454D02*
Y839437D01*
G01Y845391D02*
Y843374D01*
G01Y853265D02*
Y851248D01*
G01Y849328D02*
Y847311D01*
G01Y857202D02*
Y855185D01*
G01X-12445Y837512D02*
Y835505D01*
G01Y841449D02*
Y839442D01*
G01Y845386D02*
Y843379D01*
G01Y853260D02*
Y851253D01*
G01Y849323D02*
Y847316D01*
G01Y857197D02*
Y855190D01*
G01X-12992Y837941D02*
Y837626D01*
G01Y835421D02*
Y835106D01*
G01Y841878D02*
Y841563D01*
G01Y839358D02*
Y839043D01*
G01Y843295D02*
Y842980D01*
G01Y845815D02*
Y845500D01*
G01Y847232D02*
Y846917D01*
G01Y849752D02*
Y849437D01*
G01Y851169D02*
Y850854D01*
G01Y853689D02*
Y853374D01*
G01Y855106D02*
Y854791D01*
G01X-23518Y837388D02*
Y835628D01*
G01Y841325D02*
Y839566D01*
G01Y845262D02*
Y843503D01*
G01Y849199D02*
Y847440D01*
G01Y853136D02*
Y851377D01*
G01Y857073D02*
Y855314D01*
G01X-6693Y857571D02*
X-6350Y857626D01*
G01X-3466D02*
X-4258Y857414D01*
G01X0Y857626D02*
X-12992D01*
G01X-9843Y857571D02*
X-6693D01*
G01X-4725Y857414D02*
X-4258D01*
G01X-3150Y857256D02*
X-2196D01*
G01X-4725Y856981D02*
X-6693D01*
G01X9842Y871268D02*
X-9055Y870480D01*
G01X-10630Y857217D02*
X-9843Y857571D01*
G01X-3150Y857256D02*
X-3363Y857626D01*
G01X-4725Y856981D02*
Y857626D01*
G01X-6037D02*
Y857311D01*
G01X-6693Y857571D02*
Y856981D01*
G01X-9055Y887410D02*
Y868118D01*
G01X-12992Y857626D02*
Y857311D01*
G01X-7874Y905988D02*
Y893315D01*
G01X-9055Y879929D02*
X9842Y879142D01*
G01X24803Y887410D02*
X-9055D01*
G01X0Y905988D02*
G03X-7874I-3937J0D01*
G01X0D02*
G03X-7874I-3937J0D01*
G01Y1106301D02*
Y933234D01*
G01D02*
G03X0I3937J0D01*
G01X-7874D02*
G03X0I3937J0D01*
G01Y1106301D02*
G03X-7874I-3937J0D01*
G01X0D02*
G03X-7874I-3937J0D01*
G01Y1280567D02*
Y1129921D01*
G01D02*
G03X0I3937J0D01*
G01X-7874D02*
G03X0I3937J0D01*
G01Y1280567D02*
G03X-7874I-3937J0D01*
G01X0D02*
G03X-7874I-3937J0D01*
G01Y1309889D02*
Y1319286D01*
G01Y1309889D02*
G03X0I3937J0D01*
G01X-7874D02*
G03X0I3937J0D01*
G01X-9055Y1325191D02*
X24803D01*
G01X9842Y1333459D02*
X-9055Y1333055D01*
G01Y1342504D02*
X9842Y1341333D01*
G01X-9055Y1344482D02*
Y1325191D01*
G01X-3377Y1361589D02*
X-4258Y1361353D01*
G01X-3377Y1361589D02*
X-4258Y1361353D01*
G01X-3377Y1357652D02*
X-4258Y1357416D01*
G01X-3377Y1357652D02*
X-4258Y1357416D01*
G01X-6693Y1361510D02*
X-4725Y1361825D01*
G01X-6693Y1361510D02*
X-4725Y1361825D01*
G01X-6693Y1357573D02*
X-4725Y1357888D01*
G01X-6693Y1357573D02*
X-4725Y1357888D01*
G01Y1363282D02*
X-6693D01*
G01X-4725D02*
X-6693D01*
G01X-2196Y1363006D02*
X-3150D01*
G01X-2196D02*
X-3150D01*
G01X-4258Y1362849D02*
X-4725D01*
G01X-4258D02*
X-4725D01*
G01X-6693Y1362691D02*
X-9843D01*
G01X-6693D02*
X-9843D01*
G01X-12992Y1362652D02*
X0D01*
G01Y1361549D02*
X-12992D01*
G01X-9843Y1361510D02*
X-6693D01*
G01X-9843D02*
X-6693D01*
G01X-4725Y1361353D02*
X-4258D01*
G01X-4725D02*
X-4258D01*
G01X-3150Y1361195D02*
X-2196D01*
G01X-3150D02*
X-2196D01*
G01X-4725Y1360919D02*
X-6693D01*
G01X-4725D02*
X-6693D01*
G01X-4725Y1359345D02*
X-6693D01*
G01X-4725D02*
X-6693D01*
G01X-2196Y1359069D02*
X-3150D01*
G01X-2196D02*
X-3150D01*
G01X-4258Y1358912D02*
X-4725D01*
G01X-4258D02*
X-4725D01*
G01X-6693Y1358754D02*
X-9843D01*
G01X-6693D02*
X-9843D01*
G01X-12992Y1358715D02*
X0D01*
G01Y1357612D02*
X-12992D01*
G01X-9843Y1357573D02*
X-6693D01*
G01X-9843D02*
X-6693D01*
G01X-4725Y1357416D02*
X-4258D01*
G01X-4725D02*
X-4258D01*
G01X-3150Y1357258D02*
X-2196D01*
G01X-3150D02*
X-2196D01*
G01X-4725Y1356982D02*
X-6693D01*
G01X-4725D02*
X-6693D01*
G01X-4725Y1355408D02*
X-6693D01*
G01X-4725D02*
X-6693D01*
G01X-2196Y1355132D02*
X-3150D01*
G01X-2196D02*
X-3150D01*
G01X-4258Y1354975D02*
X-4725D01*
G01X-4258D02*
X-4725D01*
G01X-6693Y1354817D02*
X-9843D01*
G01X-6693D02*
X-9843D01*
G01X-12992Y1354778D02*
X0D01*
G01X-4725Y1362376D02*
X-6693Y1362691D01*
G01X-4725Y1362376D02*
X-6693Y1362691D01*
G01X-4725Y1358439D02*
X-6693Y1358754D01*
G01X-4725Y1358439D02*
X-6693Y1358754D01*
G01X-4725Y1354502D02*
X-6693Y1354817D01*
G01X-4725Y1354502D02*
X-6693Y1354817D01*
G01X-4258Y1362849D02*
X-3377Y1362612D01*
G01X-4258Y1362849D02*
X-3377Y1362612D01*
G01X-4258Y1358912D02*
X-3377Y1358675D01*
G01X-4258Y1358912D02*
X-3377Y1358675D01*
G01X-4258Y1354975D02*
X-3377Y1354738D01*
G01X-4258Y1354975D02*
X-3377Y1354738D01*
G01X-9843Y1362691D02*
X-10630Y1363045D01*
G01D02*
X-9843Y1362691D01*
G01Y1358754D02*
X-10630Y1359108D01*
G01D02*
X-9843Y1358754D01*
G01Y1354817D02*
X-10630Y1355171D01*
G01D02*
X-9843Y1354817D01*
G01X-3150Y1361195D02*
X-3377Y1361589D01*
G01X-3150Y1361195D02*
X-3377Y1361589D01*
G01X-3150Y1357258D02*
X-3377Y1357652D01*
G01X-3150Y1357258D02*
X-3377Y1357652D01*
G01X-10630Y1357219D02*
X-9843Y1357573D01*
G01D02*
X-10630Y1357219D01*
G01Y1361156D02*
X-9843Y1361510D01*
G01D02*
X-10630Y1361156D01*
G01X-3756Y1357297D02*
Y1355093D01*
G01Y1361234D02*
Y1359030D01*
G01Y1365171D02*
Y1362967D01*
G01X-4725Y1358439D02*
Y1359345D01*
G01Y1360919D02*
Y1361825D01*
G01Y1362376D02*
Y1363282D01*
G01Y1354502D02*
Y1355408D01*
G01Y1356982D02*
Y1357888D01*
G01Y1355408D02*
Y1354502D01*
G01Y1357888D02*
Y1356982D01*
G01Y1359345D02*
Y1358439D01*
G01Y1361825D02*
Y1360919D01*
G01Y1363282D02*
Y1362376D01*
G01X-6693Y1355408D02*
Y1354817D01*
G01Y1357573D02*
Y1356982D01*
G01Y1355408D02*
Y1354817D01*
G01Y1357573D02*
Y1356982D01*
G01Y1359345D02*
Y1358754D01*
G01Y1361510D02*
Y1360919D01*
G01Y1363282D02*
Y1362691D01*
G01Y1359345D02*
Y1358754D01*
G01Y1361510D02*
Y1360919D01*
G01Y1363282D02*
Y1362691D01*
G01X-8898Y1352356D02*
Y1398164D01*
G01X-10530Y1357264D02*
Y1355127D01*
G01Y1357264D02*
Y1355127D01*
G01Y1361201D02*
Y1359064D01*
G01Y1361201D02*
Y1359064D01*
G01Y1365138D02*
Y1363001D01*
G01Y1365138D02*
Y1363001D01*
G01X-11842Y1363059D02*
Y1365079D01*
G01Y1359122D02*
Y1361142D01*
G01Y1355185D02*
Y1357205D01*
G01D02*
Y1355185D01*
G01Y1361142D02*
Y1359122D01*
G01Y1365079D02*
Y1363059D01*
G01X-12280Y1363064D02*
Y1365074D01*
G01Y1359127D02*
Y1361137D01*
G01Y1355190D02*
Y1357200D01*
G01D02*
Y1355190D01*
G01Y1361137D02*
Y1359127D01*
G01Y1365074D02*
Y1363064D01*
G01X-12992Y1357612D02*
Y1357297D01*
G01Y1355093D02*
Y1354778D01*
G01Y1362967D02*
Y1362652D01*
G01Y1361549D02*
Y1361234D01*
G01Y1359030D02*
Y1358715D01*
G01X-23684Y1363191D02*
Y1364947D01*
G01Y1359254D02*
Y1361010D01*
G01Y1355317D02*
Y1357073D01*
G01D02*
Y1355317D01*
G01Y1361010D02*
Y1359254D01*
G01Y1364947D02*
Y1363191D01*
G01X-3377Y1354738D02*
X-3150Y1355132D01*
G01X-3377Y1354738D02*
X-3150Y1355132D01*
G01X-3377Y1358675D02*
X-3150Y1359069D01*
G01X-3377Y1358675D02*
X-3150Y1359069D01*
G01X-3377Y1362612D02*
X-3150Y1363006D01*
G01X-3377Y1362612D02*
X-3150Y1363006D01*
G01X-3377Y1381274D02*
X-4258Y1381038D01*
G01X-3377Y1381274D02*
X-4258Y1381038D01*
G01X-3377Y1377337D02*
X-4258Y1377101D01*
G01X-3377Y1377337D02*
X-4258Y1377101D01*
G01X-3377Y1373400D02*
X-4258Y1373164D01*
G01X-3377Y1373400D02*
X-4258Y1373164D01*
G01X-3377Y1369463D02*
X-4258Y1369227D01*
G01X-3377Y1369463D02*
X-4258Y1369227D01*
G01X-3377Y1365526D02*
X-4258Y1365290D01*
G01X-3377Y1365526D02*
X-4258Y1365290D01*
G01X-6693Y1381195D02*
X-4725Y1381510D01*
G01X-6693Y1381195D02*
X-4725Y1381510D01*
G01X-6693Y1377258D02*
X-4725Y1377573D01*
G01X-6693Y1377258D02*
X-4725Y1377573D01*
G01X-6693Y1373321D02*
X-4725Y1373636D01*
G01X-6693Y1373321D02*
X-4725Y1373636D01*
G01X-6693Y1369384D02*
X-4725Y1369699D01*
G01X-6693Y1369384D02*
X-4725Y1369699D01*
G01X-6693Y1365447D02*
X-4725Y1365762D01*
G01X-6693Y1365447D02*
X-4725Y1365762D01*
G01Y1384541D02*
X-6693D01*
G01X-4725D02*
X-6693D01*
G01X-4725Y1382967D02*
X-6693D01*
G01X-4725D02*
X-6693D01*
G01X-2196Y1382691D02*
X-3150D01*
G01X-2196D02*
X-3150D01*
G01X-4258Y1382534D02*
X-4725D01*
G01X-4258D02*
X-4725D01*
G01X-6693Y1382376D02*
X-9843D01*
G01X-6693D02*
X-9843D01*
G01X-12992Y1382337D02*
X0D01*
G01Y1381234D02*
X-12992D01*
G01X-9843Y1381195D02*
X-6693D01*
G01X-9843D02*
X-6693D01*
G01X-4725Y1381038D02*
X-4258D01*
G01X-4725D02*
X-4258D01*
G01X-3150Y1380880D02*
X-2196D01*
G01X-3150D02*
X-2196D01*
G01X-4725Y1380604D02*
X-6693D01*
G01X-4725D02*
X-6693D01*
G01X-4725Y1379030D02*
X-6693D01*
G01X-4725D02*
X-6693D01*
G01X-2196Y1378754D02*
X-3150D01*
G01X-2196D02*
X-3150D01*
G01X-4258Y1378597D02*
X-4725D01*
G01X-4258D02*
X-4725D01*
G01X-6693Y1378439D02*
X-9843D01*
G01X-6693D02*
X-9843D01*
G01X-12992Y1378400D02*
X0D01*
G01Y1377297D02*
X-12992D01*
G01X-9843Y1377258D02*
X-6693D01*
G01X-9843D02*
X-6693D01*
G01X-4725Y1377101D02*
X-4258D01*
G01X-4725D02*
X-4258D01*
G01X-3150Y1376943D02*
X-2196D01*
G01X-3150D02*
X-2196D01*
G01X-4725Y1376667D02*
X-6693D01*
G01X-4725D02*
X-6693D01*
G01X-4725Y1375093D02*
X-6693D01*
G01X-4725D02*
X-6693D01*
G01X-2196Y1374817D02*
X-3150D01*
G01X-2196D02*
X-3150D01*
G01X-4258Y1374660D02*
X-4725D01*
G01X-4258D02*
X-4725D01*
G01X-6693Y1374502D02*
X-9843D01*
G01X-6693D02*
X-9843D01*
G01X-12992Y1374463D02*
X0D01*
G01Y1373360D02*
X-12992D01*
G01X-9843Y1373321D02*
X-6693D01*
G01X-9843D02*
X-6693D01*
G01X-4725Y1373164D02*
X-4258D01*
G01X-4725D02*
X-4258D01*
G01X-3150Y1373006D02*
X-2196D01*
G01X-3150D02*
X-2196D01*
G01X-4725Y1372730D02*
X-6693D01*
G01X-4725D02*
X-6693D01*
G01X-4725Y1371156D02*
X-6693D01*
G01X-4725D02*
X-6693D01*
G01X-2196Y1370880D02*
X-3150D01*
G01X-2196D02*
X-3150D01*
G01X-4258Y1370723D02*
X-4725D01*
G01X-4258D02*
X-4725D01*
G01X-6693Y1370565D02*
X-9843D01*
G01X-6693D02*
X-9843D01*
G01X-12992Y1370526D02*
X0D01*
G01Y1369423D02*
X-12992D01*
G01X-9843Y1369384D02*
X-6693D01*
G01X-9843D02*
X-6693D01*
G01X-4725Y1369227D02*
X-4258D01*
G01X-4725D02*
X-4258D01*
G01X-3150Y1369069D02*
X-2196D01*
G01X-3150D02*
X-2196D01*
G01X-4725Y1368793D02*
X-6693D01*
G01X-4725D02*
X-6693D01*
G01X-4725Y1367219D02*
X-6693D01*
G01X-4725D02*
X-6693D01*
G01X-2196Y1366943D02*
X-3150D01*
G01X-2196D02*
X-3150D01*
G01X-4258Y1366786D02*
X-4725D01*
G01X-4258D02*
X-4725D01*
G01X-6693Y1366628D02*
X-9843D01*
G01X-6693D02*
X-9843D01*
G01X-12992Y1366589D02*
X0D01*
G01Y1365486D02*
X-12992D01*
G01X-9843Y1365447D02*
X-6693D01*
G01X-9843D02*
X-6693D01*
G01X-4725Y1365290D02*
X-4258D01*
G01X-4725D02*
X-4258D01*
G01X-3150Y1365132D02*
X-2196D01*
G01X-3150D02*
X-2196D01*
G01X-4725Y1364856D02*
X-6693D01*
G01X-4725D02*
X-6693D01*
G01X-4725Y1382061D02*
X-6693Y1382376D01*
G01X-4725Y1382061D02*
X-6693Y1382376D01*
G01X-4725Y1378124D02*
X-6693Y1378439D01*
G01X-4725Y1378124D02*
X-6693Y1378439D01*
G01X-4725Y1374187D02*
X-6693Y1374502D01*
G01X-4725Y1374187D02*
X-6693Y1374502D01*
G01X-4725Y1370250D02*
X-6693Y1370565D01*
G01X-4725Y1370250D02*
X-6693Y1370565D01*
G01X-4725Y1366313D02*
X-6693Y1366628D01*
G01X-4725Y1366313D02*
X-6693Y1366628D01*
G01X-4258Y1382534D02*
X-3377Y1382297D01*
G01X-4258Y1382534D02*
X-3377Y1382297D01*
G01X-4258Y1378597D02*
X-3377Y1378360D01*
G01X-4258Y1378597D02*
X-3377Y1378360D01*
G01X-4258Y1374660D02*
X-3377Y1374423D01*
G01X-4258Y1374660D02*
X-3377Y1374423D01*
G01X-4258Y1370723D02*
X-3377Y1370486D01*
G01X-4258Y1370723D02*
X-3377Y1370486D01*
G01X-4258Y1366786D02*
X-3377Y1366549D01*
G01X-4258Y1366786D02*
X-3377Y1366549D01*
G01X-9843Y1382376D02*
X-10630Y1382730D01*
G01D02*
X-9843Y1382376D01*
G01Y1378439D02*
X-10630Y1378793D01*
G01D02*
X-9843Y1378439D01*
G01Y1374502D02*
X-10630Y1374856D01*
G01D02*
X-9843Y1374502D01*
G01Y1370565D02*
X-10630Y1370919D01*
G01D02*
X-9843Y1370565D01*
G01Y1366628D02*
X-10630Y1366982D01*
G01D02*
X-9843Y1366628D01*
G01X-3150Y1380880D02*
X-3377Y1381274D01*
G01X-3150Y1380880D02*
X-3377Y1381274D01*
G01X-3150Y1376943D02*
X-3377Y1377337D01*
G01X-3150Y1376943D02*
X-3377Y1377337D01*
G01X-3150Y1373006D02*
X-3377Y1373400D01*
G01X-3150Y1373006D02*
X-3377Y1373400D01*
G01X-3150Y1369069D02*
X-3377Y1369463D01*
G01X-3150Y1369069D02*
X-3377Y1369463D01*
G01X-3150Y1365132D02*
X-3377Y1365526D01*
G01X-3150Y1365132D02*
X-3377Y1365526D01*
G01X-10630Y1365093D02*
X-9843Y1365447D01*
G01D02*
X-10630Y1365093D01*
G01Y1369030D02*
X-9843Y1369384D01*
G01D02*
X-10630Y1369030D01*
G01Y1372967D02*
X-9843Y1373321D01*
G01D02*
X-10630Y1372967D01*
G01Y1376904D02*
X-9843Y1377258D01*
G01D02*
X-10630Y1376904D01*
G01Y1380841D02*
X-9843Y1381195D01*
G01D02*
X-10630Y1380841D01*
G01X-3756Y1369108D02*
Y1366904D01*
G01Y1373045D02*
Y1370841D01*
G01Y1376982D02*
Y1374778D01*
G01Y1380919D02*
Y1378715D01*
G01Y1384856D02*
Y1382652D01*
G01X-4725Y1382061D02*
Y1382967D01*
G01Y1384541D02*
Y1385447D01*
G01Y1378124D02*
Y1379030D01*
G01Y1380604D02*
Y1381510D01*
G01Y1372730D02*
Y1373636D01*
G01Y1374187D02*
Y1375093D01*
G01Y1376667D02*
Y1377573D01*
G01Y1368793D02*
Y1369699D01*
G01Y1370250D02*
Y1371156D01*
G01Y1364856D02*
Y1365762D01*
G01Y1366313D02*
Y1367219D01*
G01Y1365762D02*
Y1364856D01*
G01Y1367219D02*
Y1366313D01*
G01Y1369699D02*
Y1368793D01*
G01Y1371156D02*
Y1370250D01*
G01Y1373636D02*
Y1372730D01*
G01Y1375093D02*
Y1374187D01*
G01Y1377573D02*
Y1376667D01*
G01Y1379030D02*
Y1378124D01*
G01Y1381510D02*
Y1380604D01*
G01Y1382967D02*
Y1382061D01*
G01Y1385447D02*
Y1384541D01*
G01X-6693Y1365447D02*
Y1364856D01*
G01Y1367219D02*
Y1366628D01*
G01Y1365447D02*
Y1364856D01*
G01Y1367219D02*
Y1366628D01*
G01Y1369384D02*
Y1368793D01*
G01Y1371156D02*
Y1370565D01*
G01Y1369384D02*
Y1368793D01*
G01Y1371156D02*
Y1370565D01*
G01Y1373321D02*
Y1372730D01*
G01Y1375093D02*
Y1374502D01*
G01Y1377258D02*
Y1376667D01*
G01Y1373321D02*
Y1372730D01*
G01Y1375093D02*
Y1374502D01*
G01Y1377258D02*
Y1376667D01*
G01Y1379030D02*
Y1378439D01*
G01Y1381195D02*
Y1380604D01*
G01Y1379030D02*
Y1378439D01*
G01Y1381195D02*
Y1380604D01*
G01Y1382967D02*
Y1382376D01*
G01Y1385132D02*
Y1384541D01*
G01Y1382967D02*
Y1382376D01*
G01Y1385132D02*
Y1384541D01*
G01X-10530Y1369075D02*
Y1366938D01*
G01Y1369075D02*
Y1366938D01*
G01Y1376949D02*
Y1374812D01*
G01Y1373012D02*
Y1370875D01*
G01Y1376949D02*
Y1374812D01*
G01Y1373012D02*
Y1370875D01*
G01Y1380886D02*
Y1378749D01*
G01Y1380886D02*
Y1378749D01*
G01Y1384823D02*
Y1382686D01*
G01Y1384823D02*
Y1382686D01*
G01X-11842Y1382744D02*
Y1384764D01*
G01Y1378807D02*
Y1380827D01*
G01Y1374870D02*
Y1376890D01*
G01Y1370933D02*
Y1372953D01*
G01Y1366996D02*
Y1369016D01*
G01D02*
Y1366996D01*
G01Y1372953D02*
Y1370933D01*
G01Y1376890D02*
Y1374870D01*
G01Y1380827D02*
Y1378807D01*
G01Y1384764D02*
Y1382744D01*
G01X-12280Y1382749D02*
Y1384759D01*
G01Y1378812D02*
Y1380822D01*
G01Y1374875D02*
Y1376885D01*
G01Y1370938D02*
Y1372948D01*
G01Y1367001D02*
Y1369011D01*
G01D02*
Y1367001D01*
G01Y1372948D02*
Y1370938D01*
G01Y1376885D02*
Y1374875D01*
G01Y1380822D02*
Y1378812D01*
G01Y1384759D02*
Y1382749D01*
G01X-12992Y1366904D02*
Y1366589D01*
G01Y1365486D02*
Y1365171D01*
G01Y1370841D02*
Y1370526D01*
G01Y1369423D02*
Y1369108D01*
G01Y1377297D02*
Y1376982D01*
G01Y1374778D02*
Y1374463D01*
G01Y1373360D02*
Y1373045D01*
G01Y1381234D02*
Y1380919D01*
G01Y1378715D02*
Y1378400D01*
G01Y1382652D02*
Y1382337D01*
G01X-23684Y1382876D02*
Y1384632D01*
G01Y1378939D02*
Y1380695D01*
G01Y1375002D02*
Y1376758D01*
G01Y1367128D02*
Y1368884D01*
G01Y1371065D02*
Y1372821D01*
G01D02*
Y1371065D01*
G01Y1368884D02*
Y1367128D01*
G01Y1376758D02*
Y1375002D01*
G01Y1380695D02*
Y1378939D01*
G01Y1384632D02*
Y1382876D01*
G01X-3377Y1366549D02*
X-3150Y1366943D01*
G01X-3377Y1366549D02*
X-3150Y1366943D01*
G01X-3377Y1370486D02*
X-3150Y1370880D01*
G01X-3377Y1370486D02*
X-3150Y1370880D01*
G01X-3377Y1374423D02*
X-3150Y1374817D01*
G01X-3377Y1374423D02*
X-3150Y1374817D01*
G01X-3377Y1378360D02*
X-3150Y1378754D01*
G01X-3377Y1378360D02*
X-3150Y1378754D01*
G01X-3377Y1382297D02*
X-3150Y1382691D01*
G01X-3377Y1382297D02*
X-3150Y1382691D01*
G01X-6693Y1396943D02*
X-4725Y1397258D01*
G01X-6693Y1396943D02*
X-4725Y1397258D01*
G01X-6693Y1393006D02*
X-4725Y1393321D01*
G01X-6693Y1393006D02*
X-4725Y1393321D01*
G01X-6693Y1389069D02*
X-4725Y1389384D01*
G01X-6693Y1389069D02*
X-4725Y1389384D01*
G01X-6693Y1385132D02*
X-4725Y1385447D01*
G01X-6693Y1385132D02*
X-4725Y1385447D01*
G01X-3377Y1397022D02*
X-4258Y1396786D01*
G01X-3377Y1397022D02*
X-4258Y1396786D01*
G01X-3377Y1393085D02*
X-4258Y1392849D01*
G01X-3377Y1393085D02*
X-4258Y1392849D01*
G01X-3377Y1389148D02*
X-4258Y1388912D01*
G01X-3377Y1389148D02*
X-4258Y1388912D01*
G01X-3377Y1385211D02*
X-4258Y1384975D01*
G01X-3377Y1385211D02*
X-4258Y1384975D01*
G01X0Y1396982D02*
X-12992D01*
G01X-9843Y1396943D02*
X-6693D01*
G01X-9843D02*
X-6693D01*
G01X-4725Y1396786D02*
X-4258D01*
G01X-4725D02*
X-4258D01*
G01X-3150Y1396628D02*
X-2196D01*
G01X-3150D02*
X-2196D01*
G01X-4725Y1396353D02*
X-6693D01*
G01X-4725D02*
X-6693D01*
G01X-4725Y1394778D02*
X-6693D01*
G01X-4725D02*
X-6693D01*
G01X-2196Y1394502D02*
X-3150D01*
G01X-2196D02*
X-3150D01*
G01X-4258Y1394345D02*
X-4725D01*
G01X-4258D02*
X-4725D01*
G01X-6693Y1394187D02*
X-9843D01*
G01X-6693D02*
X-9843D01*
G01X-12992Y1394148D02*
X0D01*
G01Y1393045D02*
X-12992D01*
G01X-9843Y1393006D02*
X-6693D01*
G01X-9843D02*
X-6693D01*
G01X-4725Y1392849D02*
X-4258D01*
G01X-4725D02*
X-4258D01*
G01X-3150Y1392691D02*
X-2196D01*
G01X-3150D02*
X-2196D01*
G01X-4725Y1392416D02*
X-6693D01*
G01X-4725D02*
X-6693D01*
G01X-4725Y1390841D02*
X-6693D01*
G01X-4725D02*
X-6693D01*
G01X-2196Y1390565D02*
X-3150D01*
G01X-2196D02*
X-3150D01*
G01X-4258Y1390408D02*
X-4725D01*
G01X-4258D02*
X-4725D01*
G01X-6693Y1390250D02*
X-9843D01*
G01X-6693D02*
X-9843D01*
G01X-12992Y1390211D02*
X0D01*
G01Y1389108D02*
X-12992D01*
G01X-9843Y1389069D02*
X-6693D01*
G01X-9843D02*
X-6693D01*
G01X-4725Y1388912D02*
X-4258D01*
G01X-4725D02*
X-4258D01*
G01X-3150Y1388754D02*
X-2196D01*
G01X-3150D02*
X-2196D01*
G01X-4725Y1388478D02*
X-6693D01*
G01X-4725D02*
X-6693D01*
G01X-4725Y1405683D02*
X-6693Y1405998D01*
G01X-4725Y1405683D02*
X-6693Y1405998D01*
G01X-4725Y1386904D02*
X-6693D01*
G01X-4725D02*
X-6693D01*
G01X-2196Y1386628D02*
X-3150D01*
G01X-2196D02*
X-3150D01*
G01X-4258Y1386471D02*
X-4725D01*
G01X-4258D02*
X-4725D01*
G01X-6693Y1386313D02*
X-9843D01*
G01X-6693D02*
X-9843D01*
G01X-12992Y1386274D02*
X0D01*
G01Y1385171D02*
X-12992D01*
G01X-9843Y1385132D02*
X-6693D01*
G01X-9843D02*
X-6693D01*
G01X-4725Y1384975D02*
X-4258D01*
G01X-4725D02*
X-4258D01*
G01X-3150Y1384817D02*
X-2196D01*
G01X-3150D02*
X-2196D01*
G01X-4258Y1394345D02*
X-3377Y1394108D01*
G01X-4258Y1394345D02*
X-3377Y1394108D01*
G01X-4258Y1390408D02*
X-3377Y1390171D01*
G01X-4258Y1390408D02*
X-3377Y1390171D01*
G01X-4258Y1386471D02*
X-3377Y1386234D01*
G01X-4258Y1386471D02*
X-3377Y1386234D01*
G01X-4725Y1393872D02*
X-6693Y1394187D01*
G01X-4725Y1393872D02*
X-6693Y1394187D01*
G01X-4725Y1389935D02*
X-6693Y1390250D01*
G01X-4725Y1389935D02*
X-6693Y1390250D01*
G01X-4725Y1385998D02*
X-6693Y1386313D01*
G01X-4725Y1385998D02*
X-6693Y1386313D01*
G01X-9843Y1394187D02*
X-10630Y1394541D01*
G01D02*
X-9843Y1394187D01*
G01Y1390250D02*
X-10630Y1390604D01*
G01D02*
X-9843Y1390250D01*
G01Y1386313D02*
X-10630Y1386667D01*
G01D02*
X-9843Y1386313D01*
G01X-3150Y1396628D02*
X-3377Y1397022D01*
G01X-3150Y1396628D02*
X-3377Y1397022D01*
G01X-3150Y1392691D02*
X-3377Y1393085D01*
G01X-3150Y1392691D02*
X-3377Y1393085D01*
G01X-3150Y1388754D02*
X-3377Y1389148D01*
G01X-3150Y1388754D02*
X-3377Y1389148D01*
G01X-3150Y1384817D02*
X-3377Y1385211D01*
G01X-3150Y1384817D02*
X-3377Y1385211D01*
G01X-10630Y1384778D02*
X-9843Y1385132D01*
G01D02*
X-10630Y1384778D01*
G01Y1388715D02*
X-9843Y1389069D01*
G01D02*
X-10630Y1388715D01*
G01Y1392652D02*
X-9843Y1393006D01*
G01D02*
X-10630Y1392652D01*
G01Y1396589D02*
X-9843Y1396943D01*
G01D02*
X-10630Y1396589D01*
G01X-3756Y1388793D02*
Y1386589D01*
G01Y1392730D02*
Y1390526D01*
G01Y1396667D02*
Y1394463D01*
G01X-4725Y1405683D02*
Y1406589D01*
G01Y1396353D02*
Y1397258D01*
G01Y1392416D02*
Y1393321D01*
G01Y1393872D02*
Y1394778D01*
G01Y1388478D02*
Y1389384D01*
G01Y1389935D02*
Y1390841D01*
G01Y1385998D02*
Y1386904D01*
G01D02*
Y1385998D01*
G01Y1389384D02*
Y1388478D01*
G01Y1390841D02*
Y1389935D01*
G01Y1393321D02*
Y1392416D01*
G01Y1394778D02*
Y1393872D01*
G01Y1397258D02*
Y1396353D01*
G01Y1406589D02*
Y1405683D01*
G01X-6693Y1386904D02*
Y1386313D01*
G01Y1386904D02*
Y1386313D01*
G01Y1389069D02*
Y1388478D01*
G01Y1390841D02*
Y1390250D01*
G01Y1389069D02*
Y1388478D01*
G01Y1390841D02*
Y1390250D01*
G01Y1393006D02*
Y1392416D01*
G01Y1394778D02*
Y1394187D01*
G01Y1393006D02*
Y1392416D01*
G01Y1394778D02*
Y1394187D01*
G01Y1396943D02*
Y1396353D01*
G01Y1396943D02*
Y1396353D01*
G01X-8898Y1404975D02*
Y1687199D01*
G01X-10530Y1388760D02*
Y1386623D01*
G01Y1388760D02*
Y1386623D01*
G01Y1392697D02*
Y1390560D01*
G01Y1392697D02*
Y1390560D01*
G01Y1396634D02*
Y1394497D01*
G01Y1396634D02*
Y1394497D01*
G01X-11842Y1394555D02*
Y1396575D01*
G01Y1390618D02*
Y1392638D01*
G01Y1386681D02*
Y1388701D01*
G01D02*
Y1386681D01*
G01Y1392638D02*
Y1390618D01*
G01Y1396575D02*
Y1394555D01*
G01X-12280Y1394560D02*
Y1396570D01*
G01Y1390623D02*
Y1392633D01*
G01Y1386686D02*
Y1388696D01*
G01D02*
Y1386686D01*
G01Y1392633D02*
Y1390623D01*
G01Y1396570D02*
Y1394560D01*
G01X-12992Y1386589D02*
Y1386274D01*
G01Y1385171D02*
Y1384856D01*
G01Y1390526D02*
Y1390211D01*
G01Y1389108D02*
Y1388793D01*
G01Y1394463D02*
Y1394148D01*
G01Y1393045D02*
Y1392730D01*
G01Y1396982D02*
Y1396667D01*
G01X-23684Y1394687D02*
Y1396443D01*
G01Y1390750D02*
Y1392506D01*
G01Y1386813D02*
Y1388569D01*
G01D02*
Y1386813D01*
G01Y1392506D02*
Y1390750D01*
G01Y1396443D02*
Y1394687D01*
G01X-3377Y1386234D02*
X-3150Y1386628D01*
G01X-3377Y1386234D02*
X-3150Y1386628D01*
G01X-3377Y1390171D02*
X-3150Y1390565D01*
G01X-3377Y1390171D02*
X-3150Y1390565D01*
G01X-3377Y1394108D02*
X-3150Y1394502D01*
G01X-3377Y1394108D02*
X-3150Y1394502D01*
G01X-3377Y1424581D02*
X-4258Y1424345D01*
G01X-3377Y1424581D02*
X-4258Y1424345D01*
G01X-3377Y1420644D02*
X-4258Y1420408D01*
G01X-3377Y1420644D02*
X-4258Y1420408D01*
G01X-6693Y1424502D02*
X-4725Y1424817D01*
G01X-6693Y1424502D02*
X-4725Y1424817D01*
G01X-6693Y1420565D02*
X-4725Y1420880D01*
G01X-6693Y1420565D02*
X-4725Y1420880D01*
G01X-6693Y1416628D02*
X-4725Y1416943D01*
G01X-6693Y1416628D02*
X-4725Y1416943D01*
G01X-6693Y1412691D02*
X-4725Y1413006D01*
G01X-6693Y1412691D02*
X-4725Y1413006D01*
G01X-6693Y1408754D02*
X-4725Y1409069D01*
G01X-6693Y1408754D02*
X-4725Y1409069D01*
G01X-3377Y1416707D02*
X-4258Y1416471D01*
G01X-3377Y1416707D02*
X-4258Y1416471D01*
G01X-3377Y1412770D02*
X-4258Y1412534D01*
G01X-3377Y1412770D02*
X-4258Y1412534D01*
G01X-3377Y1408833D02*
X-4258Y1408597D01*
G01X-3377Y1408833D02*
X-4258Y1408597D01*
G01X-4725Y1426274D02*
X-6693D01*
G01X-4725D02*
X-6693D01*
G01X-2196Y1425998D02*
X-3150D01*
G01X-2196D02*
X-3150D01*
G01X-4258Y1425841D02*
X-4725D01*
G01X-4258D02*
X-4725D01*
G01X-6693Y1425683D02*
X-9843D01*
G01X-6693D02*
X-9843D01*
G01X-12992Y1425644D02*
X0D01*
G01Y1424541D02*
X-12992D01*
G01X-9843Y1424502D02*
X-6693D01*
G01X-9843D02*
X-6693D01*
G01X-4725Y1424345D02*
X-4258D01*
G01X-4725D02*
X-4258D01*
G01X-3150Y1424187D02*
X-2196D01*
G01X-3150D02*
X-2196D01*
G01X-4725Y1423912D02*
X-6693D01*
G01X-4725D02*
X-6693D01*
G01X-4725Y1422337D02*
X-6693D01*
G01X-4725D02*
X-6693D01*
G01X-2196Y1422061D02*
X-3150D01*
G01X-2196D02*
X-3150D01*
G01X-4258Y1421904D02*
X-4725D01*
G01X-4258D02*
X-4725D01*
G01X-6693Y1421746D02*
X-9843D01*
G01X-6693D02*
X-9843D01*
G01X-12992Y1421707D02*
X0D01*
G01Y1420604D02*
X-12992D01*
G01X-9843Y1420565D02*
X-6693D01*
G01X-9843D02*
X-6693D01*
G01X-4725Y1420408D02*
X-4258D01*
G01X-4725D02*
X-4258D01*
G01X-3150Y1420250D02*
X-2196D01*
G01X-3150D02*
X-2196D01*
G01X-4725Y1419975D02*
X-6693D01*
G01X-4725D02*
X-6693D01*
G01X-4725Y1418400D02*
X-6693D01*
G01X-4725D02*
X-6693D01*
G01X-2196Y1418124D02*
X-3150D01*
G01X-2196D02*
X-3150D01*
G01X-4258Y1417967D02*
X-4725D01*
G01X-4258D02*
X-4725D01*
G01X-6693Y1417809D02*
X-9843D01*
G01X-6693D02*
X-9843D01*
G01X-12992Y1417770D02*
X0D01*
G01Y1416667D02*
X-12992D01*
G01X-9843Y1416628D02*
X-6693D01*
G01X-9843D02*
X-6693D01*
G01X-4725Y1416471D02*
X-4258D01*
G01X-4725D02*
X-4258D01*
G01X-3150Y1416313D02*
X-2196D01*
G01X-3150D02*
X-2196D01*
G01X-4725Y1416038D02*
X-6693D01*
G01X-4725D02*
X-6693D01*
G01X-4725Y1414463D02*
X-6693D01*
G01X-4725D02*
X-6693D01*
G01X-2196Y1414187D02*
X-3150D01*
G01X-2196D02*
X-3150D01*
G01X-4258Y1414030D02*
X-4725D01*
G01X-4258D02*
X-4725D01*
G01X-6693Y1413872D02*
X-9843D01*
G01X-6693D02*
X-9843D01*
G01X-12992Y1413833D02*
X0D01*
G01Y1412730D02*
X-12992D01*
G01X-9843Y1412691D02*
X-6693D01*
G01X-9843D02*
X-6693D01*
G01X-4725Y1412534D02*
X-4258D01*
G01X-4725D02*
X-4258D01*
G01X-3150Y1412376D02*
X-2196D01*
G01X-3150D02*
X-2196D01*
G01X-4725Y1412101D02*
X-6693D01*
G01X-4725D02*
X-6693D01*
G01X-4725Y1410526D02*
X-6693D01*
G01X-4725D02*
X-6693D01*
G01X-2196Y1410250D02*
X-3150D01*
G01X-2196D02*
X-3150D01*
G01X-4258Y1410093D02*
X-4725D01*
G01X-4258D02*
X-4725D01*
G01X-6693Y1409935D02*
X-9843D01*
G01X-6693D02*
X-9843D01*
G01X-12992Y1409896D02*
X0D01*
G01Y1408793D02*
X-12992D01*
G01X-9843Y1408754D02*
X-6693D01*
G01X-9843D02*
X-6693D01*
G01X-4725Y1408597D02*
X-4258D01*
G01X-4725D02*
X-4258D01*
G01X-3150Y1408439D02*
X-2196D01*
G01X-3150D02*
X-2196D01*
G01X-4725Y1408164D02*
X-6693D01*
G01X-4725D02*
X-6693D01*
G01X-4725Y1406589D02*
X-6693D01*
G01X-4725D02*
X-6693D01*
G01X-2196Y1406313D02*
X-3150D01*
G01X-2196D02*
X-3150D01*
G01X-4258Y1406156D02*
X-4725D01*
G01X-4258D02*
X-4725D01*
G01X-6693Y1405998D02*
X-9843D01*
G01X-6693D02*
X-9843D01*
G01X-12992Y1405959D02*
X0D01*
G01X-4725Y1425368D02*
X-6693Y1425683D01*
G01X-4725Y1425368D02*
X-6693Y1425683D01*
G01X-4725Y1421431D02*
X-6693Y1421746D01*
G01X-4725Y1421431D02*
X-6693Y1421746D01*
G01X-4725Y1417494D02*
X-6693Y1417809D01*
G01X-4725Y1417494D02*
X-6693Y1417809D01*
G01X-4725Y1413557D02*
X-6693Y1413872D01*
G01X-4725Y1413557D02*
X-6693Y1413872D01*
G01X-4725Y1409620D02*
X-6693Y1409935D01*
G01X-4725Y1409620D02*
X-6693Y1409935D01*
G01X-4258Y1425841D02*
X-3377Y1425604D01*
G01X-4258Y1425841D02*
X-3377Y1425604D01*
G01X-4258Y1421904D02*
X-3377Y1421667D01*
G01X-4258Y1421904D02*
X-3377Y1421667D01*
G01X-4258Y1417967D02*
X-3377Y1417730D01*
G01X-4258Y1417967D02*
X-3377Y1417730D01*
G01X-4258Y1414030D02*
X-3377Y1413793D01*
G01X-4258Y1414030D02*
X-3377Y1413793D01*
G01X-4258Y1410093D02*
X-3377Y1409856D01*
G01X-4258Y1410093D02*
X-3377Y1409856D01*
G01X-4258Y1406156D02*
X-3377Y1405919D01*
G01X-4258Y1406156D02*
X-3377Y1405919D01*
G01X-9843Y1425683D02*
X-10630Y1426038D01*
G01D02*
X-9843Y1425683D01*
G01Y1421746D02*
X-10630Y1422101D01*
G01D02*
X-9843Y1421746D01*
G01Y1417809D02*
X-10630Y1418164D01*
G01D02*
X-9843Y1417809D01*
G01Y1413872D02*
X-10630Y1414227D01*
G01D02*
X-9843Y1413872D01*
G01Y1409935D02*
X-10630Y1410290D01*
G01D02*
X-9843Y1409935D01*
G01Y1405998D02*
X-10630Y1406353D01*
G01D02*
X-9843Y1405998D01*
G01X-3150Y1424187D02*
X-3377Y1424581D01*
G01X-3150Y1424187D02*
X-3377Y1424581D01*
G01X-3150Y1420250D02*
X-3377Y1420644D01*
G01X-3150Y1420250D02*
X-3377Y1420644D01*
G01X-3150Y1416313D02*
X-3377Y1416707D01*
G01X-3150Y1416313D02*
X-3377Y1416707D01*
G01X-3150Y1412376D02*
X-3377Y1412770D01*
G01X-3150Y1412376D02*
X-3377Y1412770D01*
G01X-3150Y1408439D02*
X-3377Y1408833D01*
G01X-3150Y1408439D02*
X-3377Y1408833D01*
G01X-10630Y1408400D02*
X-9843Y1408754D01*
G01D02*
X-10630Y1408400D01*
G01Y1412337D02*
X-9843Y1412691D01*
G01D02*
X-10630Y1412337D01*
G01X-3756Y1408478D02*
Y1406274D01*
G01Y1412416D02*
Y1410211D01*
G01Y1416353D02*
Y1414148D01*
G01Y1424227D02*
Y1422022D01*
G01Y1420290D02*
Y1418085D01*
G01Y1428164D02*
Y1425959D01*
G01X-4725Y1423912D02*
Y1424817D01*
G01Y1425368D02*
Y1426274D01*
G01Y1419975D02*
Y1420880D01*
G01Y1421431D02*
Y1422337D01*
G01Y1416038D02*
Y1416943D01*
G01Y1417494D02*
Y1418400D01*
G01Y1409620D02*
Y1410526D01*
G01Y1412101D02*
Y1413006D01*
G01Y1413557D02*
Y1414463D01*
G01Y1408164D02*
Y1409069D01*
G01D02*
Y1408164D01*
G01Y1410526D02*
Y1409620D01*
G01Y1413006D02*
Y1412101D01*
G01Y1414463D02*
Y1413557D01*
G01Y1416943D02*
Y1416038D01*
G01Y1418400D02*
Y1417494D01*
G01Y1420880D02*
Y1419975D01*
G01Y1422337D02*
Y1421431D01*
G01Y1424817D02*
Y1423912D01*
G01Y1426274D02*
Y1425368D01*
G01X-6693Y1406589D02*
Y1405998D01*
G01Y1408754D02*
Y1408164D01*
G01Y1406589D02*
Y1405998D01*
G01Y1408754D02*
Y1408164D01*
G01Y1410526D02*
Y1409935D01*
G01Y1412691D02*
Y1412101D01*
G01Y1414463D02*
Y1413872D01*
G01Y1410526D02*
Y1409935D01*
G01Y1412691D02*
Y1412101D01*
G01Y1414463D02*
Y1413872D01*
G01Y1416628D02*
Y1416038D01*
G01Y1418400D02*
Y1417809D01*
G01Y1416628D02*
Y1416038D01*
G01Y1418400D02*
Y1417809D01*
G01Y1420565D02*
Y1419975D01*
G01Y1422337D02*
Y1421746D01*
G01Y1420565D02*
Y1419975D01*
G01Y1422337D02*
Y1421746D01*
G01Y1424502D02*
Y1423912D01*
G01Y1426274D02*
Y1425683D01*
G01Y1424502D02*
Y1423912D01*
G01Y1426274D02*
Y1425683D01*
G01X-10530Y1408445D02*
Y1406308D01*
G01Y1408445D02*
Y1406308D01*
G01Y1412382D02*
Y1410245D01*
G01Y1412382D02*
Y1410245D01*
G01Y1416319D02*
Y1414182D01*
G01Y1416319D02*
Y1414182D01*
G01Y1424193D02*
Y1422056D01*
G01Y1420256D02*
Y1418119D01*
G01Y1424193D02*
Y1422056D01*
G01Y1420256D02*
Y1418119D01*
G01Y1428130D02*
Y1425993D01*
G01Y1428130D02*
Y1425993D01*
G01X-11842Y1426051D02*
Y1428071D01*
G01Y1422114D02*
Y1424134D01*
G01Y1418177D02*
Y1420197D01*
G01Y1414240D02*
Y1416260D01*
G01Y1410303D02*
Y1412323D01*
G01Y1406366D02*
Y1408386D01*
G01D02*
Y1406366D01*
G01Y1412323D02*
Y1410303D01*
G01Y1416260D02*
Y1414240D01*
G01Y1420197D02*
Y1418177D01*
G01Y1424134D02*
Y1422114D01*
G01Y1428071D02*
Y1426051D01*
G01X-12280Y1426056D02*
Y1428066D01*
G01Y1422119D02*
Y1424129D01*
G01Y1418182D02*
Y1420192D01*
G01Y1414245D02*
Y1416255D01*
G01Y1410308D02*
Y1412318D01*
G01Y1406371D02*
Y1408381D01*
G01D02*
Y1406371D01*
G01Y1412318D02*
Y1410308D01*
G01Y1416255D02*
Y1414245D01*
G01Y1420192D02*
Y1418182D01*
G01Y1424129D02*
Y1422119D01*
G01Y1428066D02*
Y1426056D01*
G01X-12992Y1410211D02*
Y1409896D01*
G01Y1406274D02*
Y1405959D01*
G01Y1408793D02*
Y1408478D01*
G01Y1412730D02*
Y1412416D01*
G01Y1414148D02*
Y1413833D01*
G01Y1416667D02*
Y1416353D01*
G01Y1418085D02*
Y1417770D01*
G01Y1420604D02*
Y1420290D01*
G01Y1422022D02*
Y1421707D01*
G01Y1424541D02*
Y1424227D01*
G01Y1425959D02*
Y1425644D01*
G01X-23684Y1426183D02*
Y1427940D01*
G01Y1418309D02*
Y1420066D01*
G01Y1422246D02*
Y1424003D01*
G01Y1414372D02*
Y1416128D01*
G01Y1410435D02*
Y1412191D01*
G01Y1406498D02*
Y1408254D01*
G01D02*
Y1406498D01*
G01Y1412191D02*
Y1410435D01*
G01Y1416128D02*
Y1414372D01*
G01Y1424003D02*
Y1422246D01*
G01Y1420066D02*
Y1418309D01*
G01Y1427940D02*
Y1426183D01*
G01X-10630Y1416274D02*
X-9843Y1416628D01*
G01D02*
X-10630Y1416274D01*
G01Y1420211D02*
X-9843Y1420565D01*
G01D02*
X-10630Y1420211D01*
G01Y1424148D02*
X-9843Y1424502D01*
G01D02*
X-10630Y1424148D01*
G01X-3377Y1405919D02*
X-3150Y1406313D01*
G01X-3377Y1405919D02*
X-3150Y1406313D01*
G01X-3377Y1409856D02*
X-3150Y1410250D01*
G01X-3377Y1409856D02*
X-3150Y1410250D01*
G01X-3377Y1413793D02*
X-3150Y1414187D01*
G01X-3377Y1413793D02*
X-3150Y1414187D01*
G01X-3377Y1417730D02*
X-3150Y1418124D01*
G01X-3377Y1417730D02*
X-3150Y1418124D01*
G01X-3377Y1421667D02*
X-3150Y1422061D01*
G01X-3377Y1421667D02*
X-3150Y1422061D01*
G01X-3377Y1425604D02*
X-3150Y1425998D01*
G01X-3377Y1425604D02*
X-3150Y1425998D01*
G01X-3377Y1448203D02*
X-4258Y1447967D01*
G01X-3377Y1448203D02*
X-4258Y1447967D01*
G01X-3377Y1444266D02*
X-4258Y1444030D01*
G01X-3377Y1444266D02*
X-4258Y1444030D01*
G01X-3377Y1440329D02*
X-4258Y1440093D01*
G01X-3377Y1440329D02*
X-4258Y1440093D01*
G01X-3377Y1436392D02*
X-4258Y1436156D01*
G01X-3377Y1436392D02*
X-4258Y1436156D01*
G01X-3377Y1432455D02*
X-4258Y1432219D01*
G01X-3377Y1432455D02*
X-4258Y1432219D01*
G01X-3377Y1428518D02*
X-4258Y1428282D01*
G01X-3377Y1428518D02*
X-4258Y1428282D01*
G01X-6693Y1444187D02*
X-4725Y1444502D01*
G01X-6693Y1444187D02*
X-4725Y1444502D01*
G01X-6693Y1440250D02*
X-4725Y1440565D01*
G01X-6693Y1440250D02*
X-4725Y1440565D01*
G01X-6693Y1436313D02*
X-4725Y1436628D01*
G01X-6693Y1436313D02*
X-4725Y1436628D01*
G01X-6693Y1432376D02*
X-4725Y1432691D01*
G01X-6693Y1432376D02*
X-4725Y1432691D01*
G01X-6693Y1428439D02*
X-4725Y1428754D01*
G01X-6693Y1428439D02*
X-4725Y1428754D01*
G01Y1447967D02*
X-4258D01*
G01X-4725D02*
X-4258D01*
G01X-3150Y1447809D02*
X-2196D01*
G01X-3150D02*
X-2196D01*
G01X-4725Y1447534D02*
X-6693D01*
G01X-4725D02*
X-6693D01*
G01X-4725Y1445959D02*
X-6693D01*
G01X-4725D02*
X-6693D01*
G01X-2196Y1445683D02*
X-3150D01*
G01X-2196D02*
X-3150D01*
G01X-4258Y1445526D02*
X-4725D01*
G01X-4258D02*
X-4725D01*
G01X-6693Y1445368D02*
X-9843D01*
G01X-6693D02*
X-9843D01*
G01X-12992Y1445329D02*
X0D01*
G01Y1444227D02*
X-12992D01*
G01X-9843Y1444187D02*
X-6693D01*
G01X-9843D02*
X-6693D01*
G01X-4725Y1444030D02*
X-4258D01*
G01X-4725D02*
X-4258D01*
G01X-3150Y1443872D02*
X-2196D01*
G01X-3150D02*
X-2196D01*
G01X-4725Y1443597D02*
X-6693D01*
G01X-4725D02*
X-6693D01*
G01X-4725Y1442022D02*
X-6693D01*
G01X-4725D02*
X-6693D01*
G01X-2196Y1441746D02*
X-3150D01*
G01X-2196D02*
X-3150D01*
G01X-4258Y1441589D02*
X-4725D01*
G01X-4258D02*
X-4725D01*
G01X-6693Y1441431D02*
X-9843D01*
G01X-6693D02*
X-9843D01*
G01X-12992Y1441392D02*
X0D01*
G01Y1440290D02*
X-12992D01*
G01X-9843Y1440250D02*
X-6693D01*
G01X-9843D02*
X-6693D01*
G01X-4725Y1440093D02*
X-4258D01*
G01X-4725D02*
X-4258D01*
G01X-3150Y1439935D02*
X-2196D01*
G01X-3150D02*
X-2196D01*
G01X-4725Y1439660D02*
X-6693D01*
G01X-4725D02*
X-6693D01*
G01X-4725Y1438085D02*
X-6693D01*
G01X-4725D02*
X-6693D01*
G01X-2196Y1437809D02*
X-3150D01*
G01X-2196D02*
X-3150D01*
G01X-4258Y1437652D02*
X-4725D01*
G01X-4258D02*
X-4725D01*
G01X-6693Y1437494D02*
X-9843D01*
G01X-6693D02*
X-9843D01*
G01X-12992Y1437455D02*
X0D01*
G01Y1436353D02*
X-12992D01*
G01X-9843Y1436313D02*
X-6693D01*
G01X-9843D02*
X-6693D01*
G01X-4725Y1436156D02*
X-4258D01*
G01X-4725D02*
X-4258D01*
G01X-3150Y1435998D02*
X-2196D01*
G01X-3150D02*
X-2196D01*
G01X-4725Y1435723D02*
X-6693D01*
G01X-4725D02*
X-6693D01*
G01X-4725Y1434148D02*
X-6693D01*
G01X-4725D02*
X-6693D01*
G01X-2196Y1433872D02*
X-3150D01*
G01X-2196D02*
X-3150D01*
G01X-4258Y1433715D02*
X-4725D01*
G01X-4258D02*
X-4725D01*
G01X-6693Y1433557D02*
X-9843D01*
G01X-6693D02*
X-9843D01*
G01X-12992Y1433518D02*
X0D01*
G01Y1432416D02*
X-12992D01*
G01X-9843Y1432376D02*
X-6693D01*
G01X-9843D02*
X-6693D01*
G01X-4725Y1432219D02*
X-4258D01*
G01X-4725D02*
X-4258D01*
G01X-3150Y1432061D02*
X-2196D01*
G01X-3150D02*
X-2196D01*
G01X-4725Y1431786D02*
X-6693D01*
G01X-4725D02*
X-6693D01*
G01X-4725Y1430211D02*
X-6693D01*
G01X-4725D02*
X-6693D01*
G01X-2196Y1429935D02*
X-3150D01*
G01X-2196D02*
X-3150D01*
G01X-4258Y1429778D02*
X-4725D01*
G01X-4258D02*
X-4725D01*
G01X-6693Y1429620D02*
X-9843D01*
G01X-6693D02*
X-9843D01*
G01X-12992Y1429581D02*
X0D01*
G01Y1428478D02*
X-12992D01*
G01X-9843Y1428439D02*
X-6693D01*
G01X-9843D02*
X-6693D01*
G01X-4725Y1428282D02*
X-4258D01*
G01X-4725D02*
X-4258D01*
G01X-3150Y1428124D02*
X-2196D01*
G01X-3150D02*
X-2196D01*
G01X-4725Y1427849D02*
X-6693D01*
G01X-4725D02*
X-6693D01*
G01X-4725Y1445053D02*
X-6693Y1445368D01*
G01X-4725Y1445053D02*
X-6693Y1445368D01*
G01X-4725Y1441116D02*
X-6693Y1441431D01*
G01X-4725Y1441116D02*
X-6693Y1441431D01*
G01X-4725Y1437179D02*
X-6693Y1437494D01*
G01X-4725Y1437179D02*
X-6693Y1437494D01*
G01X-4725Y1433242D02*
X-6693Y1433557D01*
G01X-4725Y1433242D02*
X-6693Y1433557D01*
G01X-4725Y1429305D02*
X-6693Y1429620D01*
G01X-4725Y1429305D02*
X-6693Y1429620D01*
G01X-4258Y1445526D02*
X-3377Y1445290D01*
G01X-4258Y1445526D02*
X-3377Y1445290D01*
G01X-4258Y1441589D02*
X-3377Y1441353D01*
G01X-4258Y1441589D02*
X-3377Y1441353D01*
G01X-4258Y1437652D02*
X-3377Y1437416D01*
G01X-4258Y1437652D02*
X-3377Y1437416D01*
G01X-4258Y1433715D02*
X-3377Y1433478D01*
G01X-4258Y1433715D02*
X-3377Y1433478D01*
G01X-4258Y1429778D02*
X-3377Y1429541D01*
G01X-4258Y1429778D02*
X-3377Y1429541D01*
G01X-9843Y1445368D02*
X-10630Y1445723D01*
G01D02*
X-9843Y1445368D01*
G01Y1441431D02*
X-10630Y1441786D01*
G01D02*
X-9843Y1441431D01*
G01Y1437494D02*
X-10630Y1437849D01*
G01D02*
X-9843Y1437494D01*
G01Y1433557D02*
X-10630Y1433912D01*
G01D02*
X-9843Y1433557D01*
G01Y1429620D02*
X-10630Y1429975D01*
G01D02*
X-9843Y1429620D01*
G01X-3150Y1447809D02*
X-3377Y1448203D01*
G01X-3150Y1447809D02*
X-3377Y1448203D01*
G01X-3150Y1443872D02*
X-3377Y1444266D01*
G01X-3150Y1443872D02*
X-3377Y1444266D01*
G01X-3150Y1439935D02*
X-3377Y1440329D01*
G01X-3150Y1439935D02*
X-3377Y1440329D01*
G01X-3150Y1435998D02*
X-3377Y1436392D01*
G01X-3150Y1435998D02*
X-3377Y1436392D01*
G01X-3150Y1432061D02*
X-3377Y1432455D01*
G01X-3150Y1432061D02*
X-3377Y1432455D01*
G01X-3150Y1428124D02*
X-3377Y1428518D01*
G01X-3150Y1428124D02*
X-3377Y1428518D01*
G01X-3756Y1432101D02*
Y1429896D01*
G01Y1436038D02*
Y1433833D01*
G01Y1439975D02*
Y1437770D01*
G01Y1443912D02*
Y1441707D01*
G01Y1447849D02*
Y1445644D01*
G01X-4725Y1447534D02*
Y1448439D01*
G01Y1443597D02*
Y1444502D01*
G01Y1445053D02*
Y1445959D01*
G01Y1441116D02*
Y1442022D01*
G01Y1439660D02*
Y1440565D01*
G01Y1433242D02*
Y1434148D01*
G01Y1435723D02*
Y1436628D01*
G01Y1437179D02*
Y1438085D01*
G01Y1429305D02*
Y1430211D01*
G01Y1431786D02*
Y1432691D01*
G01Y1427849D02*
Y1428754D01*
G01D02*
Y1427849D01*
G01Y1430211D02*
Y1429305D01*
G01Y1432691D02*
Y1431786D01*
G01Y1434148D02*
Y1433242D01*
G01Y1436628D02*
Y1435723D01*
G01Y1438085D02*
Y1437179D01*
G01Y1442022D02*
Y1441116D01*
G01Y1440565D02*
Y1439660D01*
G01Y1445959D02*
Y1445053D01*
G01Y1444502D02*
Y1443597D01*
G01Y1448439D02*
Y1447534D01*
G01X-6693Y1428439D02*
Y1427849D01*
G01Y1428439D02*
Y1427849D01*
G01Y1430211D02*
Y1429620D01*
G01Y1432376D02*
Y1431786D01*
G01Y1430211D02*
Y1429620D01*
G01Y1432376D02*
Y1431786D01*
G01Y1434148D02*
Y1433557D01*
G01Y1436313D02*
Y1435723D01*
G01Y1438085D02*
Y1437494D01*
G01Y1434148D02*
Y1433557D01*
G01Y1436313D02*
Y1435723D01*
G01Y1438085D02*
Y1437494D01*
G01Y1442022D02*
Y1441431D01*
G01Y1440250D02*
Y1439660D01*
G01Y1442022D02*
Y1441431D01*
G01Y1440250D02*
Y1439660D01*
G01Y1445959D02*
Y1445368D01*
G01Y1444187D02*
Y1443597D01*
G01Y1444187D02*
Y1443597D01*
G01Y1445959D02*
Y1445368D01*
G01Y1448124D02*
Y1447534D01*
G01Y1448124D02*
Y1447534D01*
G01X-10530Y1432067D02*
Y1429930D01*
G01Y1432067D02*
Y1429930D01*
G01Y1436004D02*
Y1433867D01*
G01Y1436004D02*
Y1433867D01*
G01Y1439941D02*
Y1437804D01*
G01Y1439941D02*
Y1437804D01*
G01Y1447815D02*
Y1445678D01*
G01Y1443878D02*
Y1441741D01*
G01Y1447815D02*
Y1445678D01*
G01Y1443878D02*
Y1441741D01*
G01X-11842Y1445736D02*
Y1447756D01*
G01Y1441799D02*
Y1443819D01*
G01Y1437862D02*
Y1439882D01*
G01Y1433925D02*
Y1435945D01*
G01Y1429988D02*
Y1432008D01*
G01D02*
Y1429988D01*
G01Y1435945D02*
Y1433925D01*
G01Y1439882D02*
Y1437862D01*
G01Y1443819D02*
Y1441799D01*
G01Y1447756D02*
Y1445736D01*
G01X-12280Y1445741D02*
Y1447751D01*
G01Y1441804D02*
Y1443814D01*
G01Y1437867D02*
Y1439877D01*
G01Y1433930D02*
Y1435940D01*
G01Y1429993D02*
Y1432003D01*
G01D02*
Y1429993D01*
G01Y1435940D02*
Y1433930D01*
G01Y1439877D02*
Y1437867D01*
G01Y1447751D02*
Y1445741D01*
G01Y1443814D02*
Y1441804D01*
G01X-12992Y1428478D02*
Y1428164D01*
G01Y1432416D02*
Y1432101D01*
G01Y1429896D02*
Y1429581D01*
G01Y1436353D02*
Y1436038D01*
G01Y1433833D02*
Y1433518D01*
G01Y1437770D02*
Y1437455D01*
G01Y1440290D02*
Y1439975D01*
G01Y1441707D02*
Y1441392D01*
G01Y1444227D02*
Y1443912D01*
G01Y1445644D02*
Y1445329D01*
G01Y1448164D02*
Y1447849D01*
G01X-23684Y1441931D02*
Y1443688D01*
G01Y1445868D02*
Y1447625D01*
G01Y1437994D02*
Y1439751D01*
G01Y1434057D02*
Y1435814D01*
G01Y1430120D02*
Y1431877D01*
G01D02*
Y1430120D01*
G01Y1435814D02*
Y1434057D01*
G01Y1439751D02*
Y1437994D01*
G01Y1447625D02*
Y1445868D01*
G01Y1443688D02*
Y1441931D01*
G01X-10630Y1428085D02*
X-9843Y1428439D01*
G01D02*
X-10630Y1428085D01*
G01Y1432022D02*
X-9843Y1432376D01*
G01D02*
X-10630Y1432022D01*
G01Y1435959D02*
X-9843Y1436313D01*
G01D02*
X-10630Y1435959D01*
G01Y1439896D02*
X-9843Y1440250D01*
G01D02*
X-10630Y1439896D01*
G01Y1443833D02*
X-9843Y1444187D01*
G01D02*
X-10630Y1443833D01*
G01Y1447770D02*
X-9843Y1448124D01*
G01D02*
X-10630Y1447770D01*
G01X-3377Y1429541D02*
X-3150Y1429935D01*
G01X-3377Y1429541D02*
X-3150Y1429935D01*
G01X-3377Y1433478D02*
X-3150Y1433872D01*
G01X-3377Y1433478D02*
X-3150Y1433872D01*
G01X-3377Y1437416D02*
X-3150Y1437809D01*
G01X-3377Y1437416D02*
X-3150Y1437809D01*
G01X-3377Y1441353D02*
X-3150Y1441746D01*
G01X-3377Y1441353D02*
X-3150Y1441746D01*
G01X-3377Y1445290D02*
X-3150Y1445683D01*
G01X-3377Y1445290D02*
X-3150Y1445683D01*
G01X-6693Y1467809D02*
X-4725Y1468124D01*
G01X-6693Y1467809D02*
X-4725Y1468124D01*
G01X-6693Y1463872D02*
X-4725Y1464187D01*
G01X-6693Y1463872D02*
X-4725Y1464187D01*
G01X-3377Y1467888D02*
X-4258Y1467652D01*
G01X-3377Y1467888D02*
X-4258Y1467652D01*
G01X-3377Y1463951D02*
X-4258Y1463715D01*
G01X-3377Y1463951D02*
X-4258Y1463715D01*
G01X-3377Y1460014D02*
X-4258Y1459778D01*
G01X-3377Y1460014D02*
X-4258Y1459778D01*
G01X-3377Y1456077D02*
X-4258Y1455841D01*
G01X-3377Y1456077D02*
X-4258Y1455841D01*
G01X-3377Y1452140D02*
X-4258Y1451904D01*
G01X-3377Y1452140D02*
X-4258Y1451904D01*
G01Y1469148D02*
X-4725D01*
G01X-4258D02*
X-4725D01*
G01X-6693Y1468990D02*
X-9843D01*
G01X-6693D02*
X-9843D01*
G01X-12992Y1468951D02*
X0D01*
G01Y1467849D02*
X-12992D01*
G01X-9843Y1467809D02*
X-6693D01*
G01X-9843D02*
X-6693D01*
G01X-4725Y1467652D02*
X-4258D01*
G01X-4725D02*
X-4258D01*
G01X-3150Y1467494D02*
X-2196D01*
G01X-3150D02*
X-2196D01*
G01X-4725Y1467219D02*
X-6693D01*
G01X-4725D02*
X-6693D01*
G01X-4725Y1465644D02*
X-6693D01*
G01X-4725D02*
X-6693D01*
G01X-2196Y1465368D02*
X-3150D01*
G01X-2196D02*
X-3150D01*
G01X-4258Y1465211D02*
X-4725D01*
G01X-4258D02*
X-4725D01*
G01X-6693Y1465053D02*
X-9843D01*
G01X-6693D02*
X-9843D01*
G01X-12992Y1465014D02*
X0D01*
G01Y1463912D02*
X-12992D01*
G01X-9843Y1463872D02*
X-6693D01*
G01X-9843D02*
X-6693D01*
G01X-4725Y1463715D02*
X-4258D01*
G01X-4725D02*
X-4258D01*
G01X-3150Y1463557D02*
X-2196D01*
G01X-3150D02*
X-2196D01*
G01X-4725Y1463282D02*
X-6693D01*
G01X-4725D02*
X-6693D01*
G01Y1459935D02*
X-4725Y1460250D01*
G01X-6693Y1459935D02*
X-4725Y1460250D01*
G01X-6693Y1455998D02*
X-4725Y1456313D01*
G01X-6693Y1455998D02*
X-4725Y1456313D01*
G01X-6693Y1452061D02*
X-4725Y1452376D01*
G01X-6693Y1452061D02*
X-4725Y1452376D01*
G01X-6693Y1448124D02*
X-4725Y1448439D01*
G01X-6693Y1448124D02*
X-4725Y1448439D01*
G01Y1461707D02*
X-6693D01*
G01X-4725D02*
X-6693D01*
G01X-2196Y1461431D02*
X-3150D01*
G01X-2196D02*
X-3150D01*
G01X-4258Y1461274D02*
X-4725D01*
G01X-4258D02*
X-4725D01*
G01X-6693Y1461116D02*
X-9843D01*
G01X-6693D02*
X-9843D01*
G01X-12992Y1461077D02*
X0D01*
G01Y1459975D02*
X-12992D01*
G01X-9843Y1459935D02*
X-6693D01*
G01X-9843D02*
X-6693D01*
G01X-4725Y1459778D02*
X-4258D01*
G01X-4725D02*
X-4258D01*
G01X-3150Y1459620D02*
X-2196D01*
G01X-3150D02*
X-2196D01*
G01X-4725Y1459345D02*
X-6693D01*
G01X-4725D02*
X-6693D01*
G01X-4725Y1457770D02*
X-6693D01*
G01X-4725D02*
X-6693D01*
G01X-2196Y1457494D02*
X-3150D01*
G01X-2196D02*
X-3150D01*
G01X-4258Y1457337D02*
X-4725D01*
G01X-4258D02*
X-4725D01*
G01X-6693Y1457179D02*
X-9843D01*
G01X-6693D02*
X-9843D01*
G01X-12992Y1457140D02*
X0D01*
G01Y1456038D02*
X-12992D01*
G01X-9843Y1455998D02*
X-6693D01*
G01X-9843D02*
X-6693D01*
G01X-4725Y1455841D02*
X-4258D01*
G01X-4725D02*
X-4258D01*
G01X-3150Y1455683D02*
X-2196D01*
G01X-3150D02*
X-2196D01*
G01X-4725Y1455408D02*
X-6693D01*
G01X-4725D02*
X-6693D01*
G01X-4725Y1453833D02*
X-6693D01*
G01X-4725D02*
X-6693D01*
G01X-2196Y1453557D02*
X-3150D01*
G01X-2196D02*
X-3150D01*
G01X-4258Y1453400D02*
X-4725D01*
G01X-4258D02*
X-4725D01*
G01X-6693Y1453242D02*
X-9843D01*
G01X-6693D02*
X-9843D01*
G01X-12992Y1453203D02*
X0D01*
G01Y1452101D02*
X-12992D01*
G01X-9843Y1452061D02*
X-6693D01*
G01X-9843D02*
X-6693D01*
G01X-4725Y1451904D02*
X-4258D01*
G01X-4725D02*
X-4258D01*
G01X-3150Y1451746D02*
X-2196D01*
G01X-3150D02*
X-2196D01*
G01X-4725Y1451471D02*
X-6693D01*
G01X-4725D02*
X-6693D01*
G01X-4725Y1449896D02*
X-6693D01*
G01X-4725D02*
X-6693D01*
G01X-2196Y1449620D02*
X-3150D01*
G01X-2196D02*
X-3150D01*
G01X-4258Y1449463D02*
X-4725D01*
G01X-4258D02*
X-4725D01*
G01X-6693Y1449305D02*
X-9843D01*
G01X-6693D02*
X-9843D01*
G01X-12992Y1449266D02*
X0D01*
G01Y1448164D02*
X-12992D01*
G01X-9843Y1448124D02*
X-6693D01*
G01X-9843D02*
X-6693D01*
G01X-4258Y1469148D02*
X-3377Y1468912D01*
G01X-4258Y1469148D02*
X-3377Y1468912D01*
G01X-4258Y1465211D02*
X-3377Y1464975D01*
G01X-4258Y1465211D02*
X-3377Y1464975D01*
G01X-4725Y1468675D02*
X-6693Y1468990D01*
G01X-4725Y1468675D02*
X-6693Y1468990D01*
G01X-4725Y1464738D02*
X-6693Y1465053D01*
G01X-4725Y1464738D02*
X-6693Y1465053D01*
G01X-4725Y1460801D02*
X-6693Y1461116D01*
G01X-4725Y1460801D02*
X-6693Y1461116D01*
G01X-4725Y1456864D02*
X-6693Y1457179D01*
G01X-4725Y1456864D02*
X-6693Y1457179D01*
G01X-4725Y1452927D02*
X-6693Y1453242D01*
G01X-4725Y1452927D02*
X-6693Y1453242D01*
G01X-4725Y1448990D02*
X-6693Y1449305D01*
G01X-4725Y1448990D02*
X-6693Y1449305D01*
G01X-4258Y1461274D02*
X-3377Y1461038D01*
G01X-4258Y1461274D02*
X-3377Y1461038D01*
G01X-4258Y1457337D02*
X-3377Y1457101D01*
G01X-4258Y1457337D02*
X-3377Y1457101D01*
G01X-4258Y1453400D02*
X-3377Y1453164D01*
G01X-4258Y1453400D02*
X-3377Y1453164D01*
G01X-4258Y1449463D02*
X-3377Y1449227D01*
G01X-4258Y1449463D02*
X-3377Y1449227D01*
G01X-9843Y1468990D02*
X-10630Y1469345D01*
G01D02*
X-9843Y1468990D01*
G01Y1465053D02*
X-10630Y1465408D01*
G01D02*
X-9843Y1465053D01*
G01Y1461116D02*
X-10630Y1461471D01*
G01D02*
X-9843Y1461116D01*
G01Y1457179D02*
X-10630Y1457534D01*
G01D02*
X-9843Y1457179D01*
G01Y1453242D02*
X-10630Y1453597D01*
G01D02*
X-9843Y1453242D01*
G01Y1449305D02*
X-10630Y1449660D01*
G01D02*
X-9843Y1449305D01*
G01X-3150Y1467494D02*
X-3377Y1467888D01*
G01X-3150Y1467494D02*
X-3377Y1467888D01*
G01X-3150Y1463557D02*
X-3377Y1463951D01*
G01X-3150Y1463557D02*
X-3377Y1463951D01*
G01X-3150Y1459620D02*
X-3377Y1460014D01*
G01X-3150Y1459620D02*
X-3377Y1460014D01*
G01X-3150Y1455683D02*
X-3377Y1456077D01*
G01X-3150Y1455683D02*
X-3377Y1456077D01*
G01X-3150Y1451746D02*
X-3377Y1452140D01*
G01X-3150Y1451746D02*
X-3377Y1452140D01*
G01X-3756Y1451786D02*
Y1449581D01*
G01Y1455723D02*
Y1453518D01*
G01Y1459660D02*
Y1457455D01*
G01Y1463597D02*
Y1461392D01*
G01Y1467534D02*
Y1465329D01*
G01X-4725Y1467219D02*
Y1468124D01*
G01Y1468675D02*
Y1469581D01*
G01Y1463282D02*
Y1464187D01*
G01Y1464738D02*
Y1465644D01*
G01Y1456864D02*
Y1457770D01*
G01Y1459345D02*
Y1460250D01*
G01Y1460801D02*
Y1461707D01*
G01Y1452927D02*
Y1453833D01*
G01Y1455408D02*
Y1456313D01*
G01Y1448990D02*
Y1449896D01*
G01Y1451471D02*
Y1452376D01*
G01Y1449896D02*
Y1448990D01*
G01Y1452376D02*
Y1451471D01*
G01Y1453833D02*
Y1452927D01*
G01Y1456313D02*
Y1455408D01*
G01Y1457770D02*
Y1456864D01*
G01Y1460250D02*
Y1459345D01*
G01Y1461707D02*
Y1460801D01*
G01Y1464187D02*
Y1463282D01*
G01Y1465644D02*
Y1464738D01*
G01Y1468124D02*
Y1467219D01*
G01Y1469581D02*
Y1468675D01*
G01X-6693Y1449896D02*
Y1449305D01*
G01Y1452061D02*
Y1451471D01*
G01Y1449896D02*
Y1449305D01*
G01Y1452061D02*
Y1451471D01*
G01Y1453833D02*
Y1453242D01*
G01Y1455998D02*
Y1455408D01*
G01Y1453833D02*
Y1453242D01*
G01Y1455998D02*
Y1455408D01*
G01Y1457770D02*
Y1457179D01*
G01Y1459935D02*
Y1459345D01*
G01Y1461707D02*
Y1461116D01*
G01Y1457770D02*
Y1457179D01*
G01Y1459935D02*
Y1459345D01*
G01Y1461707D02*
Y1461116D01*
G01Y1463872D02*
Y1463282D01*
G01Y1465644D02*
Y1465053D01*
G01Y1463872D02*
Y1463282D01*
G01Y1465644D02*
Y1465053D01*
G01Y1467809D02*
Y1467219D01*
G01Y1469581D02*
Y1468990D01*
G01Y1467809D02*
Y1467219D01*
G01Y1469581D02*
Y1468990D01*
G01X-10530Y1451752D02*
Y1449615D01*
G01Y1451752D02*
Y1449615D01*
G01Y1455689D02*
Y1453552D01*
G01Y1455689D02*
Y1453552D01*
G01Y1459626D02*
Y1457489D01*
G01Y1459626D02*
Y1457489D01*
G01Y1463563D02*
Y1461426D01*
G01Y1463563D02*
Y1461426D01*
G01Y1467500D02*
Y1465363D01*
G01Y1467500D02*
Y1465363D01*
G01X-11842Y1465421D02*
Y1467441D01*
G01Y1461484D02*
Y1463504D01*
G01Y1457547D02*
Y1459567D01*
G01Y1453610D02*
Y1455630D01*
G01Y1449673D02*
Y1451693D01*
G01D02*
Y1449673D01*
G01Y1455630D02*
Y1453610D01*
G01Y1459567D02*
Y1457547D01*
G01Y1463504D02*
Y1461484D01*
G01Y1467441D02*
Y1465421D01*
G01X-12280Y1465426D02*
Y1467436D01*
G01Y1461489D02*
Y1463499D01*
G01Y1457552D02*
Y1459562D01*
G01Y1453615D02*
Y1455625D01*
G01Y1449678D02*
Y1451688D01*
G01D02*
Y1449678D01*
G01Y1455625D02*
Y1453615D01*
G01Y1459562D02*
Y1457552D01*
G01Y1463499D02*
Y1461489D01*
G01Y1467436D02*
Y1465426D01*
G01X-12992Y1452101D02*
Y1451786D01*
G01Y1449581D02*
Y1449266D01*
G01Y1456038D02*
Y1455723D01*
G01Y1453518D02*
Y1453203D01*
G01Y1459975D02*
Y1459660D01*
G01Y1457455D02*
Y1457140D01*
G01Y1461392D02*
Y1461077D01*
G01Y1463912D02*
Y1463597D01*
G01Y1465329D02*
Y1465014D01*
G01Y1467849D02*
Y1467534D01*
G01Y1469266D02*
Y1468951D01*
G01X-23684Y1465553D02*
Y1467310D01*
G01Y1461616D02*
Y1463373D01*
G01Y1457679D02*
Y1459436D01*
G01Y1453742D02*
Y1455499D01*
G01Y1449805D02*
Y1451562D01*
G01D02*
Y1449805D01*
G01Y1455499D02*
Y1453742D01*
G01Y1459436D02*
Y1457679D01*
G01Y1463373D02*
Y1461616D01*
G01Y1467310D02*
Y1465553D01*
G01X-10630Y1451707D02*
X-9843Y1452061D01*
G01D02*
X-10630Y1451707D01*
G01Y1455644D02*
X-9843Y1455998D01*
G01D02*
X-10630Y1455644D01*
G01Y1459581D02*
X-9843Y1459935D01*
G01D02*
X-10630Y1459581D01*
G01Y1463518D02*
X-9843Y1463872D01*
G01D02*
X-10630Y1463518D01*
G01Y1467455D02*
X-9843Y1467809D01*
G01D02*
X-10630Y1467455D01*
G01X-3377Y1449227D02*
X-3150Y1449620D01*
G01X-3377Y1449227D02*
X-3150Y1449620D01*
G01X-3377Y1453164D02*
X-3150Y1453557D01*
G01X-3377Y1453164D02*
X-3150Y1453557D01*
G01X-3377Y1457101D02*
X-3150Y1457494D01*
G01X-3377Y1457101D02*
X-3150Y1457494D01*
G01X-3377Y1461038D02*
X-3150Y1461431D01*
G01X-3377Y1461038D02*
X-3150Y1461431D01*
G01X-3377Y1464975D02*
X-3150Y1465368D01*
G01X-3377Y1464975D02*
X-3150Y1465368D01*
G01X-3377Y1468912D02*
X-3150Y1469305D01*
G01X-3377Y1468912D02*
X-3150Y1469305D01*
G01X-6693Y1487494D02*
X-4725Y1487809D01*
G01X-6693Y1487494D02*
X-4725Y1487809D01*
G01X-6693Y1483557D02*
X-4725Y1483872D01*
G01X-6693Y1483557D02*
X-4725Y1483872D01*
G01X-6693Y1479620D02*
X-4725Y1479935D01*
G01X-6693Y1479620D02*
X-4725Y1479935D01*
G01X-6693Y1475683D02*
X-4725Y1475998D01*
G01X-6693Y1475683D02*
X-4725Y1475998D01*
G01X-6693Y1471746D02*
X-4725Y1472061D01*
G01X-6693Y1471746D02*
X-4725Y1472061D01*
G01X-3377Y1487573D02*
X-4258Y1487337D01*
G01X-3377Y1487573D02*
X-4258Y1487337D01*
G01X-3377Y1483636D02*
X-4258Y1483400D01*
G01X-3377Y1483636D02*
X-4258Y1483400D01*
G01X-3377Y1479699D02*
X-4258Y1479463D01*
G01X-3377Y1479699D02*
X-4258Y1479463D01*
G01X-3377Y1475762D02*
X-4258Y1475526D01*
G01X-3377Y1475762D02*
X-4258Y1475526D01*
G01X-3377Y1471825D02*
X-4258Y1471589D01*
G01X-3377Y1471825D02*
X-4258Y1471589D01*
G01X-4725Y1489266D02*
X-6693D01*
G01X-4725D02*
X-6693D01*
G01X-2196Y1488990D02*
X-3150D01*
G01X-2196D02*
X-3150D01*
G01X-4258Y1488833D02*
X-4725D01*
G01X-4258D02*
X-4725D01*
G01X-6693Y1488675D02*
X-9843D01*
G01X-6693D02*
X-9843D01*
G01X-12992Y1488636D02*
X0D01*
G01Y1487534D02*
X-12992D01*
G01X-9843Y1487494D02*
X-6693D01*
G01X-9843D02*
X-6693D01*
G01X-4725Y1487337D02*
X-4258D01*
G01X-4725D02*
X-4258D01*
G01X-3150Y1487179D02*
X-2196D01*
G01X-3150D02*
X-2196D01*
G01X-4725Y1486904D02*
X-6693D01*
G01X-4725D02*
X-6693D01*
G01X-4725Y1485329D02*
X-6693D01*
G01X-4725D02*
X-6693D01*
G01X-2196Y1485053D02*
X-3150D01*
G01X-2196D02*
X-3150D01*
G01X-4258Y1484896D02*
X-4725D01*
G01X-4258D02*
X-4725D01*
G01X-6693Y1484738D02*
X-9843D01*
G01X-6693D02*
X-9843D01*
G01X-12992Y1484699D02*
X0D01*
G01Y1483597D02*
X-12992D01*
G01X-9843Y1483557D02*
X-6693D01*
G01X-9843D02*
X-6693D01*
G01X-4725Y1483400D02*
X-4258D01*
G01X-4725D02*
X-4258D01*
G01X-3150Y1483242D02*
X-2196D01*
G01X-3150D02*
X-2196D01*
G01X-4725Y1482967D02*
X-6693D01*
G01X-4725D02*
X-6693D01*
G01X-4725Y1481392D02*
X-6693D01*
G01X-4725D02*
X-6693D01*
G01X-2196Y1481116D02*
X-3150D01*
G01X-2196D02*
X-3150D01*
G01X-4258Y1480959D02*
X-4725D01*
G01X-4258D02*
X-4725D01*
G01X-6693Y1480801D02*
X-9843D01*
G01X-6693D02*
X-9843D01*
G01X-12992Y1480762D02*
X0D01*
G01Y1479660D02*
X-12992D01*
G01X-9843Y1479620D02*
X-6693D01*
G01X-9843D02*
X-6693D01*
G01X-4725Y1479463D02*
X-4258D01*
G01X-4725D02*
X-4258D01*
G01X-3150Y1479305D02*
X-2196D01*
G01X-3150D02*
X-2196D01*
G01X-4725Y1479030D02*
X-6693D01*
G01X-4725D02*
X-6693D01*
G01X-4725Y1477455D02*
X-6693D01*
G01X-4725D02*
X-6693D01*
G01X-2196Y1477179D02*
X-3150D01*
G01X-2196D02*
X-3150D01*
G01X-4258Y1477022D02*
X-4725D01*
G01X-4258D02*
X-4725D01*
G01X-6693Y1476864D02*
X-9843D01*
G01X-6693D02*
X-9843D01*
G01X-12992Y1476825D02*
X0D01*
G01Y1475723D02*
X-12992D01*
G01X-9843Y1475683D02*
X-6693D01*
G01X-9843D02*
X-6693D01*
G01X-4725Y1475526D02*
X-4258D01*
G01X-4725D02*
X-4258D01*
G01X-3150Y1475368D02*
X-2196D01*
G01X-3150D02*
X-2196D01*
G01X-4725Y1475093D02*
X-6693D01*
G01X-4725D02*
X-6693D01*
G01X-4725Y1473518D02*
X-6693D01*
G01X-4725D02*
X-6693D01*
G01X-2196Y1473242D02*
X-3150D01*
G01X-2196D02*
X-3150D01*
G01X-4258Y1473085D02*
X-4725D01*
G01X-4258D02*
X-4725D01*
G01X-6693Y1472927D02*
X-9843D01*
G01X-6693D02*
X-9843D01*
G01X-12992Y1472888D02*
X0D01*
G01Y1471786D02*
X-12992D01*
G01X-9843Y1471746D02*
X-6693D01*
G01X-9843D02*
X-6693D01*
G01X-4725Y1471589D02*
X-4258D01*
G01X-4725D02*
X-4258D01*
G01X-3150Y1471431D02*
X-2196D01*
G01X-3150D02*
X-2196D01*
G01X-4725Y1471156D02*
X-6693D01*
G01X-4725D02*
X-6693D01*
G01X-4725Y1469581D02*
X-6693D01*
G01X-4725D02*
X-6693D01*
G01X-2196Y1469305D02*
X-3150D01*
G01X-2196D02*
X-3150D01*
G01X-4725Y1488360D02*
X-6693Y1488675D01*
G01X-4725Y1488360D02*
X-6693Y1488675D01*
G01X-4725Y1484423D02*
X-6693Y1484738D01*
G01X-4725Y1484423D02*
X-6693Y1484738D01*
G01X-4725Y1480486D02*
X-6693Y1480801D01*
G01X-4725Y1480486D02*
X-6693Y1480801D01*
G01X-4725Y1476549D02*
X-6693Y1476864D01*
G01X-4725Y1476549D02*
X-6693Y1476864D01*
G01X-4258Y1488833D02*
X-3377Y1488597D01*
G01X-4258Y1488833D02*
X-3377Y1488597D01*
G01X-4258Y1484896D02*
X-3377Y1484660D01*
G01X-4258Y1484896D02*
X-3377Y1484660D01*
G01X-4258Y1480959D02*
X-3377Y1480723D01*
G01X-4258Y1480959D02*
X-3377Y1480723D01*
G01X-4258Y1477022D02*
X-3377Y1476786D01*
G01X-4258Y1477022D02*
X-3377Y1476786D01*
G01X-4258Y1473085D02*
X-3377Y1472849D01*
G01X-4258Y1473085D02*
X-3377Y1472849D01*
G01X-4725Y1472612D02*
X-6693Y1472927D01*
G01X-4725Y1472612D02*
X-6693Y1472927D01*
G01X-9843Y1488675D02*
X-10630Y1489030D01*
G01D02*
X-9843Y1488675D01*
G01Y1484738D02*
X-10630Y1485093D01*
G01D02*
X-9843Y1484738D01*
G01Y1480801D02*
X-10630Y1481156D01*
G01D02*
X-9843Y1480801D01*
G01Y1476864D02*
X-10630Y1477219D01*
G01D02*
X-9843Y1476864D01*
G01Y1472927D02*
X-10630Y1473282D01*
G01D02*
X-9843Y1472927D01*
G01X-3150Y1487179D02*
X-3377Y1487573D01*
G01X-3150Y1487179D02*
X-3377Y1487573D01*
G01X-3150Y1483242D02*
X-3377Y1483636D01*
G01X-3150Y1483242D02*
X-3377Y1483636D01*
G01X-3150Y1479305D02*
X-3377Y1479699D01*
G01X-3150Y1479305D02*
X-3377Y1479699D01*
G01X-3150Y1475368D02*
X-3377Y1475762D01*
G01X-3150Y1475368D02*
X-3377Y1475762D01*
G01X-3150Y1471431D02*
X-3377Y1471825D01*
G01X-3150Y1471431D02*
X-3377Y1471825D01*
G01X-3756Y1475408D02*
Y1473203D01*
G01Y1471471D02*
Y1469266D01*
G01Y1479345D02*
Y1477140D01*
G01Y1483282D02*
Y1481077D01*
G01Y1487219D02*
Y1485014D01*
G01Y1491156D02*
Y1488951D01*
G01X-4725Y1484423D02*
Y1485329D01*
G01Y1486904D02*
Y1487809D01*
G01Y1488360D02*
Y1489266D01*
G01Y1480486D02*
Y1481392D01*
G01Y1482967D02*
Y1483872D01*
G01Y1475093D02*
Y1475998D01*
G01Y1476549D02*
Y1477455D01*
G01Y1479030D02*
Y1479935D01*
G01Y1471156D02*
Y1472061D01*
G01Y1472612D02*
Y1473518D01*
G01Y1472061D02*
Y1471156D01*
G01Y1473518D02*
Y1472612D01*
G01Y1475998D02*
Y1475093D01*
G01Y1477455D02*
Y1476549D01*
G01Y1479935D02*
Y1479030D01*
G01Y1481392D02*
Y1480486D01*
G01Y1483872D02*
Y1482967D01*
G01Y1485329D02*
Y1484423D01*
G01Y1487809D02*
Y1486904D01*
G01Y1489266D02*
Y1488360D01*
G01X-6693Y1471746D02*
Y1471156D01*
G01Y1473518D02*
Y1472927D01*
G01Y1475683D02*
Y1475093D01*
G01Y1471746D02*
Y1471156D01*
G01Y1473518D02*
Y1472927D01*
G01Y1475683D02*
Y1475093D01*
G01Y1477455D02*
Y1476864D01*
G01Y1479620D02*
Y1479030D01*
G01Y1477455D02*
Y1476864D01*
G01Y1479620D02*
Y1479030D01*
G01Y1481392D02*
Y1480801D01*
G01Y1483557D02*
Y1482967D01*
G01Y1481392D02*
Y1480801D01*
G01Y1483557D02*
Y1482967D01*
G01Y1485329D02*
Y1484738D01*
G01Y1487494D02*
Y1486904D01*
G01Y1489266D02*
Y1488675D01*
G01Y1485329D02*
Y1484738D01*
G01Y1487494D02*
Y1486904D01*
G01Y1489266D02*
Y1488675D01*
G01X-10530Y1475374D02*
Y1473237D01*
G01Y1471437D02*
Y1469300D01*
G01Y1475374D02*
Y1473237D01*
G01Y1471437D02*
Y1469300D01*
G01Y1479311D02*
Y1477174D01*
G01Y1479311D02*
Y1477174D01*
G01Y1483248D02*
Y1481111D01*
G01Y1483248D02*
Y1481111D01*
G01Y1487185D02*
Y1485048D01*
G01Y1487185D02*
Y1485048D01*
G01Y1491122D02*
Y1488985D01*
G01Y1491122D02*
Y1488985D01*
G01X-11842Y1489043D02*
Y1491064D01*
G01Y1485106D02*
Y1487127D01*
G01Y1481169D02*
Y1483190D01*
G01Y1477232D02*
Y1479253D01*
G01Y1473295D02*
Y1475316D01*
G01Y1469358D02*
Y1471378D01*
G01D02*
Y1469358D01*
G01Y1475316D02*
Y1473295D01*
G01Y1479253D02*
Y1477232D01*
G01Y1483190D02*
Y1481169D01*
G01Y1487127D02*
Y1485106D01*
G01Y1491064D02*
Y1489043D01*
G01X-12280Y1489048D02*
Y1491058D01*
G01Y1485111D02*
Y1487121D01*
G01Y1481174D02*
Y1483184D01*
G01Y1477237D02*
Y1479247D01*
G01Y1473300D02*
Y1475310D01*
G01Y1469363D02*
Y1471373D01*
G01D02*
Y1469363D01*
G01Y1475310D02*
Y1473300D01*
G01Y1479247D02*
Y1477237D01*
G01Y1483184D02*
Y1481174D01*
G01Y1487121D02*
Y1485111D01*
G01Y1491058D02*
Y1489048D01*
G01X-12992Y1471786D02*
Y1471471D01*
G01Y1475723D02*
Y1475408D01*
G01Y1473203D02*
Y1472888D01*
G01Y1479660D02*
Y1479345D01*
G01Y1477140D02*
Y1476825D01*
G01Y1483597D02*
Y1483282D01*
G01Y1481077D02*
Y1480762D01*
G01Y1485014D02*
Y1484699D01*
G01Y1487534D02*
Y1487219D01*
G01Y1488951D02*
Y1488636D01*
G01X-23684Y1489175D02*
Y1490932D01*
G01Y1485238D02*
Y1486995D01*
G01Y1481301D02*
Y1483058D01*
G01Y1477364D02*
Y1479121D01*
G01Y1469490D02*
Y1471247D01*
G01Y1473427D02*
Y1475184D01*
G01D02*
Y1473427D01*
G01Y1471247D02*
Y1469490D01*
G01Y1479121D02*
Y1477364D01*
G01Y1483058D02*
Y1481301D01*
G01Y1486995D02*
Y1485238D01*
G01Y1490932D02*
Y1489175D01*
G01X-10630Y1471392D02*
X-9843Y1471746D01*
G01D02*
X-10630Y1471392D01*
G01Y1475329D02*
X-9843Y1475683D01*
G01D02*
X-10630Y1475329D01*
G01Y1479266D02*
X-9843Y1479620D01*
G01D02*
X-10630Y1479266D01*
G01Y1483203D02*
X-9843Y1483557D01*
G01D02*
X-10630Y1483203D01*
G01Y1487140D02*
X-9843Y1487494D01*
G01D02*
X-10630Y1487140D01*
G01X-3377Y1472849D02*
X-3150Y1473242D01*
G01X-3377Y1472849D02*
X-3150Y1473242D01*
G01X-3377Y1476786D02*
X-3150Y1477179D01*
G01X-3377Y1476786D02*
X-3150Y1477179D01*
G01X-3377Y1480723D02*
X-3150Y1481116D01*
G01X-3377Y1480723D02*
X-3150Y1481116D01*
G01X-3377Y1484660D02*
X-3150Y1485053D01*
G01X-3377Y1484660D02*
X-3150Y1485053D01*
G01X-3377Y1488597D02*
X-3150Y1488990D01*
G01X-3377Y1488597D02*
X-3150Y1488990D01*
G01X-3377Y1511195D02*
X-4258Y1510959D01*
G01X-3377Y1511195D02*
X-4258Y1510959D01*
G01X-3377Y1507258D02*
X-4258Y1507022D01*
G01X-3377Y1507258D02*
X-4258Y1507022D01*
G01X-3377Y1503321D02*
X-4258Y1503085D01*
G01X-3377Y1503321D02*
X-4258Y1503085D01*
G01X-3377Y1499384D02*
X-4258Y1499148D01*
G01X-3377Y1499384D02*
X-4258Y1499148D01*
G01X-6693Y1511116D02*
X-4725Y1511431D01*
G01X-6693Y1511116D02*
X-4725Y1511431D01*
G01X-6693Y1507179D02*
X-4725Y1507494D01*
G01X-6693Y1507179D02*
X-4725Y1507494D01*
G01X-6693Y1503242D02*
X-4725Y1503557D01*
G01X-6693Y1503242D02*
X-4725Y1503557D01*
G01X-6693Y1499305D02*
X-4725Y1499620D01*
G01X-6693Y1499305D02*
X-4725Y1499620D01*
G01X-6693Y1495368D02*
X-4725Y1495683D01*
G01X-6693Y1495368D02*
X-4725Y1495683D01*
G01X-6693Y1491431D02*
X-4725Y1491746D01*
G01X-6693Y1491431D02*
X-4725Y1491746D01*
G01X-3377Y1495447D02*
X-4258Y1495211D01*
G01X-3377Y1495447D02*
X-4258Y1495211D01*
G01X-3377Y1491510D02*
X-4258Y1491274D01*
G01X-3377Y1491510D02*
X-4258Y1491274D01*
G01X0Y1511156D02*
X-12992D01*
G01X-9843Y1511116D02*
X-6693D01*
G01X-9843D02*
X-6693D01*
G01X-4725Y1510959D02*
X-4258D01*
G01X-4725D02*
X-4258D01*
G01X-3150Y1510801D02*
X-2196D01*
G01X-3150D02*
X-2196D01*
G01X-4725Y1510526D02*
X-6693D01*
G01X-4725D02*
X-6693D01*
G01X-4725Y1508951D02*
X-6693D01*
G01X-4725D02*
X-6693D01*
G01X-2196Y1508675D02*
X-3150D01*
G01X-2196D02*
X-3150D01*
G01X-4258Y1508518D02*
X-4725D01*
G01X-4258D02*
X-4725D01*
G01X-6693Y1508360D02*
X-9843D01*
G01X-6693D02*
X-9843D01*
G01X-12992Y1508321D02*
X0D01*
G01Y1507219D02*
X-12992D01*
G01X-9843Y1507179D02*
X-6693D01*
G01X-9843D02*
X-6693D01*
G01X-4725Y1507022D02*
X-4258D01*
G01X-4725D02*
X-4258D01*
G01X-3150Y1506864D02*
X-2196D01*
G01X-3150D02*
X-2196D01*
G01X-4725Y1506589D02*
X-6693D01*
G01X-4725D02*
X-6693D01*
G01X-4725Y1505014D02*
X-6693D01*
G01X-4725D02*
X-6693D01*
G01X-2196Y1504738D02*
X-3150D01*
G01X-2196D02*
X-3150D01*
G01X-4258Y1504581D02*
X-4725D01*
G01X-4258D02*
X-4725D01*
G01X-6693Y1504423D02*
X-9843D01*
G01X-6693D02*
X-9843D01*
G01X-12992Y1504384D02*
X0D01*
G01Y1503282D02*
X-12992D01*
G01X-9843Y1503242D02*
X-6693D01*
G01X-9843D02*
X-6693D01*
G01X-4725Y1503085D02*
X-4258D01*
G01X-4725D02*
X-4258D01*
G01X-3150Y1502927D02*
X-2196D01*
G01X-3150D02*
X-2196D01*
G01X-4725Y1502652D02*
X-6693D01*
G01X-4725D02*
X-6693D01*
G01X-4725Y1501077D02*
X-6693D01*
G01X-4725D02*
X-6693D01*
G01X-2196Y1500801D02*
X-3150D01*
G01X-2196D02*
X-3150D01*
G01X-4258Y1500644D02*
X-4725D01*
G01X-4258D02*
X-4725D01*
G01X-6693Y1500486D02*
X-9843D01*
G01X-6693D02*
X-9843D01*
G01X-12992Y1500447D02*
X0D01*
G01Y1499345D02*
X-12992D01*
G01X-9843Y1499305D02*
X-6693D01*
G01X-9843D02*
X-6693D01*
G01X-4725Y1499148D02*
X-4258D01*
G01X-4725D02*
X-4258D01*
G01X-3150Y1498990D02*
X-2196D01*
G01X-3150D02*
X-2196D01*
G01X-4725Y1498715D02*
X-6693D01*
G01X-4725D02*
X-6693D01*
G01X-4725Y1497140D02*
X-6693D01*
G01X-4725D02*
X-6693D01*
G01X-2196Y1496864D02*
X-3150D01*
G01X-2196D02*
X-3150D01*
G01X-4258Y1496707D02*
X-4725D01*
G01X-4258D02*
X-4725D01*
G01X-6693Y1496549D02*
X-9843D01*
G01X-6693D02*
X-9843D01*
G01X-12992Y1496510D02*
X0D01*
G01Y1495408D02*
X-12992D01*
G01X-9843Y1495368D02*
X-6693D01*
G01X-9843D02*
X-6693D01*
G01X-4725Y1495211D02*
X-4258D01*
G01X-4725D02*
X-4258D01*
G01X-3150Y1495053D02*
X-2196D01*
G01X-3150D02*
X-2196D01*
G01X-4725Y1494778D02*
X-6693D01*
G01X-4725D02*
X-6693D01*
G01X-4725Y1493203D02*
X-6693D01*
G01X-4725D02*
X-6693D01*
G01X-2196Y1492927D02*
X-3150D01*
G01X-2196D02*
X-3150D01*
G01X-4258Y1492770D02*
X-4725D01*
G01X-4258D02*
X-4725D01*
G01X-6693Y1492612D02*
X-9843D01*
G01X-6693D02*
X-9843D01*
G01X-12992Y1492573D02*
X0D01*
G01Y1491471D02*
X-12992D01*
G01X-9843Y1491431D02*
X-6693D01*
G01X-9843D02*
X-6693D01*
G01X-4725Y1491274D02*
X-4258D01*
G01X-4725D02*
X-4258D01*
G01X-3150Y1491116D02*
X-2196D01*
G01X-3150D02*
X-2196D01*
G01X-4725Y1490841D02*
X-6693D01*
G01X-4725D02*
X-6693D01*
G01X-4725Y1508045D02*
X-6693Y1508360D01*
G01X-4725Y1508045D02*
X-6693Y1508360D01*
G01X-4725Y1504108D02*
X-6693Y1504423D01*
G01X-4725Y1504108D02*
X-6693Y1504423D01*
G01X-4725Y1500171D02*
X-6693Y1500486D01*
G01X-4725Y1500171D02*
X-6693Y1500486D01*
G01X-4725Y1496234D02*
X-6693Y1496549D01*
G01X-4725Y1496234D02*
X-6693Y1496549D01*
G01X-4725Y1492297D02*
X-6693Y1492612D01*
G01X-4725Y1492297D02*
X-6693Y1492612D01*
G01X-4258Y1508518D02*
X-3377Y1508282D01*
G01X-4258Y1508518D02*
X-3377Y1508282D01*
G01X-4258Y1504581D02*
X-3377Y1504345D01*
G01X-4258Y1504581D02*
X-3377Y1504345D01*
G01X-4258Y1500644D02*
X-3377Y1500408D01*
G01X-4258Y1500644D02*
X-3377Y1500408D01*
G01X-4258Y1496707D02*
X-3377Y1496471D01*
G01X-4258Y1496707D02*
X-3377Y1496471D01*
G01X-4258Y1492770D02*
X-3377Y1492534D01*
G01X-4258Y1492770D02*
X-3377Y1492534D01*
G01X-9843Y1508360D02*
X-10630Y1508715D01*
G01D02*
X-9843Y1508360D01*
G01Y1504423D02*
X-10630Y1504778D01*
G01D02*
X-9843Y1504423D01*
G01Y1500486D02*
X-10630Y1500841D01*
G01D02*
X-9843Y1500486D01*
G01Y1496549D02*
X-10630Y1496904D01*
G01D02*
X-9843Y1496549D01*
G01Y1492612D02*
X-10630Y1492967D01*
G01D02*
X-9843Y1492612D01*
G01X-3150Y1510801D02*
X-3377Y1511195D01*
G01X-3150Y1510801D02*
X-3377Y1511195D01*
G01X-3150Y1506864D02*
X-3377Y1507258D01*
G01X-3150Y1506864D02*
X-3377Y1507258D01*
G01X-3150Y1502927D02*
X-3377Y1503321D01*
G01X-3150Y1502927D02*
X-3377Y1503321D01*
G01X-3150Y1498990D02*
X-3377Y1499384D01*
G01X-3150Y1498990D02*
X-3377Y1499384D01*
G01X-3150Y1495053D02*
X-3377Y1495447D01*
G01X-3150Y1495053D02*
X-3377Y1495447D01*
G01X-3150Y1491116D02*
X-3377Y1491510D01*
G01X-3150Y1491116D02*
X-3377Y1491510D01*
G01X-3756Y1499030D02*
Y1496825D01*
G01Y1495093D02*
Y1492888D01*
G01Y1502967D02*
Y1500762D01*
G01Y1506904D02*
Y1504699D01*
G01Y1510841D02*
Y1508636D01*
G01X-4725Y1508045D02*
Y1508951D01*
G01Y1510526D02*
Y1511431D01*
G01Y1504108D02*
Y1505014D01*
G01Y1506589D02*
Y1507494D01*
G01Y1498715D02*
Y1499620D01*
G01Y1500171D02*
Y1501077D01*
G01Y1502652D02*
Y1503557D01*
G01Y1494778D02*
Y1495683D01*
G01Y1496234D02*
Y1497140D01*
G01Y1490841D02*
Y1491746D01*
G01Y1492297D02*
Y1493203D01*
G01Y1491746D02*
Y1490841D01*
G01Y1493203D02*
Y1492297D01*
G01Y1495683D02*
Y1494778D01*
G01Y1497140D02*
Y1496234D01*
G01Y1499620D02*
Y1498715D01*
G01Y1501077D02*
Y1500171D01*
G01Y1503557D02*
Y1502652D01*
G01Y1505014D02*
Y1504108D01*
G01Y1507494D02*
Y1506589D01*
G01Y1508951D02*
Y1508045D01*
G01Y1511431D02*
Y1510526D01*
G01X-6693Y1491431D02*
Y1490841D01*
G01Y1493203D02*
Y1492612D01*
G01Y1491431D02*
Y1490841D01*
G01Y1493203D02*
Y1492612D01*
G01Y1495368D02*
Y1494778D01*
G01Y1497140D02*
Y1496549D01*
G01Y1499305D02*
Y1498715D01*
G01Y1495368D02*
Y1494778D01*
G01Y1497140D02*
Y1496549D01*
G01Y1499305D02*
Y1498715D01*
G01Y1501077D02*
Y1500486D01*
G01Y1503242D02*
Y1502652D01*
G01Y1501077D02*
Y1500486D01*
G01Y1503242D02*
Y1502652D01*
G01Y1505014D02*
Y1504423D01*
G01Y1507179D02*
Y1506589D01*
G01Y1505014D02*
Y1504423D01*
G01Y1507179D02*
Y1506589D01*
G01Y1508951D02*
Y1508360D01*
G01Y1511116D02*
Y1510526D01*
G01Y1508951D02*
Y1508360D01*
G01Y1511116D02*
Y1510526D01*
G01X-10530Y1498996D02*
Y1496859D01*
G01Y1495059D02*
Y1492922D01*
G01Y1498996D02*
Y1496859D01*
G01Y1495059D02*
Y1492922D01*
G01Y1502933D02*
Y1500796D01*
G01Y1502933D02*
Y1500796D01*
G01Y1506870D02*
Y1504733D01*
G01Y1506870D02*
Y1504733D01*
G01Y1510807D02*
Y1508670D01*
G01Y1510807D02*
Y1508670D01*
G01X-11842Y1508728D02*
Y1510749D01*
G01Y1504791D02*
Y1506812D01*
G01Y1500854D02*
Y1502875D01*
G01Y1496917D02*
Y1498938D01*
G01Y1492980D02*
Y1495001D01*
G01D02*
Y1492980D01*
G01Y1498938D02*
Y1496917D01*
G01Y1502875D02*
Y1500854D01*
G01Y1506812D02*
Y1504791D01*
G01Y1510749D02*
Y1508728D01*
G01X-12280Y1508733D02*
Y1510743D01*
G01Y1504796D02*
Y1506806D01*
G01Y1500859D02*
Y1502869D01*
G01Y1496922D02*
Y1498932D01*
G01Y1492985D02*
Y1494995D01*
G01D02*
Y1492985D01*
G01Y1498932D02*
Y1496922D01*
G01Y1502869D02*
Y1500859D01*
G01Y1506806D02*
Y1504796D01*
G01Y1510743D02*
Y1508733D01*
G01X-12992Y1491471D02*
Y1491156D01*
G01Y1492888D02*
Y1492573D01*
G01Y1495408D02*
Y1495093D01*
G01Y1496825D02*
Y1496510D01*
G01Y1499345D02*
Y1499030D01*
G01Y1503282D02*
Y1502967D01*
G01Y1500762D02*
Y1500447D01*
G01Y1507219D02*
Y1506904D01*
G01Y1504699D02*
Y1504384D01*
G01Y1508636D02*
Y1508321D01*
G01Y1511156D02*
Y1510841D01*
G01X-23684Y1508860D02*
Y1510617D01*
G01Y1504923D02*
Y1506680D01*
G01Y1500986D02*
Y1502743D01*
G01Y1493112D02*
Y1494869D01*
G01Y1497049D02*
Y1498806D01*
G01D02*
Y1497049D01*
G01Y1494869D02*
Y1493112D01*
G01Y1502743D02*
Y1500986D01*
G01Y1506680D02*
Y1504923D01*
G01Y1510617D02*
Y1508860D01*
G01X-10630Y1491077D02*
X-9843Y1491431D01*
G01D02*
X-10630Y1491077D01*
G01Y1495014D02*
X-9843Y1495368D01*
G01D02*
X-10630Y1495014D01*
G01Y1498951D02*
X-9843Y1499305D01*
G01D02*
X-10630Y1498951D01*
G01Y1502888D02*
X-9843Y1503242D01*
G01D02*
X-10630Y1502888D01*
G01Y1506825D02*
X-9843Y1507179D01*
G01D02*
X-10630Y1506825D01*
G01Y1510762D02*
X-9843Y1511116D01*
G01D02*
X-10630Y1510762D01*
G01X-3377Y1492534D02*
X-3150Y1492927D01*
G01X-3377Y1492534D02*
X-3150Y1492927D01*
G01X-3377Y1496471D02*
X-3150Y1496864D01*
G01X-3377Y1496471D02*
X-3150Y1496864D01*
G01X-3377Y1500408D02*
X-3150Y1500801D01*
G01X-3377Y1500408D02*
X-3150Y1500801D01*
G01X-3377Y1504345D02*
X-3150Y1504738D01*
G01X-3377Y1504345D02*
X-3150Y1504738D01*
G01X-3377Y1508282D02*
X-3150Y1508675D01*
G01X-3377Y1508282D02*
X-3150Y1508675D01*
G01X-3377Y1530880D02*
X-4258Y1530644D01*
G01X-3377Y1530880D02*
X-4258Y1530644D01*
G01X-3377Y1526943D02*
X-4258Y1526707D01*
G01X-3377Y1526943D02*
X-4258Y1526707D01*
G01X-3377Y1523006D02*
X-4258Y1522770D01*
G01X-3377Y1523006D02*
X-4258Y1522770D01*
G01X-3377Y1519069D02*
X-4258Y1518833D01*
G01X-3377Y1519069D02*
X-4258Y1518833D01*
G01X-3377Y1515132D02*
X-4258Y1514896D01*
G01X-3377Y1515132D02*
X-4258Y1514896D01*
G01X-6693Y1530801D02*
X-4725Y1531116D01*
G01X-6693Y1530801D02*
X-4725Y1531116D01*
G01X-6693Y1526864D02*
X-4725Y1527179D01*
G01X-6693Y1526864D02*
X-4725Y1527179D01*
G01X-6693Y1522927D02*
X-4725Y1523242D01*
G01X-6693Y1522927D02*
X-4725Y1523242D01*
G01X-6693Y1518990D02*
X-4725Y1519305D01*
G01X-6693Y1518990D02*
X-4725Y1519305D01*
G01X-6693Y1515053D02*
X-4725Y1515368D01*
G01X-6693Y1515053D02*
X-4725Y1515368D01*
G01Y1532573D02*
X-6693D01*
G01X-4725D02*
X-6693D01*
G01X-2196Y1532297D02*
X-3150D01*
G01X-2196D02*
X-3150D01*
G01X-4258Y1532140D02*
X-4725D01*
G01X-4258D02*
X-4725D01*
G01X-6693Y1531982D02*
X-9843D01*
G01X-6693D02*
X-9843D01*
G01X-12992Y1531943D02*
X0D01*
G01Y1530841D02*
X-12992D01*
G01X-9843Y1530801D02*
X-6693D01*
G01X-9843D02*
X-6693D01*
G01X-4725Y1530644D02*
X-4258D01*
G01X-4725D02*
X-4258D01*
G01X-3150Y1530486D02*
X-2196D01*
G01X-3150D02*
X-2196D01*
G01X-4725Y1530211D02*
X-6693D01*
G01X-4725D02*
X-6693D01*
G01X-4725Y1528636D02*
X-6693D01*
G01X-4725D02*
X-6693D01*
G01X-2196Y1528360D02*
X-3150D01*
G01X-2196D02*
X-3150D01*
G01X-4258Y1528203D02*
X-4725D01*
G01X-4258D02*
X-4725D01*
G01X-6693Y1528045D02*
X-9843D01*
G01X-6693D02*
X-9843D01*
G01X-12992Y1528006D02*
X0D01*
G01Y1526904D02*
X-12992D01*
G01X-9843Y1526864D02*
X-6693D01*
G01X-9843D02*
X-6693D01*
G01X-4725Y1526707D02*
X-4258D01*
G01X-4725D02*
X-4258D01*
G01X-3150Y1526549D02*
X-2196D01*
G01X-3150D02*
X-2196D01*
G01X-4725Y1526274D02*
X-6693D01*
G01X-4725D02*
X-6693D01*
G01X-4725Y1524699D02*
X-6693D01*
G01X-4725D02*
X-6693D01*
G01X-2196Y1524423D02*
X-3150D01*
G01X-2196D02*
X-3150D01*
G01X-4258Y1524266D02*
X-4725D01*
G01X-4258D02*
X-4725D01*
G01X-6693Y1524108D02*
X-9843D01*
G01X-6693D02*
X-9843D01*
G01X-12992Y1524069D02*
X0D01*
G01Y1522967D02*
X-12992D01*
G01X-9843Y1522927D02*
X-6693D01*
G01X-9843D02*
X-6693D01*
G01X-4725Y1522770D02*
X-4258D01*
G01X-4725D02*
X-4258D01*
G01X-3150Y1522612D02*
X-2196D01*
G01X-3150D02*
X-2196D01*
G01X-4725Y1522337D02*
X-6693D01*
G01X-4725D02*
X-6693D01*
G01X-4725Y1520762D02*
X-6693D01*
G01X-4725D02*
X-6693D01*
G01X-2196Y1520486D02*
X-3150D01*
G01X-2196D02*
X-3150D01*
G01X-4258Y1520329D02*
X-4725D01*
G01X-4258D02*
X-4725D01*
G01X-6693Y1520171D02*
X-9843D01*
G01X-6693D02*
X-9843D01*
G01X-12992Y1520132D02*
X0D01*
G01Y1519030D02*
X-12992D01*
G01X-9843Y1518990D02*
X-6693D01*
G01X-9843D02*
X-6693D01*
G01X-4725Y1518833D02*
X-4258D01*
G01X-4725D02*
X-4258D01*
G01X-3150Y1518675D02*
X-2196D01*
G01X-3150D02*
X-2196D01*
G01X-4725Y1518400D02*
X-6693D01*
G01X-4725D02*
X-6693D01*
G01X-4725Y1516825D02*
X-6693D01*
G01X-4725D02*
X-6693D01*
G01X-2196Y1516549D02*
X-3150D01*
G01X-2196D02*
X-3150D01*
G01X-4258Y1516392D02*
X-4725D01*
G01X-4258D02*
X-4725D01*
G01X-6693Y1516234D02*
X-9843D01*
G01X-6693D02*
X-9843D01*
G01X-12992Y1516195D02*
X0D01*
G01Y1515093D02*
X-12992D01*
G01X-9843Y1515053D02*
X-6693D01*
G01X-9843D02*
X-6693D01*
G01X-4725Y1514896D02*
X-4258D01*
G01X-4725D02*
X-4258D01*
G01X-3150Y1514738D02*
X-2196D01*
G01X-3150D02*
X-2196D01*
G01X-4725Y1514463D02*
X-6693D01*
G01X-4725D02*
X-6693D01*
G01X-4725Y1512888D02*
X-6693D01*
G01X-4725D02*
X-6693D01*
G01X-2196Y1512612D02*
X-3150D01*
G01X-2196D02*
X-3150D01*
G01X-4258Y1512455D02*
X-4725D01*
G01X-4258D02*
X-4725D01*
G01X-6693Y1512297D02*
X-9843D01*
G01X-6693D02*
X-9843D01*
G01X-12992Y1512258D02*
X0D01*
G01X-4725Y1531667D02*
X-6693Y1531982D01*
G01X-4725Y1531667D02*
X-6693Y1531982D01*
G01X-4725Y1527730D02*
X-6693Y1528045D01*
G01X-4725Y1527730D02*
X-6693Y1528045D01*
G01X-4725Y1523793D02*
X-6693Y1524108D01*
G01X-4725Y1523793D02*
X-6693Y1524108D01*
G01X-4725Y1519856D02*
X-6693Y1520171D01*
G01X-4725Y1519856D02*
X-6693Y1520171D01*
G01X-4725Y1515919D02*
X-6693Y1516234D01*
G01X-4725Y1515919D02*
X-6693Y1516234D01*
G01X-4725Y1511982D02*
X-6693Y1512297D01*
G01X-4725Y1511982D02*
X-6693Y1512297D01*
G01X-4258Y1532140D02*
X-3377Y1531904D01*
G01X-4258Y1532140D02*
X-3377Y1531904D01*
G01X-4258Y1528203D02*
X-3377Y1527967D01*
G01X-4258Y1528203D02*
X-3377Y1527967D01*
G01X-4258Y1524266D02*
X-3377Y1524030D01*
G01X-4258Y1524266D02*
X-3377Y1524030D01*
G01X-4258Y1520329D02*
X-3377Y1520093D01*
G01X-4258Y1520329D02*
X-3377Y1520093D01*
G01X-4258Y1516392D02*
X-3377Y1516156D01*
G01X-4258Y1516392D02*
X-3377Y1516156D01*
G01X-4258Y1512455D02*
X-3377Y1512219D01*
G01X-4258Y1512455D02*
X-3377Y1512219D01*
G01X-9843Y1531982D02*
X-10630Y1532337D01*
G01D02*
X-9843Y1531982D01*
G01Y1528045D02*
X-10630Y1528400D01*
G01D02*
X-9843Y1528045D01*
G01Y1524108D02*
X-10630Y1524463D01*
G01D02*
X-9843Y1524108D01*
G01Y1520171D02*
X-10630Y1520526D01*
G01D02*
X-9843Y1520171D01*
G01Y1516234D02*
X-10630Y1516589D01*
G01D02*
X-9843Y1516234D01*
G01Y1512297D02*
X-10630Y1512652D01*
G01D02*
X-9843Y1512297D01*
G01X-3150Y1530486D02*
X-3377Y1530880D01*
G01X-3150Y1530486D02*
X-3377Y1530880D01*
G01X-3150Y1526549D02*
X-3377Y1526943D01*
G01X-3150Y1526549D02*
X-3377Y1526943D01*
G01X-3150Y1522612D02*
X-3377Y1523006D01*
G01X-3150Y1522612D02*
X-3377Y1523006D01*
G01X-3150Y1518675D02*
X-3377Y1519069D01*
G01X-3150Y1518675D02*
X-3377Y1519069D01*
G01X-3150Y1514738D02*
X-3377Y1515132D01*
G01X-3150Y1514738D02*
X-3377Y1515132D01*
G01X-3756Y1514778D02*
Y1512573D01*
G01Y1522652D02*
Y1520447D01*
G01Y1518715D02*
Y1516510D01*
G01Y1526589D02*
Y1524384D01*
G01Y1530526D02*
Y1528321D01*
G01Y1534463D02*
Y1532258D01*
G01X-4725Y1531667D02*
Y1532573D01*
G01Y1527730D02*
Y1528636D01*
G01Y1530211D02*
Y1531116D01*
G01Y1522337D02*
Y1523242D01*
G01Y1523793D02*
Y1524699D01*
G01Y1526274D02*
Y1527179D01*
G01Y1518400D02*
Y1519305D01*
G01Y1519856D02*
Y1520762D01*
G01Y1514463D02*
Y1515368D01*
G01Y1515919D02*
Y1516825D01*
G01Y1511982D02*
Y1512888D01*
G01D02*
Y1511982D01*
G01Y1515368D02*
Y1514463D01*
G01Y1516825D02*
Y1515919D01*
G01Y1519305D02*
Y1518400D01*
G01Y1520762D02*
Y1519856D01*
G01Y1523242D02*
Y1522337D01*
G01Y1524699D02*
Y1523793D01*
G01Y1527179D02*
Y1526274D01*
G01Y1528636D02*
Y1527730D01*
G01Y1531116D02*
Y1530211D01*
G01Y1532573D02*
Y1531667D01*
G01X-6693Y1512888D02*
Y1512297D01*
G01Y1512888D02*
Y1512297D01*
G01Y1515053D02*
Y1514463D01*
G01Y1516825D02*
Y1516234D01*
G01Y1515053D02*
Y1514463D01*
G01Y1516825D02*
Y1516234D01*
G01Y1518990D02*
Y1518400D01*
G01Y1520762D02*
Y1520171D01*
G01Y1518990D02*
Y1518400D01*
G01Y1520762D02*
Y1520171D01*
G01Y1522927D02*
Y1522337D01*
G01Y1524699D02*
Y1524108D01*
G01Y1526864D02*
Y1526274D01*
G01Y1522927D02*
Y1522337D01*
G01Y1524699D02*
Y1524108D01*
G01Y1526864D02*
Y1526274D01*
G01Y1528636D02*
Y1528045D01*
G01Y1530801D02*
Y1530211D01*
G01Y1528636D02*
Y1528045D01*
G01Y1530801D02*
Y1530211D01*
G01Y1532573D02*
Y1531982D01*
G01Y1532573D02*
Y1531982D01*
G01X-10530Y1514744D02*
Y1512607D01*
G01Y1514744D02*
Y1512607D01*
G01Y1522618D02*
Y1520481D01*
G01Y1518681D02*
Y1516544D01*
G01Y1522618D02*
Y1520481D01*
G01Y1518681D02*
Y1516544D01*
G01Y1526555D02*
Y1524418D01*
G01Y1526555D02*
Y1524418D01*
G01Y1530492D02*
Y1528355D01*
G01Y1530492D02*
Y1528355D01*
G01Y1534429D02*
Y1532292D01*
G01Y1534429D02*
Y1532292D01*
G01X-11842Y1532350D02*
Y1534371D01*
G01Y1528413D02*
Y1530434D01*
G01Y1524476D02*
Y1526497D01*
G01Y1520539D02*
Y1522560D01*
G01Y1516602D02*
Y1518623D01*
G01Y1512665D02*
Y1514686D01*
G01D02*
Y1512665D01*
G01Y1518623D02*
Y1516602D01*
G01Y1522560D02*
Y1520539D01*
G01Y1526497D02*
Y1524476D01*
G01Y1530434D02*
Y1528413D01*
G01Y1534371D02*
Y1532350D01*
G01X-12280Y1532355D02*
Y1534366D01*
G01Y1528418D02*
Y1530428D01*
G01Y1524481D02*
Y1526491D01*
G01Y1520544D02*
Y1522554D01*
G01Y1516607D02*
Y1518617D01*
G01Y1512670D02*
Y1514680D01*
G01D02*
Y1512670D01*
G01Y1518617D02*
Y1516607D01*
G01Y1522554D02*
Y1520544D01*
G01Y1526491D02*
Y1524481D01*
G01Y1530428D02*
Y1528418D01*
G01Y1534366D02*
Y1532355D01*
G01X-12992Y1512573D02*
Y1512258D01*
G01Y1515093D02*
Y1514778D01*
G01Y1516510D02*
Y1516195D01*
G01Y1519030D02*
Y1518715D01*
G01Y1520447D02*
Y1520132D01*
G01Y1522967D02*
Y1522652D01*
G01Y1526904D02*
Y1526589D01*
G01Y1524384D02*
Y1524069D01*
G01Y1530841D02*
Y1530526D01*
G01Y1528321D02*
Y1528006D01*
G01Y1532258D02*
Y1531943D01*
G01X-23684Y1532482D02*
Y1534239D01*
G01Y1528545D02*
Y1530302D01*
G01Y1524608D02*
Y1526365D01*
G01Y1516734D02*
Y1518491D01*
G01Y1520671D02*
Y1522428D01*
G01Y1512797D02*
Y1514554D01*
G01D02*
Y1512797D01*
G01Y1522428D02*
Y1520671D01*
G01Y1518491D02*
Y1516734D01*
G01Y1526365D02*
Y1524608D01*
G01Y1530302D02*
Y1528545D01*
G01Y1534239D02*
Y1532482D01*
G01X-10630Y1514699D02*
X-9843Y1515053D01*
G01D02*
X-10630Y1514699D01*
G01Y1518636D02*
X-9843Y1518990D01*
G01D02*
X-10630Y1518636D01*
G01Y1522573D02*
X-9843Y1522927D01*
G01D02*
X-10630Y1522573D01*
G01Y1526510D02*
X-9843Y1526864D01*
G01D02*
X-10630Y1526510D01*
G01Y1530447D02*
X-9843Y1530801D01*
G01D02*
X-10630Y1530447D01*
G01X-3377Y1512219D02*
X-3150Y1512612D01*
G01X-3377Y1512219D02*
X-3150Y1512612D01*
G01X-3377Y1516156D02*
X-3150Y1516549D01*
G01X-3377Y1516156D02*
X-3150Y1516549D01*
G01X-3377Y1520093D02*
X-3150Y1520486D01*
G01X-3377Y1520093D02*
X-3150Y1520486D01*
G01X-3377Y1524030D02*
X-3150Y1524423D01*
G01X-3377Y1524030D02*
X-3150Y1524423D01*
G01X-3377Y1527967D02*
X-3150Y1528360D01*
G01X-3377Y1527967D02*
X-3150Y1528360D01*
G01X-3377Y1531904D02*
X-3150Y1532297D01*
G01X-3377Y1531904D02*
X-3150Y1532297D01*
G01X-6693Y1550486D02*
X-4725Y1550801D01*
G01X-6693Y1550486D02*
X-4725Y1550801D01*
G01X-6693Y1546549D02*
X-4725Y1546864D01*
G01X-6693Y1546549D02*
X-4725Y1546864D01*
G01X-6693Y1542612D02*
X-4725Y1542927D01*
G01X-6693Y1542612D02*
X-4725Y1542927D01*
G01X-3377Y1550565D02*
X-4258Y1550329D01*
G01X-3377Y1550565D02*
X-4258Y1550329D01*
G01X-3377Y1546628D02*
X-4258Y1546392D01*
G01X-3377Y1546628D02*
X-4258Y1546392D01*
G01X-3377Y1542691D02*
X-4258Y1542455D01*
G01X-3377Y1542691D02*
X-4258Y1542455D01*
G01X-3377Y1538754D02*
X-4258Y1538518D01*
G01X-3377Y1538754D02*
X-4258Y1538518D01*
G01X-3377Y1534817D02*
X-4258Y1534581D01*
G01X-3377Y1534817D02*
X-4258Y1534581D01*
G01X-4725Y1552258D02*
X-6693D01*
G01X-4725D02*
X-6693D01*
G01X-2196Y1551982D02*
X-3150D01*
G01X-2196D02*
X-3150D01*
G01X-4258Y1551825D02*
X-4725D01*
G01X-4258D02*
X-4725D01*
G01X-6693Y1551667D02*
X-9843D01*
G01X-6693D02*
X-9843D01*
G01X-12992Y1551628D02*
X0D01*
G01Y1550526D02*
X-12992D01*
G01X-9843Y1550486D02*
X-6693D01*
G01X-9843D02*
X-6693D01*
G01X-4725Y1550329D02*
X-4258D01*
G01X-4725D02*
X-4258D01*
G01X-3150Y1550171D02*
X-2196D01*
G01X-3150D02*
X-2196D01*
G01X-4725Y1549896D02*
X-6693D01*
G01X-4725D02*
X-6693D01*
G01X-4725Y1548321D02*
X-6693D01*
G01X-4725D02*
X-6693D01*
G01X-2196Y1548045D02*
X-3150D01*
G01X-2196D02*
X-3150D01*
G01X-4258Y1547888D02*
X-4725D01*
G01X-4258D02*
X-4725D01*
G01X-6693Y1547730D02*
X-9843D01*
G01X-6693D02*
X-9843D01*
G01X-12992Y1547691D02*
X0D01*
G01Y1546589D02*
X-12992D01*
G01X-9843Y1546549D02*
X-6693D01*
G01X-9843D02*
X-6693D01*
G01X-4725Y1546392D02*
X-4258D01*
G01X-4725D02*
X-4258D01*
G01X-3150Y1546234D02*
X-2196D01*
G01X-3150D02*
X-2196D01*
G01X-4725Y1545959D02*
X-6693D01*
G01X-4725D02*
X-6693D01*
G01X-4725Y1544384D02*
X-6693D01*
G01X-4725D02*
X-6693D01*
G01X-2196Y1544108D02*
X-3150D01*
G01X-2196D02*
X-3150D01*
G01X-4258Y1543951D02*
X-4725D01*
G01X-4258D02*
X-4725D01*
G01X-6693Y1543793D02*
X-9843D01*
G01X-6693D02*
X-9843D01*
G01X-12992Y1543754D02*
X0D01*
G01Y1542652D02*
X-12992D01*
G01X-9843Y1542612D02*
X-6693D01*
G01X-9843D02*
X-6693D01*
G01X-4725Y1542455D02*
X-4258D01*
G01X-4725D02*
X-4258D01*
G01X-3150Y1542297D02*
X-2196D01*
G01X-3150D02*
X-2196D01*
G01X-4725Y1542022D02*
X-6693D01*
G01X-4725D02*
X-6693D01*
G01X-4725Y1540447D02*
X-6693D01*
G01X-4725D02*
X-6693D01*
G01X-2196Y1540171D02*
X-3150D01*
G01X-2196D02*
X-3150D01*
G01X-4258Y1540014D02*
X-4725D01*
G01X-4258D02*
X-4725D01*
G01X-6693Y1539856D02*
X-9843D01*
G01X-6693D02*
X-9843D01*
G01X-12992Y1539817D02*
X0D01*
G01X-6693Y1538675D02*
X-4725Y1538990D01*
G01X-6693Y1538675D02*
X-4725Y1538990D01*
G01X-6693Y1534738D02*
X-4725Y1535053D01*
G01X-6693Y1534738D02*
X-4725Y1535053D01*
G01X0Y1538715D02*
X-12992D01*
G01X-9843Y1538675D02*
X-6693D01*
G01X-9843D02*
X-6693D01*
G01X-4725Y1538518D02*
X-4258D01*
G01X-4725D02*
X-4258D01*
G01X-3150Y1538360D02*
X-2196D01*
G01X-3150D02*
X-2196D01*
G01X-4725Y1538085D02*
X-6693D01*
G01X-4725D02*
X-6693D01*
G01X-4725Y1536510D02*
X-6693D01*
G01X-4725D02*
X-6693D01*
G01X-2196Y1536234D02*
X-3150D01*
G01X-2196D02*
X-3150D01*
G01X-4258Y1536077D02*
X-4725D01*
G01X-4258D02*
X-4725D01*
G01X-6693Y1535919D02*
X-9843D01*
G01X-6693D02*
X-9843D01*
G01X-12992Y1535880D02*
X0D01*
G01Y1534778D02*
X-12992D01*
G01X-9843Y1534738D02*
X-6693D01*
G01X-9843D02*
X-6693D01*
G01X-4725Y1534581D02*
X-4258D01*
G01X-4725D02*
X-4258D01*
G01X-3150Y1534423D02*
X-2196D01*
G01X-3150D02*
X-2196D01*
G01X-4725Y1534148D02*
X-6693D01*
G01X-4725D02*
X-6693D01*
G01X-4258Y1551825D02*
X-3377Y1551589D01*
G01X-4258Y1551825D02*
X-3377Y1551589D01*
G01X-4258Y1547888D02*
X-3377Y1547652D01*
G01X-4258Y1547888D02*
X-3377Y1547652D01*
G01X-4258Y1543951D02*
X-3377Y1543715D01*
G01X-4258Y1543951D02*
X-3377Y1543715D01*
G01X-4725Y1551353D02*
X-6693Y1551667D01*
G01X-4725Y1551353D02*
X-6693Y1551667D01*
G01X-4725Y1547416D02*
X-6693Y1547730D01*
G01X-4725Y1547416D02*
X-6693Y1547730D01*
G01X-4725Y1543478D02*
X-6693Y1543793D01*
G01X-4725Y1543478D02*
X-6693Y1543793D01*
G01X-4725Y1539541D02*
X-6693Y1539856D01*
G01X-4725Y1539541D02*
X-6693Y1539856D01*
G01X-4725Y1535604D02*
X-6693Y1535919D01*
G01X-4725Y1535604D02*
X-6693Y1535919D01*
G01X-4258Y1540014D02*
X-3377Y1539778D01*
G01X-4258Y1540014D02*
X-3377Y1539778D01*
G01X-4258Y1536077D02*
X-3377Y1535841D01*
G01X-4258Y1536077D02*
X-3377Y1535841D01*
G01X-9843Y1551667D02*
X-10630Y1552022D01*
G01D02*
X-9843Y1551667D01*
G01Y1547730D02*
X-10630Y1548085D01*
G01D02*
X-9843Y1547730D01*
G01Y1543793D02*
X-10630Y1544148D01*
G01D02*
X-9843Y1543793D01*
G01Y1539856D02*
X-10630Y1540211D01*
G01D02*
X-9843Y1539856D01*
G01Y1535919D02*
X-10630Y1536274D01*
G01D02*
X-9843Y1535919D01*
G01X-3150Y1550171D02*
X-3377Y1550565D01*
G01X-3150Y1550171D02*
X-3377Y1550565D01*
G01X-3150Y1546234D02*
X-3377Y1546628D01*
G01X-3150Y1546234D02*
X-3377Y1546628D01*
G01X-3150Y1542297D02*
X-3377Y1542691D01*
G01X-3150Y1542297D02*
X-3377Y1542691D01*
G01X-3150Y1538360D02*
X-3377Y1538754D01*
G01X-3150Y1538360D02*
X-3377Y1538754D01*
G01X-3150Y1534423D02*
X-3377Y1534817D01*
G01X-3150Y1534423D02*
X-3377Y1534817D01*
G01X-3756Y1538400D02*
Y1536195D01*
G01Y1542337D02*
Y1540132D01*
G01Y1550211D02*
Y1548006D01*
G01Y1546274D02*
Y1544069D01*
G01Y1554148D02*
Y1551943D01*
G01X-4725Y1551353D02*
Y1552258D01*
G01Y1545959D02*
Y1546864D01*
G01Y1547416D02*
Y1548321D01*
G01Y1549896D02*
Y1550801D01*
G01Y1542022D02*
Y1542927D01*
G01Y1543478D02*
Y1544384D01*
G01Y1538085D02*
Y1538990D01*
G01Y1539541D02*
Y1540447D01*
G01Y1534148D02*
Y1535053D01*
G01Y1535604D02*
Y1536510D01*
G01D02*
Y1535604D01*
G01Y1535053D02*
Y1534148D01*
G01Y1540447D02*
Y1539541D01*
G01Y1538990D02*
Y1538085D01*
G01Y1544384D02*
Y1543478D01*
G01Y1542927D02*
Y1542022D01*
G01Y1548321D02*
Y1547416D01*
G01Y1550801D02*
Y1549896D01*
G01Y1546864D02*
Y1545959D01*
G01Y1552258D02*
Y1551353D01*
G01X-6693Y1536510D02*
Y1535919D01*
G01Y1534738D02*
Y1534148D01*
G01Y1534738D02*
Y1534148D01*
G01Y1536510D02*
Y1535919D01*
G01Y1540447D02*
Y1539856D01*
G01Y1538675D02*
Y1538085D01*
G01Y1538675D02*
Y1538085D01*
G01Y1540447D02*
Y1539856D01*
G01Y1544384D02*
Y1543793D01*
G01Y1542612D02*
Y1542022D01*
G01Y1542612D02*
Y1542022D01*
G01Y1544384D02*
Y1543793D01*
G01Y1548321D02*
Y1547730D01*
G01Y1550486D02*
Y1549896D01*
G01Y1546549D02*
Y1545959D01*
G01Y1546549D02*
Y1545959D01*
G01Y1548321D02*
Y1547730D01*
G01Y1550486D02*
Y1549896D01*
G01Y1552258D02*
Y1551667D01*
G01Y1552258D02*
Y1551667D01*
G01X-10530Y1538366D02*
Y1536229D01*
G01Y1538366D02*
Y1536229D01*
G01Y1542303D02*
Y1540166D01*
G01Y1542303D02*
Y1540166D01*
G01Y1550177D02*
Y1548040D01*
G01Y1546240D02*
Y1544103D01*
G01Y1550177D02*
Y1548040D01*
G01Y1546240D02*
Y1544103D01*
G01Y1554114D02*
Y1551977D01*
G01Y1554114D02*
Y1551977D01*
G01X-11842Y1552035D02*
Y1554056D01*
G01Y1548098D02*
Y1550119D01*
G01Y1544161D02*
Y1546182D01*
G01Y1540224D02*
Y1542245D01*
G01Y1536287D02*
Y1538308D01*
G01D02*
Y1536287D01*
G01Y1542245D02*
Y1540224D01*
G01Y1546182D02*
Y1544161D01*
G01Y1550119D02*
Y1548098D01*
G01Y1554056D02*
Y1552035D01*
G01X-12280Y1552040D02*
Y1554051D01*
G01Y1548103D02*
Y1550114D01*
G01Y1544166D02*
Y1546177D01*
G01Y1540229D02*
Y1542240D01*
G01Y1536292D02*
Y1538303D01*
G01D02*
Y1536292D01*
G01Y1542240D02*
Y1540229D01*
G01Y1550114D02*
Y1548103D01*
G01Y1546177D02*
Y1544166D01*
G01Y1554051D02*
Y1552040D01*
G01X-12992Y1534778D02*
Y1534463D01*
G01Y1536195D02*
Y1535880D01*
G01Y1538715D02*
Y1538400D01*
G01Y1540132D02*
Y1539817D01*
G01Y1542652D02*
Y1542337D01*
G01Y1544069D02*
Y1543754D01*
G01Y1546589D02*
Y1546274D01*
G01Y1550526D02*
Y1550211D01*
G01Y1548006D02*
Y1547691D01*
G01Y1551943D02*
Y1551628D01*
G01X-23684Y1552167D02*
Y1553924D01*
G01Y1548230D02*
Y1549987D01*
G01Y1540356D02*
Y1542113D01*
G01Y1544293D02*
Y1546050D01*
G01Y1536419D02*
Y1538176D01*
G01D02*
Y1536419D01*
G01Y1546050D02*
Y1544293D01*
G01Y1542113D02*
Y1540356D01*
G01Y1549987D02*
Y1548230D01*
G01Y1553924D02*
Y1552167D01*
G01X-10630Y1534384D02*
X-9843Y1534738D01*
G01D02*
X-10630Y1534384D01*
G01Y1538321D02*
X-9843Y1538675D01*
G01D02*
X-10630Y1538321D01*
G01Y1542258D02*
X-9843Y1542612D01*
G01D02*
X-10630Y1542258D01*
G01Y1546195D02*
X-9843Y1546549D01*
G01D02*
X-10630Y1546195D01*
G01Y1550132D02*
X-9843Y1550486D01*
G01D02*
X-10630Y1550132D01*
G01X-3377Y1535841D02*
X-3150Y1536234D01*
G01X-3377Y1535841D02*
X-3150Y1536234D01*
G01X-3377Y1539778D02*
X-3150Y1540171D01*
G01X-3377Y1539778D02*
X-3150Y1540171D01*
G01X-3377Y1543715D02*
X-3150Y1544108D01*
G01X-3377Y1543715D02*
X-3150Y1544108D01*
G01X-3377Y1547652D02*
X-3150Y1548045D01*
G01X-3377Y1547652D02*
X-3150Y1548045D01*
G01X-3377Y1551589D02*
X-3150Y1551982D01*
G01X-3377Y1551589D02*
X-3150Y1551982D01*
G01X-6693Y1574108D02*
X-4725Y1574423D01*
G01X-6693Y1574108D02*
X-4725Y1574423D01*
G01X-6693Y1570171D02*
X-4725Y1570486D01*
G01X-6693Y1570171D02*
X-4725Y1570486D01*
G01X-6693Y1566234D02*
X-4725Y1566549D01*
G01X-6693Y1566234D02*
X-4725Y1566549D01*
G01X-6693Y1562297D02*
X-4725Y1562612D01*
G01X-6693Y1562297D02*
X-4725Y1562612D01*
G01X-6693Y1558360D02*
X-4725Y1558675D01*
G01X-6693Y1558360D02*
X-4725Y1558675D01*
G01X-6693Y1554423D02*
X-4725Y1554738D01*
G01X-6693Y1554423D02*
X-4725Y1554738D01*
G01X-3377Y1574187D02*
X-4258Y1573951D01*
G01X-3377Y1574187D02*
X-4258Y1573951D01*
G01X-3377Y1570250D02*
X-4258Y1570014D01*
G01X-3377Y1570250D02*
X-4258Y1570014D01*
G01X-3377Y1566313D02*
X-4258Y1566077D01*
G01X-3377Y1566313D02*
X-4258Y1566077D01*
G01X-3377Y1562376D02*
X-4258Y1562140D01*
G01X-3377Y1562376D02*
X-4258Y1562140D01*
G01X-3377Y1558439D02*
X-4258Y1558203D01*
G01X-3377Y1558439D02*
X-4258Y1558203D01*
G01X-3377Y1554502D02*
X-4258Y1554266D01*
G01X-3377Y1554502D02*
X-4258Y1554266D01*
G01X0Y1574148D02*
X-12992D01*
G01X-9843Y1574108D02*
X-6693D01*
G01X-9843D02*
X-6693D01*
G01X-4725Y1573951D02*
X-4258D01*
G01X-4725D02*
X-4258D01*
G01X-3150Y1573793D02*
X-2196D01*
G01X-3150D02*
X-2196D01*
G01X-4725Y1573518D02*
X-6693D01*
G01X-4725D02*
X-6693D01*
G01X-4725Y1571943D02*
X-6693D01*
G01X-4725D02*
X-6693D01*
G01X-2196Y1571667D02*
X-3150D01*
G01X-2196D02*
X-3150D01*
G01X-4258Y1571510D02*
X-4725D01*
G01X-4258D02*
X-4725D01*
G01X-6693Y1571353D02*
X-9843D01*
G01X-6693D02*
X-9843D01*
G01X-12992Y1571313D02*
X0D01*
G01Y1570211D02*
X-12992D01*
G01X-9843Y1570171D02*
X-6693D01*
G01X-9843D02*
X-6693D01*
G01X-4725Y1570014D02*
X-4258D01*
G01X-4725D02*
X-4258D01*
G01X-3150Y1569856D02*
X-2196D01*
G01X-3150D02*
X-2196D01*
G01X-4725Y1569581D02*
X-6693D01*
G01X-4725D02*
X-6693D01*
G01X-4725Y1568006D02*
X-6693D01*
G01X-4725D02*
X-6693D01*
G01X-2196Y1567730D02*
X-3150D01*
G01X-2196D02*
X-3150D01*
G01X-4258Y1567573D02*
X-4725D01*
G01X-4258D02*
X-4725D01*
G01X-6693Y1567416D02*
X-9843D01*
G01X-6693D02*
X-9843D01*
G01X-12992Y1567376D02*
X0D01*
G01Y1566274D02*
X-12992D01*
G01X-9843Y1566234D02*
X-6693D01*
G01X-9843D02*
X-6693D01*
G01X-4725Y1566077D02*
X-4258D01*
G01X-4725D02*
X-4258D01*
G01X-3150Y1565919D02*
X-2196D01*
G01X-3150D02*
X-2196D01*
G01X-4725Y1565644D02*
X-6693D01*
G01X-4725D02*
X-6693D01*
G01X-4725Y1564069D02*
X-6693D01*
G01X-4725D02*
X-6693D01*
G01X-2196Y1563793D02*
X-3150D01*
G01X-2196D02*
X-3150D01*
G01X-4258Y1563636D02*
X-4725D01*
G01X-4258D02*
X-4725D01*
G01X-6693Y1563478D02*
X-9843D01*
G01X-6693D02*
X-9843D01*
G01X-12992Y1563439D02*
X0D01*
G01Y1562337D02*
X-12992D01*
G01X-9843Y1562297D02*
X-6693D01*
G01X-9843D02*
X-6693D01*
G01X-4725Y1562140D02*
X-4258D01*
G01X-4725D02*
X-4258D01*
G01X-3150Y1561982D02*
X-2196D01*
G01X-3150D02*
X-2196D01*
G01X-4725Y1561707D02*
X-6693D01*
G01X-4725D02*
X-6693D01*
G01X-4725Y1560132D02*
X-6693D01*
G01X-4725D02*
X-6693D01*
G01X-2196Y1559856D02*
X-3150D01*
G01X-2196D02*
X-3150D01*
G01X-4258Y1559699D02*
X-4725D01*
G01X-4258D02*
X-4725D01*
G01X-6693Y1559541D02*
X-9843D01*
G01X-6693D02*
X-9843D01*
G01X-12992Y1559502D02*
X0D01*
G01Y1558400D02*
X-12992D01*
G01X-9843Y1558360D02*
X-6693D01*
G01X-9843D02*
X-6693D01*
G01X-4725Y1558203D02*
X-4258D01*
G01X-4725D02*
X-4258D01*
G01X-3150Y1558045D02*
X-2196D01*
G01X-3150D02*
X-2196D01*
G01X-4725Y1557770D02*
X-6693D01*
G01X-4725D02*
X-6693D01*
G01X-4725Y1556195D02*
X-6693D01*
G01X-4725D02*
X-6693D01*
G01X-2196Y1555919D02*
X-3150D01*
G01X-2196D02*
X-3150D01*
G01X-4258Y1555762D02*
X-4725D01*
G01X-4258D02*
X-4725D01*
G01X-6693Y1555604D02*
X-9843D01*
G01X-6693D02*
X-9843D01*
G01X-12992Y1555565D02*
X0D01*
G01Y1554463D02*
X-12992D01*
G01X-9843Y1554423D02*
X-6693D01*
G01X-9843D02*
X-6693D01*
G01X-4725Y1554266D02*
X-4258D01*
G01X-4725D02*
X-4258D01*
G01X-3150Y1554108D02*
X-2196D01*
G01X-3150D02*
X-2196D01*
G01X-4725Y1553833D02*
X-6693D01*
G01X-4725D02*
X-6693D01*
G01X-4725Y1571038D02*
X-6693Y1571353D01*
G01X-4725Y1571038D02*
X-6693Y1571353D01*
G01X-4725Y1567101D02*
X-6693Y1567416D01*
G01X-4725Y1567101D02*
X-6693Y1567416D01*
G01X-4725Y1563164D02*
X-6693Y1563478D01*
G01X-4725Y1563164D02*
X-6693Y1563478D01*
G01X-4725Y1559227D02*
X-6693Y1559541D01*
G01X-4725Y1559227D02*
X-6693Y1559541D01*
G01X-4725Y1555290D02*
X-6693Y1555604D01*
G01X-4725Y1555290D02*
X-6693Y1555604D01*
G01X-4258Y1571510D02*
X-3377Y1571274D01*
G01X-4258Y1571510D02*
X-3377Y1571274D01*
G01X-4258Y1567573D02*
X-3377Y1567337D01*
G01X-4258Y1567573D02*
X-3377Y1567337D01*
G01X-4258Y1563636D02*
X-3377Y1563400D01*
G01X-4258Y1563636D02*
X-3377Y1563400D01*
G01X-4258Y1559699D02*
X-3377Y1559463D01*
G01X-4258Y1559699D02*
X-3377Y1559463D01*
G01X-4258Y1555762D02*
X-3377Y1555526D01*
G01X-4258Y1555762D02*
X-3377Y1555526D01*
G01X-9843Y1571353D02*
X-10630Y1571707D01*
G01D02*
X-9843Y1571353D01*
G01Y1567416D02*
X-10630Y1567770D01*
G01D02*
X-9843Y1567416D01*
G01Y1563478D02*
X-10630Y1563833D01*
G01D02*
X-9843Y1563478D01*
G01Y1559541D02*
X-10630Y1559896D01*
G01D02*
X-9843Y1559541D01*
G01Y1555604D02*
X-10630Y1555959D01*
G01D02*
X-9843Y1555604D01*
G01X-3150Y1573793D02*
X-3377Y1574187D01*
G01X-3150Y1573793D02*
X-3377Y1574187D01*
G01X-3150Y1569856D02*
X-3377Y1570250D01*
G01X-3150Y1569856D02*
X-3377Y1570250D01*
G01X-3150Y1565919D02*
X-3377Y1566313D01*
G01X-3150Y1565919D02*
X-3377Y1566313D01*
G01X-3150Y1561982D02*
X-3377Y1562376D01*
G01X-3150Y1561982D02*
X-3377Y1562376D01*
G01X-3150Y1558045D02*
X-3377Y1558439D01*
G01X-3150Y1558045D02*
X-3377Y1558439D01*
G01X-3150Y1554108D02*
X-3377Y1554502D01*
G01X-3150Y1554108D02*
X-3377Y1554502D01*
G01X-3756Y1558085D02*
Y1555880D01*
G01Y1562022D02*
Y1559817D01*
G01Y1565959D02*
Y1563754D01*
G01Y1573833D02*
Y1571628D01*
G01Y1569896D02*
Y1567691D01*
G01X-4725Y1573518D02*
Y1574423D01*
G01Y1569581D02*
Y1570486D01*
G01Y1571038D02*
Y1571943D01*
G01Y1565644D02*
Y1566549D01*
G01Y1567101D02*
Y1568006D01*
G01Y1561707D02*
Y1562612D01*
G01Y1563164D02*
Y1564069D01*
G01Y1555290D02*
Y1556195D01*
G01Y1557770D02*
Y1558675D01*
G01Y1559227D02*
Y1560132D01*
G01Y1553833D02*
Y1554738D01*
G01D02*
Y1553833D01*
G01Y1560132D02*
Y1559227D01*
G01Y1556195D02*
Y1555290D01*
G01Y1558675D02*
Y1557770D01*
G01Y1562612D02*
Y1561707D01*
G01Y1564069D02*
Y1563164D01*
G01Y1566549D02*
Y1565644D01*
G01Y1568006D02*
Y1567101D01*
G01Y1571943D02*
Y1571038D01*
G01Y1570486D02*
Y1569581D01*
G01Y1574423D02*
Y1573518D01*
G01X-6693Y1554423D02*
Y1553833D01*
G01Y1554423D02*
Y1553833D01*
G01Y1560132D02*
Y1559541D01*
G01Y1556195D02*
Y1555604D01*
G01Y1558360D02*
Y1557770D01*
G01Y1556195D02*
Y1555604D01*
G01Y1558360D02*
Y1557770D01*
G01Y1560132D02*
Y1559541D01*
G01Y1562297D02*
Y1561707D01*
G01Y1564069D02*
Y1563478D01*
G01Y1562297D02*
Y1561707D01*
G01Y1564069D02*
Y1563478D01*
G01Y1566234D02*
Y1565644D01*
G01Y1568006D02*
Y1567416D01*
G01Y1566234D02*
Y1565644D01*
G01Y1568006D02*
Y1567416D01*
G01Y1571943D02*
Y1571353D01*
G01Y1574108D02*
Y1573518D01*
G01Y1570171D02*
Y1569581D01*
G01Y1570171D02*
Y1569581D01*
G01Y1571943D02*
Y1571353D01*
G01Y1574108D02*
Y1573518D01*
G01X-10530Y1558051D02*
Y1555914D01*
G01Y1558051D02*
Y1555914D01*
G01Y1561988D02*
Y1559851D01*
G01Y1561988D02*
Y1559851D01*
G01Y1565925D02*
Y1563788D01*
G01Y1565925D02*
Y1563788D01*
G01Y1573799D02*
Y1571662D01*
G01Y1569862D02*
Y1567725D01*
G01Y1573799D02*
Y1571662D01*
G01Y1569862D02*
Y1567725D01*
G01X-11842Y1571720D02*
Y1573741D01*
G01Y1567783D02*
Y1569804D01*
G01Y1563846D02*
Y1565867D01*
G01Y1559909D02*
Y1561930D01*
G01Y1555972D02*
Y1557993D01*
G01D02*
Y1555972D01*
G01Y1561930D02*
Y1559909D01*
G01Y1565867D02*
Y1563846D01*
G01Y1569804D02*
Y1567783D01*
G01Y1573741D02*
Y1571720D01*
G01X-12280Y1571725D02*
Y1573736D01*
G01Y1567788D02*
Y1569799D01*
G01Y1563851D02*
Y1565862D01*
G01Y1559914D02*
Y1561925D01*
G01Y1555977D02*
Y1557988D01*
G01D02*
Y1555977D01*
G01Y1561925D02*
Y1559914D01*
G01Y1565862D02*
Y1563851D01*
G01Y1573736D02*
Y1571725D01*
G01Y1569799D02*
Y1567788D01*
G01X-12992Y1554463D02*
Y1554148D01*
G01Y1558400D02*
Y1558085D01*
G01Y1555880D02*
Y1555565D01*
G01Y1559817D02*
Y1559502D01*
G01Y1562337D02*
Y1562022D01*
G01Y1563754D02*
Y1563439D01*
G01Y1566274D02*
Y1565959D01*
G01Y1567691D02*
Y1567376D01*
G01Y1570211D02*
Y1569896D01*
G01Y1574148D02*
Y1573833D01*
G01Y1571628D02*
Y1571313D01*
G01X-23684Y1567916D02*
Y1569672D01*
G01Y1571853D02*
Y1573609D01*
G01Y1563978D02*
Y1565735D01*
G01Y1560041D02*
Y1561798D01*
G01Y1556104D02*
Y1557861D01*
G01D02*
Y1556104D01*
G01Y1561798D02*
Y1560041D01*
G01Y1565735D02*
Y1563978D01*
G01Y1573609D02*
Y1571853D01*
G01Y1569672D02*
Y1567916D01*
G01X-10630Y1554069D02*
X-9843Y1554423D01*
G01D02*
X-10630Y1554069D01*
G01Y1558006D02*
X-9843Y1558360D01*
G01D02*
X-10630Y1558006D01*
G01Y1561943D02*
X-9843Y1562297D01*
G01D02*
X-10630Y1561943D01*
G01Y1565880D02*
X-9843Y1566234D01*
G01D02*
X-10630Y1565880D01*
G01Y1569817D02*
X-9843Y1570171D01*
G01D02*
X-10630Y1569817D01*
G01Y1573754D02*
X-9843Y1574108D01*
G01D02*
X-10630Y1573754D01*
G01X-3377Y1555526D02*
X-3150Y1555919D01*
G01X-3377Y1555526D02*
X-3150Y1555919D01*
G01X-3377Y1559463D02*
X-3150Y1559856D01*
G01X-3377Y1559463D02*
X-3150Y1559856D01*
G01X-3377Y1563400D02*
X-3150Y1563793D01*
G01X-3377Y1563400D02*
X-3150Y1563793D01*
G01X-3377Y1567337D02*
X-3150Y1567730D01*
G01X-3377Y1567337D02*
X-3150Y1567730D01*
G01X-3377Y1571274D02*
X-3150Y1571667D01*
G01X-3377Y1571274D02*
X-3150Y1571667D01*
G01X-3377Y1593872D02*
X-4258Y1593636D01*
G01X-3377Y1593872D02*
X-4258Y1593636D01*
G01X-3377Y1589935D02*
X-4258Y1589699D01*
G01X-3377Y1589935D02*
X-4258Y1589699D01*
G01X-3377Y1585998D02*
X-4258Y1585762D01*
G01X-3377Y1585998D02*
X-4258Y1585762D01*
G01X-3377Y1582061D02*
X-4258Y1581825D01*
G01X-3377Y1582061D02*
X-4258Y1581825D01*
G01X-3377Y1578124D02*
X-4258Y1577888D01*
G01X-3377Y1578124D02*
X-4258Y1577888D01*
G01X-6693Y1593793D02*
X-4725Y1594108D01*
G01X-6693Y1593793D02*
X-4725Y1594108D01*
G01X-6693Y1589856D02*
X-4725Y1590171D01*
G01X-6693Y1589856D02*
X-4725Y1590171D01*
G01X-6693Y1585919D02*
X-4725Y1586234D01*
G01X-6693Y1585919D02*
X-4725Y1586234D01*
G01X-6693Y1581982D02*
X-4725Y1582297D01*
G01X-6693Y1581982D02*
X-4725Y1582297D01*
G01X-6693Y1578045D02*
X-4725Y1578360D01*
G01X-6693Y1578045D02*
X-4725Y1578360D01*
G01Y1595565D02*
X-6693D01*
G01X-4725D02*
X-6693D01*
G01X-2196Y1595290D02*
X-3150D01*
G01X-2196D02*
X-3150D01*
G01X-4258Y1595132D02*
X-4725D01*
G01X-4258D02*
X-4725D01*
G01X-6693Y1594975D02*
X-9843D01*
G01X-6693D02*
X-9843D01*
G01X-12992Y1594935D02*
X0D01*
G01Y1593833D02*
X-12992D01*
G01X-9843Y1593793D02*
X-6693D01*
G01X-9843D02*
X-6693D01*
G01X-4725Y1593636D02*
X-4258D01*
G01X-4725D02*
X-4258D01*
G01X-3150Y1593478D02*
X-2196D01*
G01X-3150D02*
X-2196D01*
G01X-4725Y1593203D02*
X-6693D01*
G01X-4725D02*
X-6693D01*
G01X-4725Y1591628D02*
X-6693D01*
G01X-4725D02*
X-6693D01*
G01X-2196Y1591353D02*
X-3150D01*
G01X-2196D02*
X-3150D01*
G01X-4258Y1591195D02*
X-4725D01*
G01X-4258D02*
X-4725D01*
G01X-6693Y1591038D02*
X-9843D01*
G01X-6693D02*
X-9843D01*
G01X-12992Y1590998D02*
X0D01*
G01Y1589896D02*
X-12992D01*
G01X-9843Y1589856D02*
X-6693D01*
G01X-9843D02*
X-6693D01*
G01X-4725Y1589699D02*
X-4258D01*
G01X-4725D02*
X-4258D01*
G01X-3150Y1589541D02*
X-2196D01*
G01X-3150D02*
X-2196D01*
G01X-4725Y1589266D02*
X-6693D01*
G01X-4725D02*
X-6693D01*
G01X-4725Y1587691D02*
X-6693D01*
G01X-4725D02*
X-6693D01*
G01X-2196Y1587416D02*
X-3150D01*
G01X-2196D02*
X-3150D01*
G01X-4258Y1587258D02*
X-4725D01*
G01X-4258D02*
X-4725D01*
G01X-6693Y1587101D02*
X-9843D01*
G01X-6693D02*
X-9843D01*
G01X-12992Y1587061D02*
X0D01*
G01Y1585959D02*
X-12992D01*
G01X-9843Y1585919D02*
X-6693D01*
G01X-9843D02*
X-6693D01*
G01X-4725Y1585762D02*
X-4258D01*
G01X-4725D02*
X-4258D01*
G01X-3150Y1585604D02*
X-2196D01*
G01X-3150D02*
X-2196D01*
G01X-4725Y1585329D02*
X-6693D01*
G01X-4725D02*
X-6693D01*
G01X-4725Y1583754D02*
X-6693D01*
G01X-4725D02*
X-6693D01*
G01X-2196Y1583478D02*
X-3150D01*
G01X-2196D02*
X-3150D01*
G01X-4258Y1583321D02*
X-4725D01*
G01X-4258D02*
X-4725D01*
G01X-6693Y1583164D02*
X-9843D01*
G01X-6693D02*
X-9843D01*
G01X-12992Y1583124D02*
X0D01*
G01Y1582022D02*
X-12992D01*
G01X-9843Y1581982D02*
X-6693D01*
G01X-9843D02*
X-6693D01*
G01X-4725Y1581825D02*
X-4258D01*
G01X-4725D02*
X-4258D01*
G01X-3150Y1581667D02*
X-2196D01*
G01X-3150D02*
X-2196D01*
G01X-4725Y1581392D02*
X-6693D01*
G01X-4725D02*
X-6693D01*
G01X-4725Y1579817D02*
X-6693D01*
G01X-4725D02*
X-6693D01*
G01X-2196Y1579541D02*
X-3150D01*
G01X-2196D02*
X-3150D01*
G01X-4258Y1579384D02*
X-4725D01*
G01X-4258D02*
X-4725D01*
G01X-6693Y1579227D02*
X-9843D01*
G01X-6693D02*
X-9843D01*
G01X-12992Y1579187D02*
X0D01*
G01Y1578085D02*
X-12992D01*
G01X-9843Y1578045D02*
X-6693D01*
G01X-9843D02*
X-6693D01*
G01X-4725Y1577888D02*
X-4258D01*
G01X-4725D02*
X-4258D01*
G01X-3150Y1577730D02*
X-2196D01*
G01X-3150D02*
X-2196D01*
G01X-4725Y1577455D02*
X-6693D01*
G01X-4725D02*
X-6693D01*
G01X-4725Y1575880D02*
X-6693D01*
G01X-4725D02*
X-6693D01*
G01X-2196Y1575604D02*
X-3150D01*
G01X-2196D02*
X-3150D01*
G01X-4258Y1575447D02*
X-4725D01*
G01X-4258D02*
X-4725D01*
G01X-6693Y1575290D02*
X-9843D01*
G01X-6693D02*
X-9843D01*
G01X-12992Y1575250D02*
X0D01*
G01X-4725Y1594660D02*
X-6693Y1594975D01*
G01X-4725Y1594660D02*
X-6693Y1594975D01*
G01X-4725Y1590723D02*
X-6693Y1591038D01*
G01X-4725Y1590723D02*
X-6693Y1591038D01*
G01X-4725Y1586786D02*
X-6693Y1587101D01*
G01X-4725Y1586786D02*
X-6693Y1587101D01*
G01X-4725Y1582849D02*
X-6693Y1583164D01*
G01X-4725Y1582849D02*
X-6693Y1583164D01*
G01X-4725Y1578912D02*
X-6693Y1579227D01*
G01X-4725Y1578912D02*
X-6693Y1579227D01*
G01X-4725Y1574975D02*
X-6693Y1575290D01*
G01X-4725Y1574975D02*
X-6693Y1575290D01*
G01X-4258Y1595132D02*
X-3377Y1594896D01*
G01X-4258Y1595132D02*
X-3377Y1594896D01*
G01X-4258Y1591195D02*
X-3377Y1590959D01*
G01X-4258Y1591195D02*
X-3377Y1590959D01*
G01X-4258Y1587258D02*
X-3377Y1587022D01*
G01X-4258Y1587258D02*
X-3377Y1587022D01*
G01X-4258Y1583321D02*
X-3377Y1583085D01*
G01X-4258Y1583321D02*
X-3377Y1583085D01*
G01X-4258Y1579384D02*
X-3377Y1579148D01*
G01X-4258Y1579384D02*
X-3377Y1579148D01*
G01X-4258Y1575447D02*
X-3377Y1575211D01*
G01X-4258Y1575447D02*
X-3377Y1575211D01*
G01X-9843Y1594975D02*
X-10630Y1595329D01*
G01D02*
X-9843Y1594975D01*
G01Y1591038D02*
X-10630Y1591392D01*
G01D02*
X-9843Y1591038D01*
G01Y1587101D02*
X-10630Y1587455D01*
G01D02*
X-9843Y1587101D01*
G01Y1583164D02*
X-10630Y1583518D01*
G01D02*
X-9843Y1583164D01*
G01Y1579227D02*
X-10630Y1579581D01*
G01D02*
X-9843Y1579227D01*
G01Y1575290D02*
X-10630Y1575644D01*
G01D02*
X-9843Y1575290D01*
G01X-3150Y1593478D02*
X-3377Y1593872D01*
G01X-3150Y1593478D02*
X-3377Y1593872D01*
G01X-3150Y1589541D02*
X-3377Y1589935D01*
G01X-3150Y1589541D02*
X-3377Y1589935D01*
G01X-3150Y1585604D02*
X-3377Y1585998D01*
G01X-3150Y1585604D02*
X-3377Y1585998D01*
G01X-3150Y1581667D02*
X-3377Y1582061D01*
G01X-3150Y1581667D02*
X-3377Y1582061D01*
G01X-3150Y1577730D02*
X-3377Y1578124D01*
G01X-3150Y1577730D02*
X-3377Y1578124D01*
G01X-3756Y1577770D02*
Y1575565D01*
G01Y1581707D02*
Y1579502D01*
G01Y1585644D02*
Y1583439D01*
G01Y1589581D02*
Y1587376D01*
G01Y1597455D02*
Y1595250D01*
G01Y1593518D02*
Y1591313D01*
G01X-4725Y1594660D02*
Y1595565D01*
G01Y1593203D02*
Y1594108D01*
G01Y1589266D02*
Y1590171D01*
G01Y1590723D02*
Y1591628D01*
G01Y1582849D02*
Y1583754D01*
G01Y1585329D02*
Y1586234D01*
G01Y1586786D02*
Y1587691D01*
G01Y1578912D02*
Y1579817D01*
G01Y1581392D02*
Y1582297D01*
G01Y1574975D02*
Y1575880D01*
G01Y1577455D02*
Y1578360D01*
G01Y1575880D02*
Y1574975D01*
G01Y1578360D02*
Y1577455D01*
G01Y1583754D02*
Y1582849D01*
G01Y1579817D02*
Y1578912D01*
G01Y1582297D02*
Y1581392D01*
G01Y1587691D02*
Y1586786D01*
G01Y1586234D02*
Y1585329D01*
G01Y1591628D02*
Y1590723D01*
G01Y1590171D02*
Y1589266D01*
G01Y1595565D02*
Y1594660D01*
G01Y1594108D02*
Y1593203D01*
G01X-6693Y1575880D02*
Y1575290D01*
G01Y1578045D02*
Y1577455D01*
G01Y1575880D02*
Y1575290D01*
G01Y1578045D02*
Y1577455D01*
G01Y1579817D02*
Y1579227D01*
G01Y1581982D02*
Y1581392D01*
G01Y1579817D02*
Y1579227D01*
G01Y1581982D02*
Y1581392D01*
G01Y1587691D02*
Y1587101D01*
G01Y1583754D02*
Y1583164D01*
G01Y1585919D02*
Y1585329D01*
G01Y1583754D02*
Y1583164D01*
G01Y1585919D02*
Y1585329D01*
G01Y1587691D02*
Y1587101D01*
G01Y1591628D02*
Y1591038D01*
G01Y1589856D02*
Y1589266D01*
G01Y1589856D02*
Y1589266D01*
G01Y1591628D02*
Y1591038D01*
G01Y1595565D02*
Y1594975D01*
G01Y1593793D02*
Y1593203D01*
G01Y1595565D02*
Y1594975D01*
G01Y1593793D02*
Y1593203D01*
G01X-10530Y1577736D02*
Y1575599D01*
G01Y1577736D02*
Y1575599D01*
G01Y1581673D02*
Y1579536D01*
G01Y1581673D02*
Y1579536D01*
G01Y1585610D02*
Y1583473D01*
G01Y1585610D02*
Y1583473D01*
G01Y1589547D02*
Y1587410D01*
G01Y1589547D02*
Y1587410D01*
G01Y1597421D02*
Y1595284D01*
G01Y1593484D02*
Y1591347D01*
G01Y1597421D02*
Y1595284D01*
G01Y1593484D02*
Y1591347D01*
G01X-11842Y1595342D02*
Y1597363D01*
G01Y1591405D02*
Y1593426D01*
G01Y1587468D02*
Y1589489D01*
G01Y1583531D02*
Y1585552D01*
G01Y1579594D02*
Y1581615D01*
G01Y1575657D02*
Y1577678D01*
G01D02*
Y1575657D01*
G01Y1581615D02*
Y1579594D01*
G01Y1585552D02*
Y1583531D01*
G01Y1589489D02*
Y1587468D01*
G01Y1597363D02*
Y1595342D01*
G01Y1593426D02*
Y1591405D01*
G01X-12280Y1595347D02*
Y1597358D01*
G01Y1591410D02*
Y1593421D01*
G01Y1587473D02*
Y1589484D01*
G01Y1583536D02*
Y1585547D01*
G01Y1579599D02*
Y1581610D01*
G01Y1575662D02*
Y1577673D01*
G01D02*
Y1575662D01*
G01Y1581610D02*
Y1579599D01*
G01Y1585547D02*
Y1583536D01*
G01Y1589484D02*
Y1587473D01*
G01Y1597358D02*
Y1595347D01*
G01Y1593421D02*
Y1591410D01*
G01X-12992Y1578085D02*
Y1577770D01*
G01Y1575565D02*
Y1575250D01*
G01Y1582022D02*
Y1581707D01*
G01Y1579502D02*
Y1579187D01*
G01Y1583439D02*
Y1583124D01*
G01Y1585959D02*
Y1585644D01*
G01Y1587376D02*
Y1587061D01*
G01Y1589896D02*
Y1589581D01*
G01Y1591313D02*
Y1590998D01*
G01Y1593833D02*
Y1593518D01*
G01Y1595250D02*
Y1594935D01*
G01X-23684Y1595475D02*
Y1597231D01*
G01Y1591538D02*
Y1593294D01*
G01Y1587601D02*
Y1589357D01*
G01Y1583664D02*
Y1585420D01*
G01Y1579727D02*
Y1581483D01*
G01Y1575790D02*
Y1577546D01*
G01D02*
Y1575790D01*
G01Y1581483D02*
Y1579727D01*
G01Y1585420D02*
Y1583664D01*
G01Y1589357D02*
Y1587601D01*
G01Y1597231D02*
Y1595475D01*
G01Y1593294D02*
Y1591538D01*
G01X-10630Y1577691D02*
X-9843Y1578045D01*
G01D02*
X-10630Y1577691D01*
G01X-3377Y1575211D02*
X-3150Y1575604D01*
G01X-3377Y1575211D02*
X-3150Y1575604D01*
G01X-3377Y1579148D02*
X-3150Y1579541D01*
G01X-3377Y1579148D02*
X-3150Y1579541D01*
G01X-3377Y1583085D02*
X-3150Y1583478D01*
G01X-3377Y1583085D02*
X-3150Y1583478D01*
G01X-3377Y1587022D02*
X-3150Y1587416D01*
G01X-3377Y1587022D02*
X-3150Y1587416D01*
G01X-3377Y1590959D02*
X-3150Y1591353D01*
G01X-3377Y1590959D02*
X-3150Y1591353D01*
G01X-10630Y1581628D02*
X-9843Y1581982D01*
G01D02*
X-10630Y1581628D01*
G01Y1585565D02*
X-9843Y1585919D01*
G01D02*
X-10630Y1585565D01*
G01Y1589502D02*
X-9843Y1589856D01*
G01D02*
X-10630Y1589502D01*
G01Y1593439D02*
X-9843Y1593793D01*
G01D02*
X-10630Y1593439D01*
G01X-3377Y1594896D02*
X-3150Y1595290D01*
G01X-3377Y1594896D02*
X-3150Y1595290D01*
G01X-3377Y1617494D02*
X-4258Y1617258D01*
G01X-3377Y1617494D02*
X-4258Y1617258D01*
G01X-3377Y1613557D02*
X-4258Y1613321D01*
G01X-3377Y1613557D02*
X-4258Y1613321D01*
G01X-3377Y1609620D02*
X-4258Y1609384D01*
G01X-3377Y1609620D02*
X-4258Y1609384D01*
G01X-3377Y1605683D02*
X-4258Y1605447D01*
G01X-3377Y1605683D02*
X-4258Y1605447D01*
G01X-3377Y1601746D02*
X-4258Y1601510D01*
G01X-3377Y1601746D02*
X-4258Y1601510D01*
G01X-3377Y1597809D02*
X-4258Y1597573D01*
G01X-3377Y1597809D02*
X-4258Y1597573D01*
G01X-4725Y1617258D02*
X-4258D01*
G01X-4725D02*
X-4258D01*
G01X-3150Y1617101D02*
X-2196D01*
G01X-3150D02*
X-2196D01*
G01X-4725Y1616825D02*
X-6693D01*
G01X-4725D02*
X-6693D01*
G01Y1613478D02*
X-4725Y1613793D01*
G01X-6693Y1613478D02*
X-4725Y1613793D01*
G01X-6693Y1609541D02*
X-4725Y1609856D01*
G01X-6693Y1609541D02*
X-4725Y1609856D01*
G01X-6693Y1605604D02*
X-4725Y1605919D01*
G01X-6693Y1605604D02*
X-4725Y1605919D01*
G01X-6693Y1601667D02*
X-4725Y1601982D01*
G01X-6693Y1601667D02*
X-4725Y1601982D01*
G01X-6693Y1597730D02*
X-4725Y1598045D01*
G01X-6693Y1597730D02*
X-4725Y1598045D01*
G01Y1615250D02*
X-6693D01*
G01X-4725D02*
X-6693D01*
G01X-2196Y1614975D02*
X-3150D01*
G01X-2196D02*
X-3150D01*
G01X-4258Y1614817D02*
X-4725D01*
G01X-4258D02*
X-4725D01*
G01X-6693Y1614660D02*
X-9843D01*
G01X-6693D02*
X-9843D01*
G01X-12992Y1614620D02*
X0D01*
G01Y1613518D02*
X-12992D01*
G01X-9843Y1613478D02*
X-6693D01*
G01X-9843D02*
X-6693D01*
G01X-4725Y1613321D02*
X-4258D01*
G01X-4725D02*
X-4258D01*
G01X-3150Y1613164D02*
X-2196D01*
G01X-3150D02*
X-2196D01*
G01X-4725Y1612888D02*
X-6693D01*
G01X-4725D02*
X-6693D01*
G01X-4725Y1611313D02*
X-6693D01*
G01X-4725D02*
X-6693D01*
G01X-2196Y1611038D02*
X-3150D01*
G01X-2196D02*
X-3150D01*
G01X-4258Y1610880D02*
X-4725D01*
G01X-4258D02*
X-4725D01*
G01X-6693Y1610723D02*
X-9843D01*
G01X-6693D02*
X-9843D01*
G01X-12992Y1610683D02*
X0D01*
G01Y1609581D02*
X-12992D01*
G01X-9843Y1609541D02*
X-6693D01*
G01X-9843D02*
X-6693D01*
G01X-4725Y1609384D02*
X-4258D01*
G01X-4725D02*
X-4258D01*
G01X-3150Y1609227D02*
X-2196D01*
G01X-3150D02*
X-2196D01*
G01X-4725Y1608951D02*
X-6693D01*
G01X-4725D02*
X-6693D01*
G01X-4725Y1607376D02*
X-6693D01*
G01X-4725D02*
X-6693D01*
G01X-2196Y1607101D02*
X-3150D01*
G01X-2196D02*
X-3150D01*
G01X-4258Y1606943D02*
X-4725D01*
G01X-4258D02*
X-4725D01*
G01X-6693Y1606786D02*
X-9843D01*
G01X-6693D02*
X-9843D01*
G01X-12992Y1606746D02*
X0D01*
G01Y1605644D02*
X-12992D01*
G01X-9843Y1605604D02*
X-6693D01*
G01X-9843D02*
X-6693D01*
G01X-4725Y1605447D02*
X-4258D01*
G01X-4725D02*
X-4258D01*
G01X-3150Y1605290D02*
X-2196D01*
G01X-3150D02*
X-2196D01*
G01X-4725Y1605014D02*
X-6693D01*
G01X-4725D02*
X-6693D01*
G01X-4725Y1603439D02*
X-6693D01*
G01X-4725D02*
X-6693D01*
G01X-2196Y1603164D02*
X-3150D01*
G01X-2196D02*
X-3150D01*
G01X-4258Y1603006D02*
X-4725D01*
G01X-4258D02*
X-4725D01*
G01X-6693Y1602849D02*
X-9843D01*
G01X-6693D02*
X-9843D01*
G01X-12992Y1602809D02*
X0D01*
G01Y1601707D02*
X-12992D01*
G01X-9843Y1601667D02*
X-6693D01*
G01X-9843D02*
X-6693D01*
G01X-4725Y1601510D02*
X-4258D01*
G01X-4725D02*
X-4258D01*
G01X-3150Y1601353D02*
X-2196D01*
G01X-3150D02*
X-2196D01*
G01X-4725Y1601077D02*
X-6693D01*
G01X-4725D02*
X-6693D01*
G01X-4725Y1599502D02*
X-6693D01*
G01X-4725D02*
X-6693D01*
G01X-2196Y1599227D02*
X-3150D01*
G01X-2196D02*
X-3150D01*
G01X-4258Y1599069D02*
X-4725D01*
G01X-4258D02*
X-4725D01*
G01X-6693Y1598912D02*
X-9843D01*
G01X-6693D02*
X-9843D01*
G01X-12992Y1598872D02*
X0D01*
G01Y1597770D02*
X-12992D01*
G01X-9843Y1597730D02*
X-6693D01*
G01X-9843D02*
X-6693D01*
G01X-4725Y1597573D02*
X-4258D01*
G01X-4725D02*
X-4258D01*
G01X-3150Y1597416D02*
X-2196D01*
G01X-3150D02*
X-2196D01*
G01X-4725Y1597140D02*
X-6693D01*
G01X-4725D02*
X-6693D01*
G01X-4725Y1614345D02*
X-6693Y1614660D01*
G01X-4725Y1614345D02*
X-6693Y1614660D01*
G01X-4725Y1610408D02*
X-6693Y1610723D01*
G01X-4725Y1610408D02*
X-6693Y1610723D01*
G01X-4725Y1606471D02*
X-6693Y1606786D01*
G01X-4725Y1606471D02*
X-6693Y1606786D01*
G01X-4725Y1602534D02*
X-6693Y1602849D01*
G01X-4725Y1602534D02*
X-6693Y1602849D01*
G01X-4725Y1598597D02*
X-6693Y1598912D01*
G01X-4725Y1598597D02*
X-6693Y1598912D01*
G01X-4258Y1614817D02*
X-3377Y1614581D01*
G01X-4258Y1614817D02*
X-3377Y1614581D01*
G01X-4258Y1610880D02*
X-3377Y1610644D01*
G01X-4258Y1610880D02*
X-3377Y1610644D01*
G01X-4258Y1606943D02*
X-3377Y1606707D01*
G01X-4258Y1606943D02*
X-3377Y1606707D01*
G01X-4258Y1603006D02*
X-3377Y1602770D01*
G01X-4258Y1603006D02*
X-3377Y1602770D01*
G01X-4258Y1599069D02*
X-3377Y1598833D01*
G01X-4258Y1599069D02*
X-3377Y1598833D01*
G01X-9843Y1614660D02*
X-10630Y1615014D01*
G01D02*
X-9843Y1614660D01*
G01Y1610723D02*
X-10630Y1611077D01*
G01D02*
X-9843Y1610723D01*
G01Y1606786D02*
X-10630Y1607140D01*
G01D02*
X-9843Y1606786D01*
G01Y1602849D02*
X-10630Y1603203D01*
G01D02*
X-9843Y1602849D01*
G01Y1598912D02*
X-10630Y1599266D01*
G01D02*
X-9843Y1598912D01*
G01X-3150Y1617101D02*
X-3377Y1617494D01*
G01X-3150Y1617101D02*
X-3377Y1617494D01*
G01X-3150Y1613164D02*
X-3377Y1613557D01*
G01X-3150Y1613164D02*
X-3377Y1613557D01*
G01X-3150Y1609227D02*
X-3377Y1609620D01*
G01X-3150Y1609227D02*
X-3377Y1609620D01*
G01X-3150Y1605290D02*
X-3377Y1605683D01*
G01X-3150Y1605290D02*
X-3377Y1605683D01*
G01X-3150Y1601353D02*
X-3377Y1601746D01*
G01X-3150Y1601353D02*
X-3377Y1601746D01*
G01X-3150Y1597416D02*
X-3377Y1597809D01*
G01X-3150Y1597416D02*
X-3377Y1597809D01*
G01X-3756Y1601392D02*
Y1599187D01*
G01Y1605329D02*
Y1603124D01*
G01Y1609266D02*
Y1607061D01*
G01Y1613203D02*
Y1610998D01*
G01Y1617140D02*
Y1614935D01*
G01X-4725Y1616825D02*
Y1617730D01*
G01Y1612888D02*
Y1613793D01*
G01Y1614345D02*
Y1615250D01*
G01Y1606471D02*
Y1607376D01*
G01Y1608951D02*
Y1609856D01*
G01Y1610408D02*
Y1611313D01*
G01Y1602534D02*
Y1603439D01*
G01Y1605014D02*
Y1605919D01*
G01Y1597140D02*
Y1598045D01*
G01Y1598597D02*
Y1599502D01*
G01Y1601077D02*
Y1601982D01*
G01Y1598045D02*
Y1597140D01*
G01Y1599502D02*
Y1598597D01*
G01Y1601982D02*
Y1601077D01*
G01Y1607376D02*
Y1606471D01*
G01Y1603439D02*
Y1602534D01*
G01Y1605919D02*
Y1605014D01*
G01Y1611313D02*
Y1610408D01*
G01Y1609856D02*
Y1608951D01*
G01Y1615250D02*
Y1614345D01*
G01Y1613793D02*
Y1612888D01*
G01Y1617730D02*
Y1616825D01*
G01X-6693Y1599502D02*
Y1598912D01*
G01Y1601667D02*
Y1601077D01*
G01Y1597730D02*
Y1597140D01*
G01Y1597730D02*
Y1597140D01*
G01Y1599502D02*
Y1598912D01*
G01Y1601667D02*
Y1601077D01*
G01Y1603439D02*
Y1602849D01*
G01Y1605604D02*
Y1605014D01*
G01Y1603439D02*
Y1602849D01*
G01Y1605604D02*
Y1605014D01*
G01Y1611313D02*
Y1610723D01*
G01Y1607376D02*
Y1606786D01*
G01Y1609541D02*
Y1608951D01*
G01Y1607376D02*
Y1606786D01*
G01Y1609541D02*
Y1608951D01*
G01Y1611313D02*
Y1610723D01*
G01Y1615250D02*
Y1614660D01*
G01Y1613478D02*
Y1612888D01*
G01Y1613478D02*
Y1612888D01*
G01Y1615250D02*
Y1614660D01*
G01Y1617416D02*
Y1616825D01*
G01Y1617416D02*
Y1616825D01*
G01X-10530Y1601358D02*
Y1599221D01*
G01Y1601358D02*
Y1599221D01*
G01Y1605295D02*
Y1603158D01*
G01Y1605295D02*
Y1603158D01*
G01Y1609232D02*
Y1607095D01*
G01Y1609232D02*
Y1607095D01*
G01Y1613169D02*
Y1611032D01*
G01Y1613169D02*
Y1611032D01*
G01Y1617106D02*
Y1614969D01*
G01Y1617106D02*
Y1614969D01*
G01X-11842Y1615027D02*
Y1617048D01*
G01Y1611090D02*
Y1613111D01*
G01Y1607153D02*
Y1609174D01*
G01Y1603216D02*
Y1605237D01*
G01Y1599279D02*
Y1601300D01*
G01D02*
Y1599279D01*
G01Y1605237D02*
Y1603216D01*
G01Y1609174D02*
Y1607153D01*
G01Y1613111D02*
Y1611090D01*
G01Y1617048D02*
Y1615027D01*
G01X-12280Y1615032D02*
Y1617043D01*
G01Y1611095D02*
Y1613106D01*
G01Y1607158D02*
Y1609169D01*
G01Y1603221D02*
Y1605232D01*
G01Y1599284D02*
Y1601295D01*
G01D02*
Y1599284D01*
G01Y1605232D02*
Y1603221D01*
G01Y1609169D02*
Y1607158D01*
G01Y1613106D02*
Y1611095D01*
G01Y1617043D02*
Y1615032D01*
G01X-12992Y1597770D02*
Y1597455D01*
G01Y1601707D02*
Y1601392D01*
G01Y1599187D02*
Y1598872D01*
G01Y1605644D02*
Y1605329D01*
G01Y1603124D02*
Y1602809D01*
G01Y1609581D02*
Y1609266D01*
G01Y1607061D02*
Y1606746D01*
G01Y1610998D02*
Y1610683D01*
G01Y1613518D02*
Y1613203D01*
G01Y1614935D02*
Y1614620D01*
G01Y1617455D02*
Y1617140D01*
G01X-23684Y1615160D02*
Y1616916D01*
G01Y1611223D02*
Y1612979D01*
G01Y1607286D02*
Y1609042D01*
G01Y1603349D02*
Y1605105D01*
G01Y1599412D02*
Y1601168D01*
G01D02*
Y1599412D01*
G01Y1605105D02*
Y1603349D01*
G01Y1609042D02*
Y1607286D01*
G01Y1612979D02*
Y1611223D01*
G01Y1616916D02*
Y1615160D01*
G01X-10630Y1597376D02*
X-9843Y1597730D01*
G01D02*
X-10630Y1597376D01*
G01Y1601313D02*
X-9843Y1601667D01*
G01D02*
X-10630Y1601313D01*
G01Y1605250D02*
X-9843Y1605604D01*
G01D02*
X-10630Y1605250D01*
G01Y1609187D02*
X-9843Y1609541D01*
G01D02*
X-10630Y1609187D01*
G01Y1613124D02*
X-9843Y1613478D01*
G01D02*
X-10630Y1613124D01*
G01Y1617061D02*
X-9843Y1617416D01*
G01D02*
X-10630Y1617061D01*
G01X-3377Y1598833D02*
X-3150Y1599227D01*
G01X-3377Y1598833D02*
X-3150Y1599227D01*
G01X-3377Y1602770D02*
X-3150Y1603164D01*
G01X-3377Y1602770D02*
X-3150Y1603164D01*
G01X-3377Y1606707D02*
X-3150Y1607101D01*
G01X-3377Y1606707D02*
X-3150Y1607101D01*
G01X-3377Y1610644D02*
X-3150Y1611038D01*
G01X-3377Y1610644D02*
X-3150Y1611038D01*
G01X-3377Y1614581D02*
X-3150Y1614975D01*
G01X-3377Y1614581D02*
X-3150Y1614975D01*
G01X-6693Y1637101D02*
X-4725Y1637416D01*
G01X-6693Y1637101D02*
X-4725Y1637416D01*
G01X-6693Y1633164D02*
X-4725Y1633478D01*
G01X-6693Y1633164D02*
X-4725Y1633478D01*
G01X-6693Y1629227D02*
X-4725Y1629541D01*
G01X-6693Y1629227D02*
X-4725Y1629541D01*
G01X-6693Y1625290D02*
X-4725Y1625604D01*
G01X-6693Y1625290D02*
X-4725Y1625604D01*
G01X-6693Y1621353D02*
X-4725Y1621667D01*
G01X-6693Y1621353D02*
X-4725Y1621667D01*
G01X-6693Y1617416D02*
X-4725Y1617730D01*
G01X-6693Y1617416D02*
X-4725Y1617730D01*
G01X-3377Y1637179D02*
X-4258Y1636943D01*
G01X-3377Y1637179D02*
X-4258Y1636943D01*
G01X-3377Y1633242D02*
X-4258Y1633006D01*
G01X-3377Y1633242D02*
X-4258Y1633006D01*
G01X-3377Y1629305D02*
X-4258Y1629069D01*
G01X-3377Y1629305D02*
X-4258Y1629069D01*
G01X-3377Y1625368D02*
X-4258Y1625132D01*
G01X-3377Y1625368D02*
X-4258Y1625132D01*
G01X-3377Y1621431D02*
X-4258Y1621195D01*
G01X-3377Y1621431D02*
X-4258Y1621195D01*
G01X-6693Y1638282D02*
X-9843D01*
G01X-6693D02*
X-9843D01*
G01X-12992Y1638242D02*
X0D01*
G01Y1637140D02*
X-12992D01*
G01X-9843Y1637101D02*
X-6693D01*
G01X-9843D02*
X-6693D01*
G01X-4725Y1636943D02*
X-4258D01*
G01X-4725D02*
X-4258D01*
G01X-3150Y1636786D02*
X-2196D01*
G01X-3150D02*
X-2196D01*
G01X-4725Y1636510D02*
X-6693D01*
G01X-4725D02*
X-6693D01*
G01X-4725Y1634935D02*
X-6693D01*
G01X-4725D02*
X-6693D01*
G01X-2196Y1634660D02*
X-3150D01*
G01X-2196D02*
X-3150D01*
G01X-4258Y1634502D02*
X-4725D01*
G01X-4258D02*
X-4725D01*
G01X-6693Y1634345D02*
X-9843D01*
G01X-6693D02*
X-9843D01*
G01X-12992Y1634305D02*
X0D01*
G01Y1633203D02*
X-12992D01*
G01X-9843Y1633164D02*
X-6693D01*
G01X-9843D02*
X-6693D01*
G01X-4725Y1633006D02*
X-4258D01*
G01X-4725D02*
X-4258D01*
G01X-3150Y1632849D02*
X-2196D01*
G01X-3150D02*
X-2196D01*
G01X-4725Y1632573D02*
X-6693D01*
G01X-4725D02*
X-6693D01*
G01X-4725Y1630998D02*
X-6693D01*
G01X-4725D02*
X-6693D01*
G01X-2196Y1630723D02*
X-3150D01*
G01X-2196D02*
X-3150D01*
G01X-4258Y1630565D02*
X-4725D01*
G01X-4258D02*
X-4725D01*
G01X-6693Y1630408D02*
X-9843D01*
G01X-6693D02*
X-9843D01*
G01X-12992Y1630368D02*
X0D01*
G01Y1629266D02*
X-12992D01*
G01X-9843Y1629227D02*
X-6693D01*
G01X-9843D02*
X-6693D01*
G01X-4725Y1629069D02*
X-4258D01*
G01X-4725D02*
X-4258D01*
G01X-3150Y1628912D02*
X-2196D01*
G01X-3150D02*
X-2196D01*
G01X-4725Y1628636D02*
X-6693D01*
G01X-4725D02*
X-6693D01*
G01X-4725Y1627061D02*
X-6693D01*
G01X-4725D02*
X-6693D01*
G01X-2196Y1626786D02*
X-3150D01*
G01X-2196D02*
X-3150D01*
G01X-4258Y1626628D02*
X-4725D01*
G01X-4258D02*
X-4725D01*
G01X-6693Y1626471D02*
X-9843D01*
G01X-6693D02*
X-9843D01*
G01X-12992Y1626431D02*
X0D01*
G01Y1625329D02*
X-12992D01*
G01X-9843Y1625290D02*
X-6693D01*
G01X-9843D02*
X-6693D01*
G01X-4725Y1625132D02*
X-4258D01*
G01X-4725D02*
X-4258D01*
G01X-3150Y1624975D02*
X-2196D01*
G01X-3150D02*
X-2196D01*
G01X-4725Y1624699D02*
X-6693D01*
G01X-4725D02*
X-6693D01*
G01X-4725Y1623124D02*
X-6693D01*
G01X-4725D02*
X-6693D01*
G01X-2196Y1622849D02*
X-3150D01*
G01X-2196D02*
X-3150D01*
G01X-4258Y1622691D02*
X-4725D01*
G01X-4258D02*
X-4725D01*
G01X-6693Y1622534D02*
X-9843D01*
G01X-6693D02*
X-9843D01*
G01X-12992Y1622494D02*
X0D01*
G01Y1621392D02*
X-12992D01*
G01X-9843Y1621353D02*
X-6693D01*
G01X-9843D02*
X-6693D01*
G01X-4725Y1621195D02*
X-4258D01*
G01X-4725D02*
X-4258D01*
G01X-3150Y1621038D02*
X-2196D01*
G01X-3150D02*
X-2196D01*
G01X-4725Y1620762D02*
X-6693D01*
G01X-4725D02*
X-6693D01*
G01X-4725Y1619187D02*
X-6693D01*
G01X-4725D02*
X-6693D01*
G01X-2196Y1618912D02*
X-3150D01*
G01X-2196D02*
X-3150D01*
G01X-4258Y1618754D02*
X-4725D01*
G01X-4258D02*
X-4725D01*
G01X-6693Y1618597D02*
X-9843D01*
G01X-6693D02*
X-9843D01*
G01X-12992Y1618557D02*
X0D01*
G01Y1617455D02*
X-12992D01*
G01X-9843Y1617416D02*
X-6693D01*
G01X-9843D02*
X-6693D01*
G01X-4725Y1637967D02*
X-6693Y1638282D01*
G01X-4725Y1637967D02*
X-6693Y1638282D01*
G01X-4725Y1634030D02*
X-6693Y1634345D01*
G01X-4725Y1634030D02*
X-6693Y1634345D01*
G01X-4258Y1638439D02*
X-3377Y1638203D01*
G01X-4258Y1638439D02*
X-3377Y1638203D01*
G01X-4258Y1634502D02*
X-3377Y1634266D01*
G01X-4258Y1634502D02*
X-3377Y1634266D01*
G01X-4258Y1630565D02*
X-3377Y1630329D01*
G01X-4258Y1630565D02*
X-3377Y1630329D01*
G01X-4258Y1626628D02*
X-3377Y1626392D01*
G01X-4258Y1626628D02*
X-3377Y1626392D01*
G01X-4258Y1622691D02*
X-3377Y1622455D01*
G01X-4258Y1622691D02*
X-3377Y1622455D01*
G01X-4725Y1630093D02*
X-6693Y1630408D01*
G01X-4725Y1630093D02*
X-6693Y1630408D01*
G01X-4725Y1626156D02*
X-6693Y1626471D01*
G01X-4725Y1626156D02*
X-6693Y1626471D01*
G01X-4725Y1622219D02*
X-6693Y1622534D01*
G01X-4725Y1622219D02*
X-6693Y1622534D01*
G01X-4725Y1618282D02*
X-6693Y1618597D01*
G01X-4725Y1618282D02*
X-6693Y1618597D01*
G01X-4258Y1618754D02*
X-3377Y1618518D01*
G01X-4258Y1618754D02*
X-3377Y1618518D01*
G01X-9843Y1638282D02*
X-10630Y1638636D01*
G01D02*
X-9843Y1638282D01*
G01Y1634345D02*
X-10630Y1634699D01*
G01D02*
X-9843Y1634345D01*
G01Y1630408D02*
X-10630Y1630762D01*
G01D02*
X-9843Y1630408D01*
G01Y1626471D02*
X-10630Y1626825D01*
G01D02*
X-9843Y1626471D01*
G01Y1622534D02*
X-10630Y1622888D01*
G01D02*
X-9843Y1622534D01*
G01Y1618597D02*
X-10630Y1618951D01*
G01D02*
X-9843Y1618597D01*
G01X-3150Y1636786D02*
X-3377Y1637179D01*
G01X-3150Y1636786D02*
X-3377Y1637179D01*
G01X-3150Y1632849D02*
X-3377Y1633242D01*
G01X-3150Y1632849D02*
X-3377Y1633242D01*
G01X-3150Y1628912D02*
X-3377Y1629305D01*
G01X-3150Y1628912D02*
X-3377Y1629305D01*
G01X-3150Y1624975D02*
X-3377Y1625368D01*
G01X-3150Y1624975D02*
X-3377Y1625368D01*
G01X-3150Y1621038D02*
X-3377Y1621431D01*
G01X-3150Y1621038D02*
X-3377Y1621431D01*
G01X-3756Y1625014D02*
Y1622809D01*
G01Y1621077D02*
Y1618872D01*
G01Y1628951D02*
Y1626746D01*
G01Y1632888D02*
Y1630683D01*
G01Y1636825D02*
Y1634620D01*
G01X-4725Y1636510D02*
Y1637416D01*
G01Y1637967D02*
Y1638872D01*
G01Y1630093D02*
Y1630998D01*
G01Y1632573D02*
Y1633478D01*
G01Y1634030D02*
Y1634935D01*
G01Y1626156D02*
Y1627061D01*
G01Y1628636D02*
Y1629541D01*
G01Y1620762D02*
Y1621667D01*
G01Y1622219D02*
Y1623124D01*
G01Y1624699D02*
Y1625604D01*
G01Y1618282D02*
Y1619187D01*
G01D02*
Y1618282D01*
G01Y1623124D02*
Y1622219D01*
G01Y1625604D02*
Y1624699D01*
G01Y1621667D02*
Y1620762D01*
G01Y1627061D02*
Y1626156D01*
G01Y1629541D02*
Y1628636D01*
G01Y1634935D02*
Y1634030D01*
G01Y1630998D02*
Y1630093D01*
G01Y1633478D02*
Y1632573D01*
G01Y1638872D02*
Y1637967D01*
G01Y1637416D02*
Y1636510D01*
G01X-6693Y1619187D02*
Y1618597D01*
G01Y1619187D02*
Y1618597D01*
G01Y1623124D02*
Y1622534D01*
G01Y1625290D02*
Y1624699D01*
G01Y1621353D02*
Y1620762D01*
G01Y1621353D02*
Y1620762D01*
G01Y1623124D02*
Y1622534D01*
G01Y1625290D02*
Y1624699D01*
G01Y1627061D02*
Y1626471D01*
G01Y1629227D02*
Y1628636D01*
G01Y1627061D02*
Y1626471D01*
G01Y1629227D02*
Y1628636D01*
G01Y1634935D02*
Y1634345D01*
G01Y1630998D02*
Y1630408D01*
G01Y1633164D02*
Y1632573D01*
G01Y1630998D02*
Y1630408D01*
G01Y1633164D02*
Y1632573D01*
G01Y1634935D02*
Y1634345D01*
G01Y1638872D02*
Y1638282D01*
G01Y1637101D02*
Y1636510D01*
G01Y1637101D02*
Y1636510D01*
G01Y1638872D02*
Y1638282D01*
G01X-10530Y1624980D02*
Y1622843D01*
G01Y1621043D02*
Y1618906D01*
G01Y1624980D02*
Y1622843D01*
G01Y1621043D02*
Y1618906D01*
G01Y1628917D02*
Y1626780D01*
G01Y1628917D02*
Y1626780D01*
G01Y1632854D02*
Y1630717D01*
G01Y1632854D02*
Y1630717D01*
G01Y1636791D02*
Y1634654D01*
G01Y1636791D02*
Y1634654D01*
G01X-11842Y1634712D02*
Y1636733D01*
G01Y1630775D02*
Y1632796D01*
G01Y1626838D02*
Y1628859D01*
G01Y1622901D02*
Y1624922D01*
G01Y1618964D02*
Y1620985D01*
G01D02*
Y1618964D01*
G01Y1624922D02*
Y1622901D01*
G01Y1628859D02*
Y1626838D01*
G01Y1632796D02*
Y1630775D01*
G01Y1636733D02*
Y1634712D01*
G01X-12280Y1634717D02*
Y1636728D01*
G01Y1630780D02*
Y1632791D01*
G01Y1626843D02*
Y1628854D01*
G01Y1622906D02*
Y1624917D01*
G01Y1618969D02*
Y1620980D01*
G01D02*
Y1618969D01*
G01Y1624917D02*
Y1622906D01*
G01Y1628854D02*
Y1626843D01*
G01Y1632791D02*
Y1630780D01*
G01Y1636728D02*
Y1634717D01*
G01X-12992Y1618872D02*
Y1618557D01*
G01Y1621392D02*
Y1621077D01*
G01Y1625329D02*
Y1625014D01*
G01Y1622809D02*
Y1622494D01*
G01Y1629266D02*
Y1628951D01*
G01Y1626746D02*
Y1626431D01*
G01Y1633203D02*
Y1632888D01*
G01Y1630683D02*
Y1630368D01*
G01Y1634620D02*
Y1634305D01*
G01Y1637140D02*
Y1636825D01*
G01Y1638557D02*
Y1638242D01*
G01X-23684Y1634845D02*
Y1636601D01*
G01Y1630908D02*
Y1632664D01*
G01Y1626971D02*
Y1628727D01*
G01Y1623034D02*
Y1624790D01*
G01Y1619097D02*
Y1620853D01*
G01D02*
Y1619097D01*
G01Y1624790D02*
Y1623034D01*
G01Y1628727D02*
Y1626971D01*
G01Y1632664D02*
Y1630908D01*
G01Y1636601D02*
Y1634845D01*
G01X-10630Y1620998D02*
X-9843Y1621353D01*
G01D02*
X-10630Y1620998D01*
G01Y1624935D02*
X-9843Y1625290D01*
G01D02*
X-10630Y1624935D01*
G01Y1628872D02*
X-9843Y1629227D01*
G01D02*
X-10630Y1628872D01*
G01Y1632809D02*
X-9843Y1633164D01*
G01D02*
X-10630Y1632809D01*
G01Y1636746D02*
X-9843Y1637101D01*
G01D02*
X-10630Y1636746D01*
G01X-3377Y1618518D02*
X-3150Y1618912D01*
G01X-3377Y1618518D02*
X-3150Y1618912D01*
G01X-3377Y1622455D02*
X-3150Y1622849D01*
G01X-3377Y1622455D02*
X-3150Y1622849D01*
G01X-3377Y1626392D02*
X-3150Y1626786D01*
G01X-3377Y1626392D02*
X-3150Y1626786D01*
G01X-3377Y1630329D02*
X-3150Y1630723D01*
G01X-3377Y1630329D02*
X-3150Y1630723D01*
G01X-3377Y1634266D02*
X-3150Y1634660D01*
G01X-3377Y1634266D02*
X-3150Y1634660D01*
G01X-3377Y1638203D02*
X-3150Y1638597D01*
G01X-3377Y1638203D02*
X-3150Y1638597D01*
G01X-3377Y1656864D02*
X-4258Y1656628D01*
G01X-3377Y1656864D02*
X-4258Y1656628D01*
G01X-6693Y1656786D02*
X-4725Y1657101D01*
G01X-6693Y1656786D02*
X-4725Y1657101D01*
G01X-6693Y1652849D02*
X-4725Y1653164D01*
G01X-6693Y1652849D02*
X-4725Y1653164D01*
G01X-6693Y1648912D02*
X-4725Y1649227D01*
G01X-6693Y1648912D02*
X-4725Y1649227D01*
G01X-6693Y1644975D02*
X-4725Y1645290D01*
G01X-6693Y1644975D02*
X-4725Y1645290D01*
G01X-6693Y1641038D02*
X-4725Y1641353D01*
G01X-6693Y1641038D02*
X-4725Y1641353D01*
G01X-3377Y1652927D02*
X-4258Y1652691D01*
G01X-3377Y1652927D02*
X-4258Y1652691D01*
G01X-3377Y1648990D02*
X-4258Y1648754D01*
G01X-3377Y1648990D02*
X-4258Y1648754D01*
G01X-3377Y1645053D02*
X-4258Y1644817D01*
G01X-3377Y1645053D02*
X-4258Y1644817D01*
G01X-3377Y1641116D02*
X-4258Y1640880D01*
G01X-3377Y1641116D02*
X-4258Y1640880D01*
G01X-4725Y1658557D02*
X-6693D01*
G01X-4725D02*
X-6693D01*
G01X-2196Y1658282D02*
X-3150D01*
G01X-2196D02*
X-3150D01*
G01X-4258Y1658124D02*
X-4725D01*
G01X-4258D02*
X-4725D01*
G01X-6693Y1657967D02*
X-9843D01*
G01X-6693D02*
X-9843D01*
G01X-12992Y1657927D02*
X0D01*
G01Y1656825D02*
X-12992D01*
G01X-9843Y1656786D02*
X-6693D01*
G01X-9843D02*
X-6693D01*
G01X-4725Y1656628D02*
X-4258D01*
G01X-4725D02*
X-4258D01*
G01X-3150Y1656471D02*
X-2196D01*
G01X-3150D02*
X-2196D01*
G01X-4725Y1656195D02*
X-6693D01*
G01X-4725D02*
X-6693D01*
G01X-4725Y1654620D02*
X-6693D01*
G01X-4725D02*
X-6693D01*
G01X-2196Y1654345D02*
X-3150D01*
G01X-2196D02*
X-3150D01*
G01X-4258Y1654187D02*
X-4725D01*
G01X-4258D02*
X-4725D01*
G01X-6693Y1654030D02*
X-9843D01*
G01X-6693D02*
X-9843D01*
G01X-12992Y1653990D02*
X0D01*
G01Y1652888D02*
X-12992D01*
G01X-9843Y1652849D02*
X-6693D01*
G01X-9843D02*
X-6693D01*
G01X-4725Y1652691D02*
X-4258D01*
G01X-4725D02*
X-4258D01*
G01X-3150Y1652534D02*
X-2196D01*
G01X-3150D02*
X-2196D01*
G01X-4725Y1652258D02*
X-6693D01*
G01X-4725D02*
X-6693D01*
G01X-4725Y1650683D02*
X-6693D01*
G01X-4725D02*
X-6693D01*
G01X-2196Y1650408D02*
X-3150D01*
G01X-2196D02*
X-3150D01*
G01X-4258Y1650250D02*
X-4725D01*
G01X-4258D02*
X-4725D01*
G01X-6693Y1650093D02*
X-9843D01*
G01X-6693D02*
X-9843D01*
G01X-12992Y1650053D02*
X0D01*
G01Y1648951D02*
X-12992D01*
G01X-9843Y1648912D02*
X-6693D01*
G01X-9843D02*
X-6693D01*
G01X-4725Y1648754D02*
X-4258D01*
G01X-4725D02*
X-4258D01*
G01X-3150Y1648597D02*
X-2196D01*
G01X-3150D02*
X-2196D01*
G01X-4725Y1648321D02*
X-6693D01*
G01X-4725D02*
X-6693D01*
G01X-4725Y1646746D02*
X-6693D01*
G01X-4725D02*
X-6693D01*
G01X-2196Y1646471D02*
X-3150D01*
G01X-2196D02*
X-3150D01*
G01X-4258Y1646313D02*
X-4725D01*
G01X-4258D02*
X-4725D01*
G01X-6693Y1646156D02*
X-9843D01*
G01X-6693D02*
X-9843D01*
G01X-12992Y1646116D02*
X0D01*
G01Y1645014D02*
X-12992D01*
G01X-9843Y1644975D02*
X-6693D01*
G01X-9843D02*
X-6693D01*
G01X-4725Y1644817D02*
X-4258D01*
G01X-4725D02*
X-4258D01*
G01X-3150Y1644660D02*
X-2196D01*
G01X-3150D02*
X-2196D01*
G01X-4725Y1644384D02*
X-6693D01*
G01X-4725D02*
X-6693D01*
G01X-4725Y1642809D02*
X-6693D01*
G01X-4725D02*
X-6693D01*
G01X-2196Y1642534D02*
X-3150D01*
G01X-2196D02*
X-3150D01*
G01X-4258Y1642376D02*
X-4725D01*
G01X-4258D02*
X-4725D01*
G01X-6693Y1642219D02*
X-9843D01*
G01X-6693D02*
X-9843D01*
G01X-12992Y1642179D02*
X0D01*
G01Y1641077D02*
X-12992D01*
G01X-9843Y1641038D02*
X-6693D01*
G01X-9843D02*
X-6693D01*
G01X-4725Y1640880D02*
X-4258D01*
G01X-4725D02*
X-4258D01*
G01X-3150Y1640723D02*
X-2196D01*
G01X-3150D02*
X-2196D01*
G01X-4725Y1640447D02*
X-6693D01*
G01X-4725D02*
X-6693D01*
G01X-4725Y1638872D02*
X-6693D01*
G01X-4725D02*
X-6693D01*
G01X-2196Y1638597D02*
X-3150D01*
G01X-2196D02*
X-3150D01*
G01X-4258Y1638439D02*
X-4725D01*
G01X-4258D02*
X-4725D01*
G01Y1657652D02*
X-6693Y1657967D01*
G01X-4725Y1657652D02*
X-6693Y1657967D01*
G01X-4725Y1653715D02*
X-6693Y1654030D01*
G01X-4725Y1653715D02*
X-6693Y1654030D01*
G01X-4725Y1649778D02*
X-6693Y1650093D01*
G01X-4725Y1649778D02*
X-6693Y1650093D01*
G01X-4725Y1645841D02*
X-6693Y1646156D01*
G01X-4725Y1645841D02*
X-6693Y1646156D01*
G01X-4725Y1641904D02*
X-6693Y1642219D01*
G01X-4725Y1641904D02*
X-6693Y1642219D01*
G01X-4258Y1658124D02*
X-3377Y1657888D01*
G01X-4258Y1658124D02*
X-3377Y1657888D01*
G01X-4258Y1654187D02*
X-3377Y1653951D01*
G01X-4258Y1654187D02*
X-3377Y1653951D01*
G01X-4258Y1650250D02*
X-3377Y1650014D01*
G01X-4258Y1650250D02*
X-3377Y1650014D01*
G01X-4258Y1646313D02*
X-3377Y1646077D01*
G01X-4258Y1646313D02*
X-3377Y1646077D01*
G01X-4258Y1642376D02*
X-3377Y1642140D01*
G01X-4258Y1642376D02*
X-3377Y1642140D01*
G01X-9843Y1657967D02*
X-10630Y1658321D01*
G01D02*
X-9843Y1657967D01*
G01Y1654030D02*
X-10630Y1654384D01*
G01D02*
X-9843Y1654030D01*
G01Y1650093D02*
X-10630Y1650447D01*
G01D02*
X-9843Y1650093D01*
G01Y1646156D02*
X-10630Y1646510D01*
G01D02*
X-9843Y1646156D01*
G01Y1642219D02*
X-10630Y1642573D01*
G01D02*
X-9843Y1642219D01*
G01X-3150Y1656471D02*
X-3377Y1656864D01*
G01X-3150Y1656471D02*
X-3377Y1656864D01*
G01X-3150Y1652534D02*
X-3377Y1652927D01*
G01X-3150Y1652534D02*
X-3377Y1652927D01*
G01X-3150Y1648597D02*
X-3377Y1648990D01*
G01X-3150Y1648597D02*
X-3377Y1648990D01*
G01X-3150Y1644660D02*
X-3377Y1645053D01*
G01X-3150Y1644660D02*
X-3377Y1645053D01*
G01X-3150Y1640723D02*
X-3377Y1641116D01*
G01X-3150Y1640723D02*
X-3377Y1641116D01*
G01X-3756Y1640762D02*
Y1638557D01*
G01Y1648636D02*
Y1646431D01*
G01Y1644699D02*
Y1642494D01*
G01Y1652573D02*
Y1650368D01*
G01Y1656510D02*
Y1654305D01*
G01Y1660447D02*
Y1658242D01*
G01X-4725Y1657652D02*
Y1658557D01*
G01Y1653715D02*
Y1654620D01*
G01Y1656195D02*
Y1657101D01*
G01Y1648321D02*
Y1649227D01*
G01Y1649778D02*
Y1650683D01*
G01Y1652258D02*
Y1653164D01*
G01Y1644384D02*
Y1645290D01*
G01Y1645841D02*
Y1646746D01*
G01Y1640447D02*
Y1641353D01*
G01Y1641904D02*
Y1642809D01*
G01D02*
Y1641904D01*
G01Y1641353D02*
Y1640447D01*
G01Y1645290D02*
Y1644384D01*
G01Y1646746D02*
Y1645841D01*
G01Y1649227D02*
Y1648321D01*
G01Y1650683D02*
Y1649778D01*
G01Y1653164D02*
Y1652258D01*
G01Y1658557D02*
Y1657652D01*
G01Y1654620D02*
Y1653715D01*
G01Y1657101D02*
Y1656195D01*
G01X-6693Y1642809D02*
Y1642219D01*
G01Y1641038D02*
Y1640447D01*
G01Y1641038D02*
Y1640447D01*
G01Y1642809D02*
Y1642219D01*
G01Y1644975D02*
Y1644384D01*
G01Y1646746D02*
Y1646156D01*
G01Y1648912D02*
Y1648321D01*
G01Y1644975D02*
Y1644384D01*
G01Y1646746D02*
Y1646156D01*
G01Y1648912D02*
Y1648321D01*
G01Y1650683D02*
Y1650093D01*
G01Y1652849D02*
Y1652258D01*
G01Y1650683D02*
Y1650093D01*
G01Y1652849D02*
Y1652258D01*
G01Y1654620D02*
Y1654030D01*
G01Y1656786D02*
Y1656195D01*
G01Y1654620D02*
Y1654030D01*
G01Y1656786D02*
Y1656195D01*
G01Y1658557D02*
Y1657967D01*
G01Y1658557D02*
Y1657967D01*
G01X-10530Y1640728D02*
Y1638591D01*
G01Y1640728D02*
Y1638591D01*
G01Y1648603D02*
Y1646465D01*
G01Y1644666D02*
Y1642528D01*
G01Y1648603D02*
Y1646465D01*
G01Y1644666D02*
Y1642528D01*
G01Y1652540D02*
Y1650402D01*
G01Y1652540D02*
Y1650402D01*
G01Y1656477D02*
Y1654339D01*
G01Y1656477D02*
Y1654339D01*
G01Y1660414D02*
Y1658276D01*
G01Y1660414D02*
Y1658276D01*
G01X-11842Y1658334D02*
Y1660355D01*
G01Y1654397D02*
Y1656418D01*
G01Y1650460D02*
Y1652481D01*
G01Y1646523D02*
Y1648544D01*
G01Y1642586D02*
Y1644607D01*
G01Y1638649D02*
Y1640670D01*
G01D02*
Y1638649D01*
G01Y1644607D02*
Y1642586D01*
G01Y1648544D02*
Y1646523D01*
G01Y1652481D02*
Y1650460D01*
G01Y1656418D02*
Y1654397D01*
G01Y1660355D02*
Y1658334D01*
G01X-12280Y1658340D02*
Y1660350D01*
G01Y1654403D02*
Y1656413D01*
G01Y1650466D02*
Y1652476D01*
G01Y1646528D02*
Y1648539D01*
G01Y1642591D02*
Y1644602D01*
G01Y1638654D02*
Y1640665D01*
G01D02*
Y1638654D01*
G01Y1644602D02*
Y1642591D01*
G01Y1648539D02*
Y1646528D01*
G01Y1652476D02*
Y1650466D01*
G01Y1656413D02*
Y1654403D01*
G01Y1660350D02*
Y1658340D01*
G01X-12992Y1641077D02*
Y1640762D01*
G01Y1642494D02*
Y1642179D01*
G01Y1645014D02*
Y1644699D01*
G01Y1648951D02*
Y1648636D01*
G01Y1646431D02*
Y1646116D01*
G01Y1652888D02*
Y1652573D01*
G01Y1650368D02*
Y1650053D01*
G01Y1656825D02*
Y1656510D01*
G01Y1654305D02*
Y1653990D01*
G01Y1658242D02*
Y1657927D01*
G01X-23684Y1658467D02*
Y1660223D01*
G01Y1654530D02*
Y1656286D01*
G01Y1650593D02*
Y1652349D01*
G01Y1642719D02*
Y1644475D01*
G01Y1646656D02*
Y1648412D01*
G01Y1638782D02*
Y1640538D01*
G01D02*
Y1638782D01*
G01Y1648412D02*
Y1646656D01*
G01Y1644475D02*
Y1642719D01*
G01Y1652349D02*
Y1650593D01*
G01Y1656286D02*
Y1654530D01*
G01Y1660223D02*
Y1658467D01*
G01X-10630Y1640683D02*
X-9843Y1641038D01*
G01D02*
X-10630Y1640683D01*
G01Y1644620D02*
X-9843Y1644975D01*
G01D02*
X-10630Y1644620D01*
G01Y1648557D02*
X-9843Y1648912D01*
G01D02*
X-10630Y1648557D01*
G01Y1652494D02*
X-9843Y1652849D01*
G01D02*
X-10630Y1652494D01*
G01Y1656431D02*
X-9843Y1656786D01*
G01D02*
X-10630Y1656431D01*
G01X-3377Y1642140D02*
X-3150Y1642534D01*
G01X-3377Y1642140D02*
X-3150Y1642534D01*
G01X-3377Y1646077D02*
X-3150Y1646471D01*
G01X-3377Y1646077D02*
X-3150Y1646471D01*
G01X-3377Y1650014D02*
X-3150Y1650408D01*
G01X-3377Y1650014D02*
X-3150Y1650408D01*
G01X-3377Y1653951D02*
X-3150Y1654345D01*
G01X-3377Y1653951D02*
X-3150Y1654345D01*
G01X-3377Y1657888D02*
X-3150Y1658282D01*
G01X-3377Y1657888D02*
X-3150Y1658282D01*
G01X-3377Y1680486D02*
X-4258Y1680250D01*
G01X-3377Y1680486D02*
X-4258Y1680250D01*
G01X-3377Y1676549D02*
X-4258Y1676313D01*
G01X-3377Y1676549D02*
X-4258Y1676313D01*
G01X-3377Y1672612D02*
X-4258Y1672376D01*
G01X-3377Y1672612D02*
X-4258Y1672376D01*
G01X-3377Y1668675D02*
X-4258Y1668439D01*
G01X-3377Y1668675D02*
X-4258Y1668439D01*
G01X-3377Y1664738D02*
X-4258Y1664502D01*
G01X-3377Y1664738D02*
X-4258Y1664502D01*
G01X-3377Y1660801D02*
X-4258Y1660565D01*
G01X-3377Y1660801D02*
X-4258Y1660565D01*
G01X-6693Y1680408D02*
X-4725Y1680723D01*
G01X-6693Y1680408D02*
X-4725Y1680723D01*
G01X-6693Y1676471D02*
X-4725Y1676786D01*
G01X-6693Y1676471D02*
X-4725Y1676786D01*
G01X-6693Y1672534D02*
X-4725Y1672849D01*
G01X-6693Y1672534D02*
X-4725Y1672849D01*
G01X-6693Y1668597D02*
X-4725Y1668912D01*
G01X-6693Y1668597D02*
X-4725Y1668912D01*
G01X-6693Y1664660D02*
X-4725Y1664975D01*
G01X-6693Y1664660D02*
X-4725Y1664975D01*
G01X-6693Y1660723D02*
X-4725Y1661038D01*
G01X-6693Y1660723D02*
X-4725Y1661038D01*
G01X0Y1680447D02*
X-12992D01*
G01X-9843Y1680408D02*
X-6693D01*
G01X-9843D02*
X-6693D01*
G01X-4725Y1680250D02*
X-4258D01*
G01X-4725D02*
X-4258D01*
G01X-3150Y1680093D02*
X-2196D01*
G01X-3150D02*
X-2196D01*
G01X-4725Y1679817D02*
X-6693D01*
G01X-4725D02*
X-6693D01*
G01X-4725Y1678242D02*
X-6693D01*
G01X-4725D02*
X-6693D01*
G01X-2196Y1677967D02*
X-3150D01*
G01X-2196D02*
X-3150D01*
G01X-4258Y1677809D02*
X-4725D01*
G01X-4258D02*
X-4725D01*
G01X-6693Y1677652D02*
X-9843D01*
G01X-6693D02*
X-9843D01*
G01X-12992Y1677612D02*
X0D01*
G01Y1676510D02*
X-12992D01*
G01X-9843Y1676471D02*
X-6693D01*
G01X-9843D02*
X-6693D01*
G01X-4725Y1676313D02*
X-4258D01*
G01X-4725D02*
X-4258D01*
G01X-3150Y1676156D02*
X-2196D01*
G01X-3150D02*
X-2196D01*
G01X-4725Y1675880D02*
X-6693D01*
G01X-4725D02*
X-6693D01*
G01X-4725Y1674305D02*
X-6693D01*
G01X-4725D02*
X-6693D01*
G01X-2196Y1674030D02*
X-3150D01*
G01X-2196D02*
X-3150D01*
G01X-4258Y1673872D02*
X-4725D01*
G01X-4258D02*
X-4725D01*
G01X-6693Y1673715D02*
X-9843D01*
G01X-6693D02*
X-9843D01*
G01X-12992Y1673675D02*
X0D01*
G01Y1672573D02*
X-12992D01*
G01X-9843Y1672534D02*
X-6693D01*
G01X-9843D02*
X-6693D01*
G01X-4725Y1672376D02*
X-4258D01*
G01X-4725D02*
X-4258D01*
G01X-3150Y1672219D02*
X-2196D01*
G01X-3150D02*
X-2196D01*
G01X-4725Y1671943D02*
X-6693D01*
G01X-4725D02*
X-6693D01*
G01X-4725Y1670368D02*
X-6693D01*
G01X-4725D02*
X-6693D01*
G01X-2196Y1670093D02*
X-3150D01*
G01X-2196D02*
X-3150D01*
G01X-4258Y1669935D02*
X-4725D01*
G01X-4258D02*
X-4725D01*
G01X-6693Y1669778D02*
X-9843D01*
G01X-6693D02*
X-9843D01*
G01X-12992Y1669738D02*
X0D01*
G01Y1668636D02*
X-12992D01*
G01X-9843Y1668597D02*
X-6693D01*
G01X-9843D02*
X-6693D01*
G01X-4725Y1668439D02*
X-4258D01*
G01X-4725D02*
X-4258D01*
G01X-3150Y1668282D02*
X-2196D01*
G01X-3150D02*
X-2196D01*
G01X-4725Y1668006D02*
X-6693D01*
G01X-4725D02*
X-6693D01*
G01X-4725Y1666431D02*
X-6693D01*
G01X-4725D02*
X-6693D01*
G01X-2196Y1666156D02*
X-3150D01*
G01X-2196D02*
X-3150D01*
G01X-4258Y1665998D02*
X-4725D01*
G01X-4258D02*
X-4725D01*
G01X-6693Y1665841D02*
X-9843D01*
G01X-6693D02*
X-9843D01*
G01X-12992Y1665801D02*
X0D01*
G01Y1664699D02*
X-12992D01*
G01X-9843Y1664660D02*
X-6693D01*
G01X-9843D02*
X-6693D01*
G01X-4725Y1664502D02*
X-4258D01*
G01X-4725D02*
X-4258D01*
G01X-3150Y1664345D02*
X-2196D01*
G01X-3150D02*
X-2196D01*
G01X-4725Y1664069D02*
X-6693D01*
G01X-4725D02*
X-6693D01*
G01X-4725Y1662494D02*
X-6693D01*
G01X-4725D02*
X-6693D01*
G01X-2196Y1662219D02*
X-3150D01*
G01X-2196D02*
X-3150D01*
G01X-4258Y1662061D02*
X-4725D01*
G01X-4258D02*
X-4725D01*
G01X-6693Y1661904D02*
X-9843D01*
G01X-6693D02*
X-9843D01*
G01X-12992Y1661864D02*
X0D01*
G01Y1660762D02*
X-12992D01*
G01X-9843Y1660723D02*
X-6693D01*
G01X-9843D02*
X-6693D01*
G01X-4725Y1660565D02*
X-4258D01*
G01X-4725D02*
X-4258D01*
G01X-3150Y1660408D02*
X-2196D01*
G01X-3150D02*
X-2196D01*
G01X-4725Y1660132D02*
X-6693D01*
G01X-4725D02*
X-6693D01*
G01X-4725Y1677337D02*
X-6693Y1677652D01*
G01X-4725Y1677337D02*
X-6693Y1677652D01*
G01X-4725Y1673400D02*
X-6693Y1673715D01*
G01X-4725Y1673400D02*
X-6693Y1673715D01*
G01X-4725Y1669463D02*
X-6693Y1669778D01*
G01X-4725Y1669463D02*
X-6693Y1669778D01*
G01X-4725Y1665526D02*
X-6693Y1665841D01*
G01X-4725Y1665526D02*
X-6693Y1665841D01*
G01X-4725Y1661589D02*
X-6693Y1661904D01*
G01X-4725Y1661589D02*
X-6693Y1661904D01*
G01X-4258Y1677809D02*
X-3377Y1677573D01*
G01X-4258Y1677809D02*
X-3377Y1677573D01*
G01X-4258Y1673872D02*
X-3377Y1673636D01*
G01X-4258Y1673872D02*
X-3377Y1673636D01*
G01X-4258Y1669935D02*
X-3377Y1669699D01*
G01X-4258Y1669935D02*
X-3377Y1669699D01*
G01X-4258Y1665998D02*
X-3377Y1665762D01*
G01X-4258Y1665998D02*
X-3377Y1665762D01*
G01X-4258Y1662061D02*
X-3377Y1661825D01*
G01X-4258Y1662061D02*
X-3377Y1661825D01*
G01X-9843Y1677652D02*
X-10630Y1678006D01*
G01D02*
X-9843Y1677652D01*
G01Y1673715D02*
X-10630Y1674069D01*
G01D02*
X-9843Y1673715D01*
G01Y1669778D02*
X-10630Y1670132D01*
G01D02*
X-9843Y1669778D01*
G01Y1665841D02*
X-10630Y1666195D01*
G01D02*
X-9843Y1665841D01*
G01Y1661904D02*
X-10630Y1662258D01*
G01D02*
X-9843Y1661904D01*
G01X-3150Y1680093D02*
X-3377Y1680486D01*
G01X-3150Y1680093D02*
X-3377Y1680486D01*
G01X-3150Y1676156D02*
X-3377Y1676549D01*
G01X-3150Y1676156D02*
X-3377Y1676549D01*
G01X-3150Y1672219D02*
X-3377Y1672612D01*
G01X-3150Y1672219D02*
X-3377Y1672612D01*
G01X-3150Y1668282D02*
X-3377Y1668675D01*
G01X-3150Y1668282D02*
X-3377Y1668675D01*
G01X-3150Y1664345D02*
X-3377Y1664738D01*
G01X-3150Y1664345D02*
X-3377Y1664738D01*
G01X-3150Y1660408D02*
X-3377Y1660801D01*
G01X-3150Y1660408D02*
X-3377Y1660801D01*
G01X-3756Y1664384D02*
Y1662179D01*
G01Y1672258D02*
Y1670053D01*
G01Y1668321D02*
Y1666116D01*
G01Y1676195D02*
Y1673990D01*
G01Y1680132D02*
Y1677927D01*
G01X-4725Y1677337D02*
Y1678242D01*
G01Y1679817D02*
Y1680723D01*
G01Y1673400D02*
Y1674305D01*
G01Y1675880D02*
Y1676786D01*
G01Y1671943D02*
Y1672849D01*
G01Y1669463D02*
Y1670368D01*
G01Y1668006D02*
Y1668912D01*
G01Y1664069D02*
Y1664975D01*
G01Y1665526D02*
Y1666431D01*
G01Y1660132D02*
Y1661038D01*
G01Y1661589D02*
Y1662494D01*
G01D02*
Y1661589D01*
G01Y1661038D02*
Y1660132D01*
G01Y1664975D02*
Y1664069D01*
G01Y1666431D02*
Y1665526D01*
G01Y1668912D02*
Y1668006D01*
G01Y1670368D02*
Y1669463D01*
G01Y1672849D02*
Y1671943D01*
G01Y1674305D02*
Y1673400D01*
G01Y1676786D02*
Y1675880D01*
G01Y1678242D02*
Y1677337D01*
G01Y1680723D02*
Y1679817D01*
G01X-6693Y1662494D02*
Y1661904D01*
G01Y1660723D02*
Y1660132D01*
G01Y1660723D02*
Y1660132D01*
G01Y1662494D02*
Y1661904D01*
G01Y1664660D02*
Y1664069D01*
G01Y1666431D02*
Y1665841D01*
G01Y1664660D02*
Y1664069D01*
G01Y1666431D02*
Y1665841D01*
G01Y1668597D02*
Y1668006D01*
G01Y1670368D02*
Y1669778D01*
G01Y1670368D02*
Y1669778D01*
G01Y1668597D02*
Y1668006D01*
G01Y1672534D02*
Y1671943D01*
G01Y1674305D02*
Y1673715D01*
G01Y1676471D02*
Y1675880D01*
G01Y1674305D02*
Y1673715D01*
G01Y1676471D02*
Y1675880D01*
G01Y1672534D02*
Y1671943D01*
G01Y1678242D02*
Y1677652D01*
G01Y1680408D02*
Y1679817D01*
G01Y1678242D02*
Y1677652D01*
G01Y1680408D02*
Y1679817D01*
G01X-10530Y1664351D02*
Y1662213D01*
G01Y1664351D02*
Y1662213D01*
G01Y1672225D02*
Y1670087D01*
G01Y1668288D02*
Y1666150D01*
G01Y1672225D02*
Y1670087D01*
G01Y1668288D02*
Y1666150D01*
G01Y1676162D02*
Y1674024D01*
G01Y1676162D02*
Y1674024D01*
G01Y1680099D02*
Y1677961D01*
G01Y1680099D02*
Y1677961D01*
G01X-11842Y1678019D02*
Y1680040D01*
G01Y1674082D02*
Y1676103D01*
G01Y1670145D02*
Y1672166D01*
G01Y1666208D02*
Y1668229D01*
G01Y1662271D02*
Y1664292D01*
G01D02*
Y1662271D01*
G01Y1672166D02*
Y1670145D01*
G01Y1668229D02*
Y1666208D01*
G01Y1676103D02*
Y1674082D01*
G01Y1680040D02*
Y1678019D01*
G01X-12280Y1678025D02*
Y1680035D01*
G01Y1674088D02*
Y1676098D01*
G01Y1670151D02*
Y1672161D01*
G01Y1666214D02*
Y1668224D01*
G01Y1662277D02*
Y1664287D01*
G01D02*
Y1662277D01*
G01Y1668224D02*
Y1666214D01*
G01Y1672161D02*
Y1670151D01*
G01Y1676098D02*
Y1674088D01*
G01Y1680035D02*
Y1678025D01*
G01X-12992Y1660762D02*
Y1660447D01*
G01Y1662179D02*
Y1661864D01*
G01Y1664699D02*
Y1664384D01*
G01Y1666116D02*
Y1665801D01*
G01Y1668636D02*
Y1668321D01*
G01Y1670053D02*
Y1669738D01*
G01Y1672573D02*
Y1672258D01*
G01Y1676510D02*
Y1676195D01*
G01Y1673990D02*
Y1673675D01*
G01Y1680447D02*
Y1680132D01*
G01Y1677927D02*
Y1677612D01*
G01X-23684Y1678152D02*
Y1679908D01*
G01Y1674215D02*
Y1675971D01*
G01Y1670278D02*
Y1672034D01*
G01Y1666341D02*
Y1668097D01*
G01Y1662404D02*
Y1664160D01*
G01D02*
Y1662404D01*
G01Y1672034D02*
Y1670278D01*
G01Y1668097D02*
Y1666341D01*
G01Y1675971D02*
Y1674215D01*
G01Y1679908D02*
Y1678152D01*
G01X-10630Y1660368D02*
X-9843Y1660723D01*
G01D02*
X-10630Y1660368D01*
G01Y1664305D02*
X-9843Y1664660D01*
G01D02*
X-10630Y1664305D01*
G01X-3377Y1661825D02*
X-3150Y1662219D01*
G01X-3377Y1661825D02*
X-3150Y1662219D01*
G01X-3377Y1665762D02*
X-3150Y1666156D01*
G01X-3377Y1665762D02*
X-3150Y1666156D01*
G01X-3377Y1669699D02*
X-3150Y1670093D01*
G01X-3377Y1669699D02*
X-3150Y1670093D01*
G01X-3377Y1673636D02*
X-3150Y1674030D01*
G01X-3377Y1673636D02*
X-3150Y1674030D01*
G01X-3377Y1677573D02*
X-3150Y1677967D01*
G01X-3377Y1677573D02*
X-3150Y1677967D01*
G01X-10630Y1668242D02*
X-9843Y1668597D01*
G01D02*
X-10630Y1668242D01*
G01Y1672179D02*
X-9843Y1672534D01*
G01D02*
X-10630Y1672179D01*
G01Y1676116D02*
X-9843Y1676471D01*
G01D02*
X-10630Y1676116D01*
G01Y1680053D02*
X-9843Y1680408D01*
G01D02*
X-10630Y1680053D01*
G01X-3377Y1684423D02*
X-4258Y1684187D01*
G01X-3377Y1684423D02*
X-4258Y1684187D01*
G01X9842Y1698026D02*
X-9055Y1696854D01*
G01X-6693Y1684345D02*
X-4725Y1684660D01*
G01X-6693Y1684345D02*
X-4725Y1684660D01*
G01X0Y1684384D02*
X-12992D01*
G01X-9843Y1684345D02*
X-6693D01*
G01X-9843D02*
X-6693D01*
G01X-4725Y1684187D02*
X-4258D01*
G01X-4725D02*
X-4258D01*
G01X-3150Y1684030D02*
X-2196D01*
G01X-3150D02*
X-2196D01*
G01X-4725Y1683754D02*
X-6693D01*
G01X-4725D02*
X-6693D01*
G01X-4725Y1682179D02*
X-6693D01*
G01X-4725D02*
X-6693D01*
G01X-2196Y1681904D02*
X-3150D01*
G01X-2196D02*
X-3150D01*
G01X-4258Y1681746D02*
X-4725D01*
G01X-4258D02*
X-4725D01*
G01X-6693Y1681589D02*
X-9843D01*
G01X-6693D02*
X-9843D01*
G01X-12992Y1681549D02*
X0D01*
G01X-4725Y1681274D02*
X-6693Y1681589D01*
G01X-4725Y1681274D02*
X-6693Y1681589D01*
G01X-4258Y1681746D02*
X-3377Y1681510D01*
G01X-4258Y1681746D02*
X-3377Y1681510D01*
G01X-9843Y1681589D02*
X-10630Y1681943D01*
G01D02*
X-9843Y1681589D01*
G01X-3150Y1684030D02*
X-3377Y1684423D01*
G01X-3150Y1684030D02*
X-3377Y1684423D01*
G01X-3756Y1684069D02*
Y1681864D01*
G01X-4725Y1681274D02*
Y1682179D01*
G01Y1683754D02*
Y1684660D01*
G01Y1682179D02*
Y1681274D01*
G01Y1684660D02*
Y1683754D01*
G01X-6693Y1682179D02*
Y1681589D01*
G01Y1684345D02*
Y1683754D01*
G01Y1682179D02*
Y1681589D01*
G01Y1684345D02*
Y1683754D01*
G01X-9055Y1694876D02*
Y1714167D01*
G01X-10530Y1684036D02*
Y1681898D01*
G01Y1684036D02*
Y1681898D01*
G01X-11842Y1681956D02*
Y1683977D01*
G01D02*
Y1681956D01*
G01X-12280Y1681962D02*
Y1683972D01*
G01D02*
Y1681962D01*
G01X-12992Y1681864D02*
Y1681549D01*
G01Y1684384D02*
Y1684069D01*
G01X-23684Y1682089D02*
Y1683845D01*
G01D02*
Y1682089D01*
G01X-3377Y1681510D02*
X-3150Y1681904D01*
G01X-3377Y1681510D02*
X-3150Y1681904D01*
G01X-10630Y1683990D02*
X-9843Y1684345D01*
G01D02*
X-10630Y1683990D01*
G01X-9055Y1706303D02*
X9842Y1705900D01*
G01X24803Y1714167D02*
X-9055D01*
G01Y1734654D02*
X24803D01*
G01X9842Y1742921D02*
X-9055Y1742134D01*
G01Y1734654D02*
Y1753945D01*
G01Y1751583D02*
X9842Y1750795D01*
G01X-4725Y1764855D02*
X-6693D01*
G01X-3150Y1764579D02*
X-2196D01*
G01X-4725Y1764422D02*
X-4258D01*
G01X-9843Y1764264D02*
X-6693D01*
G01X-12992Y1764240D02*
X0D01*
G01X-6544D02*
X-6693Y1764264D01*
G01X-4258Y1764422D02*
X-3582Y1764240D01*
G01X-10630Y1764619D02*
X-9843Y1764264D01*
G01X-3756Y1766760D02*
Y1764555D01*
G01X-4725Y1764240D02*
Y1764855D01*
G01X-6037Y1764555D02*
Y1764240D01*
G01X-6693Y1764855D02*
Y1764264D01*
G01X-9607Y1761819D02*
Y1807626D01*
G01X-10530Y1766711D02*
Y1764574D01*
G01X-11966Y1764634D02*
Y1766651D01*
G01X-12445Y1766646D02*
Y1764639D01*
G01X-12992Y1764555D02*
Y1764240D01*
G01X-23518Y1766522D02*
Y1764762D01*
G01X-3345Y1764240D02*
X-3150Y1764579D01*
G01X-6350Y1782823D02*
X-6693Y1782768D01*
G01X-6350Y1778886D02*
X-6693Y1778831D01*
G01X-6350Y1774949D02*
X-6693Y1774894D01*
G01X-6350Y1771012D02*
X-6693Y1770957D01*
G01X-3466Y1782823D02*
X-4258Y1782611D01*
G01X-3466Y1778886D02*
X-4258Y1778674D01*
G01X-3466Y1774949D02*
X-4258Y1774737D01*
G01X-3466Y1771012D02*
X-4258Y1770800D01*
G01X-3466Y1767075D02*
X-4258Y1766863D01*
G01X-3150Y1786390D02*
X-2196D01*
G01X-4725Y1786115D02*
X-6693D01*
G01X-4725Y1784540D02*
X-6693D01*
G01X-3150Y1784264D02*
X-2196D01*
G01X-4725Y1784107D02*
X-4258D01*
G01X-9843Y1783949D02*
X-6693D01*
G01X-12992Y1783925D02*
X0D01*
G01Y1782823D02*
X-12992D01*
G01X-6693Y1782768D02*
X-9843D01*
G01X-4258Y1782611D02*
X-4725D01*
G01X-3150Y1782453D02*
X-2196D01*
G01X-4725Y1782178D02*
X-6693D01*
G01X-4725Y1780603D02*
X-6693D01*
G01X-3150Y1780327D02*
X-2196D01*
G01X-4725Y1780170D02*
X-4258D01*
G01X-9843Y1780012D02*
X-6693D01*
G01X-12992Y1779988D02*
X0D01*
G01Y1778886D02*
X-12992D01*
G01X-6693Y1778831D02*
X-9843D01*
G01X-4258Y1778674D02*
X-4725D01*
G01X-3150Y1778516D02*
X-2196D01*
G01X-4725Y1778241D02*
X-6693D01*
G01X-4725Y1776666D02*
X-6693D01*
G01X-3150Y1776390D02*
X-2196D01*
G01X-4725Y1776233D02*
X-4258D01*
G01X-9843Y1776075D02*
X-6693D01*
G01X-12992Y1776051D02*
X0D01*
G01Y1774949D02*
X-12992D01*
G01X-6693Y1774894D02*
X-9843D01*
G01X-4258Y1774737D02*
X-4725D01*
G01X-3150Y1774579D02*
X-2196D01*
G01X-4725Y1774304D02*
X-6693D01*
G01X-4725Y1772729D02*
X-6693D01*
G01X-3150Y1772453D02*
X-2196D01*
G01X-4725Y1772296D02*
X-4258D01*
G01X-9843Y1772138D02*
X-6693D01*
G01X-12992Y1772114D02*
X0D01*
G01Y1771012D02*
X-12992D01*
G01X-6693Y1770957D02*
X-9843D01*
G01X-4258Y1770800D02*
X-4725D01*
G01X-3150Y1770642D02*
X-2196D01*
G01X-4725Y1770367D02*
X-6693D01*
G01X-4725Y1768792D02*
X-6693D01*
G01X-3150Y1768516D02*
X-2196D01*
G01X-4725Y1768359D02*
X-4258D01*
G01X-9843Y1768201D02*
X-6693D01*
G01X-12992Y1768177D02*
X0D01*
G01X-6350Y1767075D02*
X-6693Y1767020D01*
G01X0Y1767075D02*
X-12992D01*
G01X-6693Y1767020D02*
X-9843D01*
G01X-4258Y1766863D02*
X-4725D01*
G01X-3150Y1766705D02*
X-2196D01*
G01X-4725Y1766430D02*
X-6693D01*
G01X-4258Y1784107D02*
X-3582Y1783925D01*
G01X-4258Y1780170D02*
X-3582Y1779988D01*
G01X-6544Y1783925D02*
X-6693Y1783949D01*
G01X-6544Y1779988D02*
X-6693Y1780012D01*
G01X-6544Y1776051D02*
X-6693Y1776075D01*
G01X-6544Y1772114D02*
X-6693Y1772138D01*
G01X-6544Y1768177D02*
X-6693Y1768201D01*
G01X-4258Y1776233D02*
X-3582Y1776051D01*
G01X-4258Y1772296D02*
X-3582Y1772114D01*
G01X-4258Y1768359D02*
X-3582Y1768177D01*
G01X-10630Y1784304D02*
X-9843Y1783949D01*
G01X-10630Y1780367D02*
X-9843Y1780012D01*
G01X-10630Y1776430D02*
X-9843Y1776075D01*
G01X-10630Y1772493D02*
X-9843Y1772138D01*
G01X-10630Y1768556D02*
X-9843Y1768201D01*
G01X-3150Y1786390D02*
X-3363Y1786760D01*
G01X-3150Y1782453D02*
X-3363Y1782823D01*
G01X-3150Y1778516D02*
X-3363Y1778886D01*
G01X-3150Y1774579D02*
X-3363Y1774949D01*
G01X-3150Y1770642D02*
X-3363Y1771012D01*
G01X-3150Y1766705D02*
X-3363Y1767075D01*
G01X-3756Y1770697D02*
Y1768492D01*
G01Y1774634D02*
Y1772429D01*
G01Y1778571D02*
Y1776366D01*
G01Y1782508D02*
Y1780303D01*
G01Y1786445D02*
Y1784240D01*
G01X-4725Y1786115D02*
Y1786760D01*
G01Y1783925D02*
Y1784540D01*
G01Y1782178D02*
Y1782823D01*
G01Y1779988D02*
Y1780603D01*
G01Y1778241D02*
Y1778886D01*
G01Y1776051D02*
Y1776666D01*
G01Y1774304D02*
Y1774949D01*
G01Y1772114D02*
Y1772729D01*
G01Y1770367D02*
Y1771012D01*
G01Y1768177D02*
Y1768792D01*
G01Y1766430D02*
Y1767075D01*
G01X-6037Y1768492D02*
Y1768177D01*
G01Y1767075D02*
Y1766760D01*
G01Y1774949D02*
Y1774634D01*
G01Y1772429D02*
Y1772114D01*
G01Y1771012D02*
Y1770697D01*
G01Y1778886D02*
Y1778571D01*
G01Y1776366D02*
Y1776051D01*
G01Y1784240D02*
Y1783925D01*
G01Y1782823D02*
Y1782508D01*
G01Y1780303D02*
Y1779988D01*
G01Y1786760D02*
Y1786445D01*
G01X-6693Y1767020D02*
Y1766430D01*
G01Y1768792D02*
Y1768201D01*
G01Y1772729D02*
Y1772138D01*
G01Y1774894D02*
Y1774304D01*
G01Y1770957D02*
Y1770367D01*
G01Y1776666D02*
Y1776075D01*
G01Y1778831D02*
Y1778241D01*
G01Y1784540D02*
Y1783949D01*
G01Y1780603D02*
Y1780012D01*
G01Y1782768D02*
Y1782178D01*
G01Y1786705D02*
Y1786115D01*
G01X-10530Y1770648D02*
Y1768511D01*
G01Y1774585D02*
Y1772448D01*
G01Y1778522D02*
Y1776385D01*
G01Y1782459D02*
Y1780322D01*
G01Y1786396D02*
Y1784259D01*
G01X-11966Y1784319D02*
Y1786336D01*
G01Y1780382D02*
Y1782399D01*
G01Y1776445D02*
Y1778462D01*
G01Y1772508D02*
Y1774525D01*
G01Y1768571D02*
Y1770588D01*
G01X-12445Y1770583D02*
Y1768576D01*
G01Y1774520D02*
Y1772513D01*
G01Y1778457D02*
Y1776450D01*
G01Y1782394D02*
Y1780387D01*
G01Y1786331D02*
Y1784324D01*
G01X-12992Y1767075D02*
Y1766760D01*
G01Y1768492D02*
Y1768177D01*
G01Y1774949D02*
Y1774634D01*
G01Y1772429D02*
Y1772114D01*
G01Y1771012D02*
Y1770697D01*
G01Y1778886D02*
Y1778571D01*
G01Y1776366D02*
Y1776051D01*
G01Y1784240D02*
Y1783925D01*
G01Y1782823D02*
Y1782508D01*
G01Y1780303D02*
Y1779988D01*
G01Y1786760D02*
Y1786445D01*
G01X-23518Y1770459D02*
Y1768699D01*
G01Y1774396D02*
Y1772636D01*
G01Y1778333D02*
Y1776573D01*
G01Y1782270D02*
Y1780510D01*
G01Y1786207D02*
Y1784447D01*
G01X-3345Y1768177D02*
X-3150Y1768516D01*
G01X-3345Y1772114D02*
X-3150Y1772453D01*
G01X-3345Y1776051D02*
X-3150Y1776390D01*
G01X-3345Y1779988D02*
X-3150Y1780327D01*
G01X-3345Y1783925D02*
X-3150Y1784264D01*
G01X-10630Y1766666D02*
X-9843Y1767020D01*
G01X-10630Y1770603D02*
X-9843Y1770957D01*
G01X-10630Y1774540D02*
X-9843Y1774894D01*
G01Y1778831D02*
X-10630Y1778477D01*
G01X-9843Y1782768D02*
X-10630Y1782414D01*
G01X-9843Y1786705D02*
X-10630Y1786351D01*
G01X-6350Y1806445D02*
X-6693Y1806390D01*
G01X-6350Y1802508D02*
X-6693Y1802453D01*
G01X-6350Y1798571D02*
X-6693Y1798516D01*
G01X-6350Y1794634D02*
X-6693Y1794579D01*
G01X-6350Y1790697D02*
X-6693Y1790642D01*
G01X-6350Y1786760D02*
X-6693Y1786705D01*
G01X-3466Y1806445D02*
X-4258Y1806233D01*
G01X-3466Y1802508D02*
X-4258Y1802296D01*
G01X-3466Y1798571D02*
X-4258Y1798359D01*
G01X-3466Y1794634D02*
X-4258Y1794422D01*
G01X-3466Y1790697D02*
X-4258Y1790485D01*
G01X-3466Y1786760D02*
X-4258Y1786548D01*
G01X0Y1806445D02*
X-12992D01*
G01X-6693Y1806390D02*
X-9843D01*
G01X-4258Y1806233D02*
X-4725D01*
G01X-3150Y1806075D02*
X-2196D01*
G01X-4725Y1805800D02*
X-6693D01*
G01X-4725Y1804225D02*
X-6693D01*
G01X-3150Y1803949D02*
X-2196D01*
G01X-4725Y1803792D02*
X-4258D01*
G01X-9843Y1803634D02*
X-6693D01*
G01X-12992Y1803610D02*
X0D01*
G01Y1802508D02*
X-12992D01*
G01X-6693Y1802453D02*
X-9843D01*
G01X-4258Y1802296D02*
X-4725D01*
G01X-3150Y1802138D02*
X-2196D01*
G01X-4725Y1801863D02*
X-6693D01*
G01X-4725Y1800288D02*
X-6693D01*
G01X-3150Y1800012D02*
X-2196D01*
G01X-4725Y1799855D02*
X-4258D01*
G01X-9843Y1799697D02*
X-6693D01*
G01X-12992Y1799673D02*
X0D01*
G01Y1798571D02*
X-12992D01*
G01X-6693Y1798516D02*
X-9843D01*
G01X-4258Y1798359D02*
X-4725D01*
G01X-3150Y1798201D02*
X-2196D01*
G01X-4725Y1797926D02*
X-6693D01*
G01X-4725Y1796351D02*
X-6693D01*
G01X-3150Y1796075D02*
X-2196D01*
G01X-4725Y1795918D02*
X-4258D01*
G01X-9843Y1795760D02*
X-6693D01*
G01X-12992Y1795736D02*
X0D01*
G01Y1794634D02*
X-12992D01*
G01X-6693Y1794579D02*
X-9843D01*
G01X-4258Y1794422D02*
X-4725D01*
G01X-3150Y1794264D02*
X-2196D01*
G01X-4725Y1793989D02*
X-6693D01*
G01X-4725Y1792414D02*
X-6693D01*
G01X-3150Y1792138D02*
X-2196D01*
G01X-4725Y1791981D02*
X-4258D01*
G01X-9843Y1791823D02*
X-6693D01*
G01X-12992Y1791799D02*
X0D01*
G01Y1790697D02*
X-12992D01*
G01X-6693Y1790642D02*
X-9843D01*
G01X-4258Y1790485D02*
X-4725D01*
G01X-3150Y1790327D02*
X-2196D01*
G01X-4725Y1790052D02*
X-6693D01*
G01X-4725Y1788477D02*
X-6693D01*
G01X-3150Y1788201D02*
X-2196D01*
G01X-4725Y1788044D02*
X-4258D01*
G01X-9843Y1787886D02*
X-6693D01*
G01X-12992Y1787862D02*
X0D01*
G01Y1786760D02*
X-12992D01*
G01X-6693Y1786705D02*
X-9843D01*
G01X-4258Y1786548D02*
X-4725D01*
G01X-6544Y1803610D02*
X-6693Y1803634D01*
G01X-6544Y1799673D02*
X-6693Y1799697D01*
G01X-6544Y1795736D02*
X-6693Y1795760D01*
G01X-6544Y1791799D02*
X-6693Y1791823D01*
G01X-6544Y1787862D02*
X-6693Y1787886D01*
G01X-4258Y1803792D02*
X-3582Y1803610D01*
G01X-4258Y1799855D02*
X-3582Y1799673D01*
G01X-4258Y1795918D02*
X-3582Y1795736D01*
G01X-4258Y1791981D02*
X-3582Y1791799D01*
G01X-4258Y1788044D02*
X-3582Y1787862D01*
G01X-10630Y1803989D02*
X-9843Y1803634D01*
G01X-10630Y1800052D02*
X-9843Y1799697D01*
G01X-10630Y1796115D02*
X-9843Y1795760D01*
G01X-10630Y1792178D02*
X-9843Y1791823D01*
G01X-10630Y1788241D02*
X-9843Y1787886D01*
G01X-3150Y1806075D02*
X-3363Y1806445D01*
G01X-3150Y1802138D02*
X-3363Y1802508D01*
G01X-3150Y1798201D02*
X-3363Y1798571D01*
G01X-3150Y1794264D02*
X-3363Y1794634D01*
G01X-3150Y1790327D02*
X-3363Y1790697D01*
G01X-3756Y1790382D02*
Y1788177D01*
G01Y1798256D02*
Y1796051D01*
G01Y1794319D02*
Y1792114D01*
G01Y1802193D02*
Y1799988D01*
G01Y1806130D02*
Y1803925D01*
G01X-4725Y1803610D02*
Y1804225D01*
G01Y1805800D02*
Y1806445D01*
G01Y1799673D02*
Y1800288D01*
G01Y1801863D02*
Y1802508D01*
G01Y1793989D02*
Y1794634D01*
G01Y1795736D02*
Y1796351D01*
G01Y1797926D02*
Y1798571D01*
G01Y1791799D02*
Y1792414D01*
G01Y1790052D02*
Y1790697D01*
G01Y1787862D02*
Y1788477D01*
G01X-6037Y1788177D02*
Y1787862D01*
G01Y1792114D02*
Y1791799D01*
G01Y1790697D02*
Y1790382D01*
G01Y1794634D02*
Y1794319D01*
G01Y1796051D02*
Y1795736D01*
G01Y1798571D02*
Y1798256D01*
G01Y1799988D02*
Y1799673D01*
G01Y1802508D02*
Y1802193D01*
G01Y1803925D02*
Y1803610D01*
G01Y1806445D02*
Y1806130D01*
G01X-6693Y1788477D02*
Y1787886D01*
G01Y1792414D02*
Y1791823D01*
G01Y1790642D02*
Y1790052D01*
G01Y1794579D02*
Y1793989D01*
G01Y1798516D02*
Y1797926D01*
G01Y1796351D02*
Y1795760D01*
G01Y1802453D02*
Y1801863D01*
G01Y1800288D02*
Y1799697D01*
G01Y1806390D02*
Y1805800D01*
G01Y1804225D02*
Y1803634D01*
G01X-10530Y1790333D02*
Y1788196D01*
G01Y1794270D02*
Y1792133D01*
G01Y1798207D02*
Y1796070D01*
G01Y1802144D02*
Y1800007D01*
G01Y1806081D02*
Y1803944D01*
G01X-11966Y1804004D02*
Y1806021D01*
G01Y1800067D02*
Y1802084D01*
G01Y1796130D02*
Y1798147D01*
G01Y1792193D02*
Y1794210D01*
G01Y1788256D02*
Y1790273D01*
G01X-12445Y1794205D02*
Y1792198D01*
G01Y1790268D02*
Y1788261D01*
G01Y1798142D02*
Y1796135D01*
G01Y1802079D02*
Y1800072D01*
G01Y1806016D02*
Y1804009D01*
G01X-12992Y1788177D02*
Y1787862D01*
G01Y1792114D02*
Y1791799D01*
G01Y1790697D02*
Y1790382D01*
G01Y1794634D02*
Y1794319D01*
G01Y1796051D02*
Y1795736D01*
G01Y1798571D02*
Y1798256D01*
G01Y1799988D02*
Y1799673D01*
G01Y1802508D02*
Y1802193D01*
G01Y1803925D02*
Y1803610D01*
G01Y1806445D02*
Y1806130D01*
G01X-23518Y1794081D02*
Y1792321D01*
G01Y1790144D02*
Y1788384D01*
G01Y1798018D02*
Y1796258D01*
G01Y1801955D02*
Y1800195D01*
G01Y1805892D02*
Y1804132D01*
G01X-3345Y1787862D02*
X-3150Y1788201D01*
G01X-3345Y1791799D02*
X-3150Y1792138D01*
G01X-3345Y1795736D02*
X-3150Y1796075D01*
G01X-3345Y1799673D02*
X-3150Y1800012D01*
G01X-3345Y1803610D02*
X-3150Y1803949D01*
G01X-10630Y1790288D02*
X-9843Y1790642D01*
G01X-10630Y1794225D02*
X-9843Y1794579D01*
G01Y1798516D02*
X-10630Y1798162D01*
G01X-9843Y1802453D02*
X-10630Y1802099D01*
G01X-9843Y1806390D02*
X-10630Y1806036D01*
G01X-3466Y1826130D02*
X-4258Y1825918D01*
G01X-3466Y1822193D02*
X-4258Y1821981D01*
G01X-3466Y1818256D02*
X-4258Y1818044D01*
G01X-6350Y1826130D02*
X-6693Y1826075D01*
G01X-6350Y1822193D02*
X-6693Y1822138D01*
G01X-6350Y1818256D02*
X-6693Y1818201D01*
G01X-4725Y1827847D02*
X-6693D01*
G01X-3150Y1827571D02*
X-2196D01*
G01X-4725Y1827414D02*
X-4258D01*
G01X-9843Y1827256D02*
X-6693D01*
G01X-12992Y1827232D02*
X0D01*
G01Y1826130D02*
X-12992D01*
G01X-6693Y1826075D02*
X-9843D01*
G01X-4258Y1825918D02*
X-4725D01*
G01X-3150Y1825760D02*
X-2196D01*
G01X-4725Y1825485D02*
X-6693D01*
G01X-4725Y1823910D02*
X-6693D01*
G01X-3150Y1823634D02*
X-2196D01*
G01X-4725Y1823477D02*
X-4258D01*
G01X-9843Y1823319D02*
X-6693D01*
G01X-12992Y1823295D02*
X0D01*
G01Y1822193D02*
X-12992D01*
G01X-6693Y1822138D02*
X-9843D01*
G01X-4258Y1821981D02*
X-4725D01*
G01X-3150Y1821823D02*
X-2196D01*
G01X-4725Y1821548D02*
X-6693D01*
G01X-4725Y1819973D02*
X-6693D01*
G01X-3150Y1819697D02*
X-2196D01*
G01X-4725Y1819540D02*
X-4258D01*
G01X-9843Y1819382D02*
X-6693D01*
G01X-12992Y1819358D02*
X0D01*
G01Y1818256D02*
X-12992D01*
G01X-6693Y1818201D02*
X-9843D01*
G01X-4258Y1818044D02*
X-4725D01*
G01X-3150Y1817886D02*
X-2196D01*
G01X-4725Y1817611D02*
X-6693D01*
G01X-4725Y1816036D02*
X-6693D01*
G01X-3150Y1815760D02*
X-2196D01*
G01X-4725Y1815603D02*
X-4258D01*
G01X-9843Y1815445D02*
X-6693D01*
G01X-12992Y1815421D02*
X0D01*
G01X-6544Y1827232D02*
X-6693Y1827256D01*
G01X-6544Y1823295D02*
X-6693Y1823319D01*
G01X-6544Y1819358D02*
X-6693Y1819382D01*
G01X-6544Y1815421D02*
X-6693Y1815445D01*
G01X-4258Y1827414D02*
X-3582Y1827232D01*
G01X-4258Y1823477D02*
X-3582Y1823295D01*
G01X-4258Y1819540D02*
X-3582Y1819358D01*
G01X-4258Y1815603D02*
X-3582Y1815421D01*
G01X-10630Y1827611D02*
X-9843Y1827256D01*
G01X-10630Y1823674D02*
X-9843Y1823319D01*
G01X-10630Y1819737D02*
X-9843Y1819382D01*
G01X-10630Y1815800D02*
X-9843Y1815445D01*
G01X-3150Y1825760D02*
X-3363Y1826130D01*
G01X-3150Y1821823D02*
X-3363Y1822193D01*
G01X-3150Y1817886D02*
X-3363Y1818256D01*
G01X-3756Y1821878D02*
Y1819673D01*
G01Y1817941D02*
Y1815736D01*
G01Y1825815D02*
Y1823610D01*
G01Y1829752D02*
Y1827547D01*
G01X-4725Y1827232D02*
Y1827847D01*
G01Y1825485D02*
Y1826130D01*
G01Y1823295D02*
Y1823910D01*
G01Y1817611D02*
Y1818256D01*
G01Y1821548D02*
Y1822193D01*
G01Y1819358D02*
Y1819973D01*
G01Y1815421D02*
Y1816036D01*
G01X-6037Y1815736D02*
Y1815421D01*
G01Y1818256D02*
Y1817941D01*
G01Y1822193D02*
Y1821878D01*
G01Y1819673D02*
Y1819358D01*
G01Y1826130D02*
Y1825815D01*
G01Y1823610D02*
Y1823295D01*
G01Y1827547D02*
Y1827232D01*
G01X-6693Y1816036D02*
Y1815445D01*
G01Y1818201D02*
Y1817611D01*
G01Y1819973D02*
Y1819382D01*
G01Y1822138D02*
Y1821548D01*
G01Y1823910D02*
Y1823319D01*
G01Y1826075D02*
Y1825485D01*
G01Y1827847D02*
Y1827256D01*
G01X-9607Y1814437D02*
Y1844555D01*
G01X-10530Y1817892D02*
Y1815755D01*
G01Y1821829D02*
Y1819692D01*
G01Y1825766D02*
Y1823629D01*
G01Y1829703D02*
Y1827566D01*
G01X-11966Y1827626D02*
Y1829643D01*
G01Y1823689D02*
Y1825706D01*
G01Y1815815D02*
Y1817832D01*
G01Y1819752D02*
Y1821769D01*
G01X-12445Y1821764D02*
Y1819757D01*
G01Y1817827D02*
Y1815820D01*
G01Y1825701D02*
Y1823694D01*
G01Y1829638D02*
Y1827631D01*
G01X-12992Y1815736D02*
Y1815421D01*
G01Y1818256D02*
Y1817941D01*
G01Y1822193D02*
Y1821878D01*
G01Y1819673D02*
Y1819358D01*
G01Y1826130D02*
Y1825815D01*
G01Y1823610D02*
Y1823295D01*
G01Y1827547D02*
Y1827232D01*
G01X-23518Y1817703D02*
Y1815943D01*
G01Y1821640D02*
Y1819880D01*
G01Y1825577D02*
Y1823817D01*
G01Y1829514D02*
Y1827754D01*
G01X-3345Y1815421D02*
X-3150Y1815760D01*
G01X-3345Y1819358D02*
X-3150Y1819697D01*
G01X-3345Y1823295D02*
X-3150Y1823634D01*
G01X-3345Y1827232D02*
X-3150Y1827571D01*
G01X-10630Y1817847D02*
X-9843Y1818201D01*
G01Y1822138D02*
X-10630Y1821784D01*
G01X-9843Y1826075D02*
X-10630Y1825721D01*
G01X-3466Y1841878D02*
X-4258Y1841666D01*
G01X-3466Y1837941D02*
X-4258Y1837729D01*
G01X-3466Y1834004D02*
X-4258Y1833792D01*
G01X-3466Y1830067D02*
X-4258Y1829855D01*
G01X-6693Y1841823D02*
X-6350Y1841878D01*
G01Y1837941D02*
X-6693Y1837886D01*
G01X-6350Y1834004D02*
X-6693Y1833949D01*
G01X-6350Y1830067D02*
X-6693Y1830012D01*
G01X0Y1841878D02*
X-12992D01*
G01X-9843Y1841823D02*
X-6693D01*
G01X-4725Y1841666D02*
X-4258D01*
G01X-3150Y1841508D02*
X-2196D01*
G01X-4725Y1841233D02*
X-6693D01*
G01X-4725Y1839658D02*
X-6693D01*
G01X-3150Y1839382D02*
X-2196D01*
G01X-4258Y1839225D02*
X-4725D01*
G01X-6693Y1839067D02*
X-9843D01*
G01X-12992Y1839043D02*
X0D01*
G01Y1837941D02*
X-12992D01*
G01X-6693Y1837886D02*
X-9843D01*
G01X-4258Y1837729D02*
X-4725D01*
G01X-3150Y1837571D02*
X-2196D01*
G01X-4725Y1837296D02*
X-6693D01*
G01X-4725Y1835721D02*
X-6693D01*
G01X-3150Y1835445D02*
X-2196D01*
G01X-4725Y1835288D02*
X-4258D01*
G01X-9843Y1835130D02*
X-6693D01*
G01X-12992Y1835106D02*
X0D01*
G01Y1834004D02*
X-12992D01*
G01X-6693Y1833949D02*
X-9843D01*
G01X-4258Y1833792D02*
X-4725D01*
G01X-3150Y1833634D02*
X-2196D01*
G01X-4725Y1833359D02*
X-6693D01*
G01X-4725Y1831784D02*
X-6693D01*
G01X-3150Y1831508D02*
X-2196D01*
G01X-4725Y1831351D02*
X-4258D01*
G01X-9843Y1831193D02*
X-6693D01*
G01X-12992Y1831169D02*
X0D01*
G01Y1830067D02*
X-12992D01*
G01X-6693Y1830012D02*
X-9843D01*
G01X-4258Y1829855D02*
X-4725D01*
G01X-3150Y1829697D02*
X-2196D01*
G01X-4725Y1829422D02*
X-6693D01*
G01X-6544Y1839043D02*
X-6693Y1839067D01*
G01X-6544Y1835106D02*
X-6693Y1835130D01*
G01X-6544Y1831169D02*
X-6693Y1831193D01*
G01X-4258Y1839225D02*
X-3582Y1839043D01*
G01X-4258Y1835288D02*
X-3582Y1835106D01*
G01X-4258Y1831351D02*
X-3582Y1831169D01*
G01X-10630Y1839422D02*
X-9843Y1839067D01*
G01X-10630Y1835485D02*
X-9843Y1835130D01*
G01X-10630Y1831548D02*
X-9843Y1831193D01*
G01X-3150Y1841508D02*
X-3363Y1841878D01*
G01X-3150Y1837571D02*
X-3363Y1837941D01*
G01X-3150Y1833634D02*
X-3363Y1834004D01*
G01X-3150Y1829697D02*
X-3363Y1830067D01*
G01X-3756Y1833689D02*
Y1831484D01*
G01Y1837626D02*
Y1835421D01*
G01Y1841563D02*
Y1839358D01*
G01X-4725Y1841233D02*
Y1841878D01*
G01Y1837296D02*
Y1837941D01*
G01Y1839043D02*
Y1839658D01*
G01Y1833359D02*
Y1834004D01*
G01Y1835106D02*
Y1835721D01*
G01Y1829422D02*
Y1830067D01*
G01Y1831169D02*
Y1831784D01*
G01X-6037Y1830067D02*
Y1829752D01*
G01Y1831484D02*
Y1831169D01*
G01Y1834004D02*
Y1833689D01*
G01Y1835421D02*
Y1835106D01*
G01Y1837941D02*
Y1837626D01*
G01Y1839358D02*
Y1839043D01*
G01Y1841878D02*
Y1841563D01*
G01X-6693Y1830012D02*
Y1829422D01*
G01Y1831784D02*
Y1831193D01*
G01Y1833949D02*
Y1833359D01*
G01Y1835721D02*
Y1835130D01*
G01Y1837886D02*
Y1837296D01*
G01Y1839658D02*
Y1839067D01*
G01Y1841823D02*
Y1841233D01*
G01X-10530Y1833640D02*
Y1831503D01*
G01Y1837577D02*
Y1835440D01*
G01Y1841514D02*
Y1839377D01*
G01X-11966Y1839437D02*
Y1841454D01*
G01Y1835500D02*
Y1837517D01*
G01Y1831563D02*
Y1833580D01*
G01X-12445Y1833575D02*
Y1831568D01*
G01Y1837512D02*
Y1835505D01*
G01Y1841449D02*
Y1839442D01*
G01X-12992Y1830067D02*
Y1829752D01*
G01Y1831484D02*
Y1831169D01*
G01Y1834004D02*
Y1833689D01*
G01Y1835421D02*
Y1835106D01*
G01Y1837941D02*
Y1837626D01*
G01Y1839358D02*
Y1839043D01*
G01Y1841878D02*
Y1841563D01*
G01X-23518Y1833451D02*
Y1831691D01*
G01Y1837388D02*
Y1835628D01*
G01Y1841325D02*
Y1839566D01*
G01X-3345Y1831169D02*
X-3150Y1831508D01*
G01X-3345Y1835106D02*
X-3150Y1835445D01*
G01X-3345Y1839043D02*
X-3150Y1839382D01*
G01X-9843Y1830012D02*
X-10630Y1829658D01*
G01Y1833595D02*
X-9843Y1833949D01*
G01X-10630Y1837532D02*
X-9843Y1837886D01*
G01Y1841823D02*
X-10630Y1841469D01*
G01X9842Y1855520D02*
X-9055Y1854732D01*
G01Y1864181D02*
X9842Y1863394D01*
G01X-9055Y1871662D02*
Y1852370D01*
G01X-7874Y1889223D02*
Y1877953D01*
G01X0Y1889223D02*
G03X-7874I-3937J0D01*
G01X0D02*
G03X-7874I-3937J0D01*
G01X24803Y1871662D02*
X-9055D01*
G01X-7874Y1912843D02*
Y1962927D01*
G01Y1912843D02*
G03X0I3937J0D01*
G01X-7874D02*
G03X0I3937J0D01*
G01Y1962927D02*
G03X-7874I-3937J0D01*
G01X0D02*
G03X-7874I-3937J0D01*
G01Y1989582D02*
Y2064661D01*
G01Y1986547D02*
Y1992126D01*
G01Y1986547D02*
G03X0I3937J0D01*
G01X-7874D02*
G03X0I3937J0D01*
G01X-3937Y2068010D02*
X-11922D01*
X-10325Y2066813D01*
G01X-3937D02*
Y2069208D01*
G01Y2075995D02*
X-4070Y2076694D01*
X-4469Y2077493D01*
X-5134Y2077992D01*
X-6066Y2078191D01*
X-6998Y2077992D01*
X-7796Y2077393D01*
X-8196Y2076495D01*
Y2075496D01*
X-8462Y2074897D01*
X-9127Y2074398D01*
X-10059Y2074199D01*
X-10990Y2074498D01*
X-11656Y2075197D01*
X-11922Y2075995D01*
X-11656Y2076794D01*
X-10990Y2077493D01*
X-10059Y2077792D01*
X-9127Y2077592D01*
X-8462Y2077094D01*
X-8196Y2076495D01*
Y2075496D01*
X-7796Y2074598D01*
X-6998Y2073999D01*
X-6066Y2073800D01*
X-5134Y2073999D01*
X-4469Y2074498D01*
X-4070Y2075297D01*
X-3937Y2075995D01*
G01X-3671Y2083980D02*
X-3804Y2083781D01*
X-4070D01*
X-4203Y2083980D01*
X-4070Y2084180D01*
X-3804D01*
X-3671Y2083980D01*
G01X-11922Y2091965D02*
X-11656Y2091167D01*
X-10990Y2090568D01*
X-10192Y2090169D01*
X-9127Y2089869D01*
X-7929Y2089770D01*
X-6732Y2089869D01*
X-5667Y2090169D01*
X-4868Y2090568D01*
X-4203Y2091167D01*
X-3937Y2091965D01*
X-4203Y2092764D01*
X-4868Y2093363D01*
X-5667Y2093762D01*
X-6732Y2094062D01*
X-7929Y2094161D01*
X-9127Y2094062D01*
X-10192Y2093762D01*
X-10990Y2093363D01*
X-11656Y2092764D01*
X-11922Y2091965D01*
G01Y2099950D02*
X-11656Y2099152D01*
X-10990Y2098553D01*
X-10192Y2098154D01*
X-9127Y2097854D01*
X-7929Y2097755D01*
X-6732Y2097854D01*
X-5667Y2098154D01*
X-4868Y2098553D01*
X-4203Y2099152D01*
X-3937Y2099950D01*
X-4203Y2100749D01*
X-4868Y2101348D01*
X-5667Y2101747D01*
X-6732Y2102047D01*
X-7929Y2102146D01*
X-9127Y2102047D01*
X-10192Y2101747D01*
X-10990Y2101348D01*
X-11656Y2100749D01*
X-11922Y2099950D01*
G01X0Y3937D02*
G03X3937Y0I3937J0D01*
G01X0Y3937D02*
G03X3937Y0I3937J0D01*
G01X0Y3937D02*
Y340939D01*
G01Y3937D02*
Y340939D01*
G01X1029527Y0D02*
X3937D01*
G01X1029527D02*
X3937D01*
G01X45275Y309567D02*
G03I-15748J0D01*
G01X0Y340939D02*
Y409646D01*
G01Y340939D02*
Y409646D01*
G01Y340939D02*
Y360230D01*
G01Y338971D02*
X26771D01*
G01X13779Y353144D02*
G03I-3937J0D01*
G01X14370D02*
G03I-4528J0D01*
G01X0Y360230D02*
Y710624D01*
G01X24803Y366530D02*
X0D01*
G01X11313Y371884D02*
X11514Y371950D01*
G01X11246Y372278D02*
X11447Y372343D01*
G01X10174Y371950D02*
X9973Y371884D01*
G01X9906Y372278D02*
X10107Y372343D01*
G01X10978Y372081D02*
X11246Y372278D01*
G01X9638Y372081D02*
X9906Y372278D01*
G01X11179Y371753D02*
X11313Y371884D01*
G01X9973D02*
X9839Y371753D01*
G01X9437Y371818D02*
X9638Y372081D01*
G01X-1969Y373400D02*
X-2196Y373006D01*
G01X-1969Y373400D02*
X-2196Y373006D01*
G01X-1969Y377337D02*
X-2196Y376943D01*
G01X-1969Y377337D02*
X-2196Y376943D01*
G01X-1969Y381274D02*
X-2196Y380880D01*
G01X-1969Y381274D02*
X-2196Y380880D01*
G01X-1969Y385211D02*
X-2196Y384817D01*
G01X-1969Y385211D02*
X-2196Y384817D01*
G01X-1969Y389148D02*
X-2196Y388754D01*
G01X-1969Y389148D02*
X-2196Y388754D01*
G01X10911Y371950D02*
X10978Y372081D01*
G01X11112Y371556D02*
X11179Y371753D01*
G01X9839D02*
X9772Y371556D01*
G01X9370Y371490D02*
X9437Y371818D01*
G01X14580Y387022D02*
X15464Y387219D01*
G01X14580Y387022D02*
X15464Y387219D01*
G01X15078Y387022D02*
X15962Y387219D01*
G01D02*
X15078Y387022D01*
G01X14580Y383085D02*
X15464Y383282D01*
G01X14580Y383085D02*
X15464Y383282D01*
G01X15078Y383085D02*
X15962Y383282D01*
G01D02*
X15078Y383085D01*
G01X14580Y379148D02*
X15464Y379345D01*
G01X14580Y379148D02*
X15464Y379345D01*
G01X15078Y379148D02*
X15962Y379345D01*
G01D02*
X15078Y379148D01*
G01X14580Y375211D02*
X15464Y375408D01*
G01X14580Y375211D02*
X15464Y375408D01*
G01X15078Y375211D02*
X15962Y375408D01*
G01D02*
X15078Y375211D01*
G01X14580Y371274D02*
X15464Y371471D01*
G01X14580Y371274D02*
X15464Y371471D01*
G01X15078Y371274D02*
X15962Y371471D01*
G01D02*
X15078Y371274D01*
G01X15962Y387219D02*
Y388164D01*
G01Y383282D02*
Y384227D01*
G01Y379345D02*
Y380290D01*
G01Y375408D02*
Y376353D01*
G01Y371471D02*
Y372416D01*
G01D02*
Y371471D01*
G01Y376353D02*
Y375408D01*
G01Y380290D02*
Y379345D01*
G01Y384227D02*
Y383282D01*
G01Y388164D02*
Y387219D01*
G01X15464D02*
Y388164D01*
G01Y383282D02*
Y384227D01*
G01Y379345D02*
Y380290D01*
G01Y375408D02*
Y376353D01*
G01Y371471D02*
Y372416D01*
G01D02*
Y371471D01*
G01Y380290D02*
Y379345D01*
G01Y376353D02*
Y375408D01*
G01Y384227D02*
Y383282D01*
G01Y388164D02*
Y387219D01*
G01X13424Y387022D02*
Y388360D01*
G01Y383085D02*
Y384423D01*
G01Y375211D02*
Y376549D01*
G01Y379148D02*
Y380486D01*
G01Y371274D02*
Y372612D01*
G01D02*
Y371274D01*
G01Y380486D02*
Y379148D01*
G01Y376549D02*
Y375211D01*
G01Y384423D02*
Y383085D01*
G01Y388360D02*
Y387022D01*
G01X12601D02*
Y388360D01*
G01Y383085D02*
Y384423D01*
G01Y379148D02*
Y380486D01*
G01Y375211D02*
Y376549D01*
G01Y371274D02*
Y372612D01*
G01D02*
Y371274D01*
G01Y380486D02*
Y379148D01*
G01Y376549D02*
Y375211D01*
G01Y384423D02*
Y383085D01*
G01Y388360D02*
Y387022D01*
G01X12519Y373656D02*
Y373262D01*
G01Y371490D02*
Y369916D01*
G01X12117Y371556D02*
Y370309D01*
G01X11112D02*
Y371556D01*
G01X10710Y370309D02*
Y371556D01*
G01X9772D02*
Y370309D01*
G01X9370Y373262D02*
Y373656D01*
G01Y369916D02*
Y371490D01*
G01X8523Y372612D02*
Y371274D01*
G01Y372612D02*
Y371274D01*
G01Y380486D02*
Y379148D01*
G01Y376549D02*
Y375211D01*
G01Y376549D02*
Y375211D01*
G01Y380486D02*
Y379148D01*
G01Y384423D02*
Y383085D01*
G01Y384423D02*
Y383085D01*
G01Y388360D02*
Y387022D01*
G01Y388360D02*
Y387022D01*
G01X0Y390171D02*
Y390959D01*
G01Y388360D02*
Y389148D01*
G01Y386234D02*
Y387022D01*
G01Y384423D02*
Y385211D01*
G01Y380486D02*
Y381274D01*
G01Y382297D02*
Y383085D01*
G01Y376549D02*
Y377337D01*
G01Y378360D02*
Y379148D01*
G01Y372612D02*
Y373400D01*
G01Y370486D02*
Y371274D01*
G01Y374423D02*
Y375211D01*
G01Y371274D02*
Y370486D01*
G01Y375211D02*
Y374423D01*
G01Y373400D02*
Y372612D01*
G01Y379148D02*
Y378360D01*
G01Y377337D02*
Y376549D01*
G01Y383085D02*
Y382297D01*
G01Y381274D02*
Y380486D01*
G01Y385211D02*
Y384423D01*
G01Y387022D02*
Y386234D01*
G01Y389148D02*
Y388360D01*
G01Y390959D02*
Y390171D01*
G01X-984Y387022D02*
Y388360D01*
G01Y383085D02*
Y384423D01*
G01Y379148D02*
Y380486D01*
G01Y375211D02*
Y376549D01*
G01Y371274D02*
Y372612D01*
G01D02*
Y371274D01*
G01Y380486D02*
Y379148D01*
G01Y376549D02*
Y375211D01*
G01Y384423D02*
Y383085D01*
G01Y388360D02*
Y387022D01*
G01X-2251Y373360D02*
Y370526D01*
G01Y377297D02*
Y374463D01*
G01Y385171D02*
Y382337D01*
G01Y381234D02*
Y378400D01*
G01Y389108D02*
Y386274D01*
G01Y393045D02*
Y390211D01*
G01X-2520Y373045D02*
Y370841D01*
G01Y376982D02*
Y374778D01*
G01Y384856D02*
Y382652D01*
G01Y380919D02*
Y378715D01*
G01Y388793D02*
Y386589D01*
G01X12453Y371818D02*
X12519Y371490D01*
G01X-1969Y390171D02*
X0D01*
G01D02*
X-1969D01*
G01Y389148D02*
X0D01*
G01X-1969D02*
X0D01*
G01X12601Y388360D02*
X15078D01*
G01X-984D02*
X15078D01*
G01X8523D02*
X12601D01*
G01X0D02*
X8523D01*
G01X0D02*
X-984D01*
G01X15464Y388164D02*
X15962D01*
G01D02*
X15464D01*
G01Y387219D02*
X15962D01*
G01D02*
X15464D01*
G01X8523Y387022D02*
X15078D01*
G01X-984D02*
X0D01*
G01X8523D02*
X0D01*
G01X15078D02*
X-984D01*
G01X-1969Y386234D02*
X0D01*
G01D02*
X-1969D01*
G01Y385211D02*
X0D01*
G01X-1969D02*
X0D01*
G01X12601Y384423D02*
X15078D01*
G01X-984D02*
X15078D01*
G01X8523D02*
X12601D01*
G01X0D02*
X8523D01*
G01X0D02*
X-984D01*
G01X15464Y384227D02*
X15962D01*
G01D02*
X15464D01*
G01Y383282D02*
X15962D01*
G01D02*
X15464D01*
G01X8523Y383085D02*
X15078D01*
G01X-984D02*
X0D01*
G01X8523D02*
X0D01*
G01X15078D02*
X-984D01*
G01X-1969Y382297D02*
X0D01*
G01D02*
X-1969D01*
G01Y381274D02*
X0D01*
G01X-1969D02*
X0D01*
G01X12601Y380486D02*
X15078D01*
G01X-984D02*
X15078D01*
G01X8523D02*
X12601D01*
G01X0D02*
X8523D01*
G01X0D02*
X-984D01*
G01X15464Y380290D02*
X15962D01*
G01D02*
X15464D01*
G01Y379345D02*
X15962D01*
G01D02*
X15464D01*
G01X8523Y379148D02*
X15078D01*
G01X-984D02*
X0D01*
G01X8523D02*
X0D01*
G01X15078D02*
X-984D01*
G01X-1969Y378360D02*
X0D01*
G01D02*
X-1969D01*
G01Y377337D02*
X0D01*
G01X-1969D02*
X0D01*
G01X12601Y376549D02*
X15078D01*
G01X-984D02*
X15078D01*
G01X8523D02*
X12601D01*
G01X0D02*
X8523D01*
G01X0D02*
X-984D01*
G01X15464Y376353D02*
X15962D01*
G01D02*
X15464D01*
G01Y375408D02*
X15962D01*
G01D02*
X15464D01*
G01X8523Y375211D02*
X15078D01*
G01X-984D02*
X0D01*
G01X8523D02*
X0D01*
G01X15078D02*
X-984D01*
G01X-1969Y374423D02*
X0D01*
G01D02*
X-1969D01*
G01X9370Y373656D02*
X12519D01*
G01X-1969Y373400D02*
X0D01*
G01X-1969D02*
X0D01*
G01X12519Y373262D02*
X9906D01*
G01X10375Y372868D02*
X9839D01*
G01X12601Y372612D02*
X15078D01*
G01X-984D02*
X15078D01*
G01X8523D02*
X12601D01*
G01X0D02*
X8523D01*
G01X0D02*
X-984D01*
G01X15464Y372416D02*
X15962D01*
G01D02*
X15464D01*
G01X11447Y372343D02*
X11782D01*
G01X10107D02*
X10375D01*
G01X11514Y371950D02*
X11716D01*
G01X10308D02*
X10174D01*
G01X15464Y371471D02*
X15962D01*
G01D02*
X15464D01*
G01X8523Y371274D02*
X15078D01*
G01X-984D02*
X0D01*
G01X8523D02*
X0D01*
G01X15078D02*
X-984D01*
G01X-1969Y370486D02*
X0D01*
G01D02*
X-1969D01*
G01X9772Y370309D02*
X10710D01*
G01X12117D02*
X11112D01*
G01X12519Y369916D02*
X9370D01*
G01X12051Y371753D02*
X12117Y371556D01*
G01X10710D02*
X10643Y371753D01*
G01X10844Y372081D02*
X10911Y371950D01*
G01X11782Y372343D02*
X11983Y372278D01*
G01X11716Y371950D02*
X11916Y371884D01*
G01X10375Y372343D02*
X10576Y372278D01*
G01X15078Y388360D02*
X15962Y388164D01*
G01D02*
X15078Y388360D01*
G01X14580D02*
X15464Y388164D01*
G01X14580Y388360D02*
X15464Y388164D01*
G01X15078Y384423D02*
X15962Y384227D01*
G01D02*
X15078Y384423D01*
G01X14580D02*
X15464Y384227D01*
G01X14580Y384423D02*
X15464Y384227D01*
G01X15078Y380486D02*
X15962Y380290D01*
G01D02*
X15078Y380486D01*
G01X14580D02*
X15464Y380290D01*
G01X14580Y380486D02*
X15464Y380290D01*
G01X15078Y376549D02*
X15962Y376353D01*
G01D02*
X15078Y376549D01*
G01X14580D02*
X15464Y376353D01*
G01X14580Y376549D02*
X15464Y376353D01*
G01X15078Y372612D02*
X15962Y372416D01*
G01D02*
X15078Y372612D01*
G01X14580D02*
X15464Y372416D01*
G01X14580Y372612D02*
X15464Y372416D01*
G01X-2196Y390565D02*
X-1969Y390171D01*
G01X-2196Y390565D02*
X-1969Y390171D01*
G01X-2196Y386628D02*
X-1969Y386234D01*
G01X-2196Y386628D02*
X-1969Y386234D01*
G01X-2196Y382691D02*
X-1969Y382297D01*
G01X-2196Y382691D02*
X-1969Y382297D01*
G01X-2196Y378754D02*
X-1969Y378360D01*
G01X-2196Y378754D02*
X-1969Y378360D01*
G01X-2196Y374817D02*
X-1969Y374423D01*
G01X-2196Y374817D02*
X-1969Y374423D01*
G01X-2196Y370880D02*
X-1969Y370486D01*
G01X-2196Y370880D02*
X-1969Y370486D01*
G01X12251Y372081D02*
X12453Y371818D01*
G01X11916Y371884D02*
X12051Y371753D01*
G01X10643D02*
X10509Y371884D01*
G01X9906Y373262D02*
X10375Y372868D01*
G01X9839D02*
X9370Y373262D01*
G01X11983Y372278D02*
X12251Y372081D01*
G01X10576Y372278D02*
X10844Y372081D01*
G01X10509Y371884D02*
X10308Y371950D01*
G01X1168Y410814D02*
X0Y409646D01*
G01X1168Y410814D02*
X0Y409646D01*
G01X2336Y411982D02*
X1168Y410814D01*
G01X2336Y411982D02*
X1168Y410814D01*
G01X-1969Y393085D02*
X-2196Y392691D01*
G01X-1969Y393085D02*
X-2196Y392691D01*
G01X-1969Y397022D02*
X-2196Y396628D01*
G01X-1969Y397022D02*
X-2196Y396628D01*
G01X-1969Y400959D02*
X-2196Y400565D01*
G01X-1969Y400959D02*
X-2196Y400565D01*
G01X-1969Y404896D02*
X-2196Y404502D01*
G01X-1969Y404896D02*
X-2196Y404502D01*
G01X-1969Y408833D02*
X-2196Y408439D01*
G01X-1969Y408833D02*
X-2196Y408439D01*
G01X14580Y410644D02*
X15464Y410841D01*
G01X14580Y410644D02*
X15464Y410841D01*
G01X15078Y410644D02*
X15962Y410841D01*
G01D02*
X15078Y410644D01*
G01X14580Y406707D02*
X15464Y406904D01*
G01X14580Y406707D02*
X15464Y406904D01*
G01X15078Y406707D02*
X15962Y406904D01*
G01D02*
X15078Y406707D01*
G01X14580Y402770D02*
X15464Y402967D01*
G01X14580Y402770D02*
X15464Y402967D01*
G01X15078Y402770D02*
X15962Y402967D01*
G01D02*
X15078Y402770D01*
G01X14580Y398833D02*
X15464Y399030D01*
G01X14580Y398833D02*
X15464Y399030D01*
G01X15078Y398833D02*
X15962Y399030D01*
G01D02*
X15078Y398833D01*
G01X14580Y394896D02*
X15464Y395093D01*
G01X14580Y394896D02*
X15464Y395093D01*
G01X15078Y394896D02*
X15962Y395093D01*
G01D02*
X15078Y394896D01*
G01X14580Y390959D02*
X15464Y391156D01*
G01X14580Y390959D02*
X15464Y391156D01*
G01X15078Y390959D02*
X15962Y391156D01*
G01D02*
X15078Y390959D01*
G01X15962Y410841D02*
Y411786D01*
G01Y406904D02*
Y407849D01*
G01Y402967D02*
Y403912D01*
G01Y399030D02*
Y399975D01*
G01Y395093D02*
Y396038D01*
G01Y391156D02*
Y392101D01*
G01D02*
Y391156D01*
G01Y396038D02*
Y395093D01*
G01Y403912D02*
Y402967D01*
G01Y399975D02*
Y399030D01*
G01Y407849D02*
Y406904D01*
G01Y411786D02*
Y410841D01*
G01X15464D02*
Y411786D01*
G01Y406904D02*
Y407849D01*
G01Y402967D02*
Y403912D01*
G01Y399030D02*
Y399975D01*
G01Y395093D02*
Y396038D01*
G01Y391156D02*
Y392101D01*
G01D02*
Y391156D01*
G01Y396038D02*
Y395093D01*
G01Y403912D02*
Y402967D01*
G01Y399975D02*
Y399030D01*
G01Y407849D02*
Y406904D01*
G01Y411786D02*
Y410841D01*
G01X13424Y410644D02*
Y411982D01*
G01Y406707D02*
Y408045D01*
G01Y402770D02*
Y404108D01*
G01Y398833D02*
Y400171D01*
G01Y394896D02*
Y396234D01*
G01Y390959D02*
Y392297D01*
G01D02*
Y390959D01*
G01Y396234D02*
Y394896D01*
G01Y400171D02*
Y398833D01*
G01Y408045D02*
Y406707D01*
G01Y404108D02*
Y402770D01*
G01Y411982D02*
Y410644D01*
G01X12601D02*
Y411982D01*
G01Y406707D02*
Y408045D01*
G01Y402770D02*
Y404108D01*
G01Y398833D02*
Y400171D01*
G01Y394896D02*
Y396234D01*
G01Y390959D02*
Y392297D01*
G01D02*
Y390959D01*
G01Y396234D02*
Y394896D01*
G01Y400171D02*
Y398833D01*
G01Y408045D02*
Y406707D01*
G01Y404108D02*
Y402770D01*
G01Y411982D02*
Y410644D01*
G01X8523Y392297D02*
Y390959D01*
G01Y392297D02*
Y390959D01*
G01Y396234D02*
Y394896D01*
G01Y396234D02*
Y394896D01*
G01Y400171D02*
Y398833D01*
G01Y400171D02*
Y398833D01*
G01Y408045D02*
Y406707D01*
G01Y404108D02*
Y402770D01*
G01Y408045D02*
Y406707D01*
G01Y404108D02*
Y402770D01*
G01Y411982D02*
Y410644D01*
G01Y411982D02*
Y410644D01*
G01X0Y408045D02*
Y408833D01*
G01Y409856D02*
Y410644D01*
G01Y404108D02*
Y404896D01*
G01Y405919D02*
Y406707D01*
G01Y400171D02*
Y400959D01*
G01Y401982D02*
Y402770D01*
G01Y396234D02*
Y397022D01*
G01Y394108D02*
Y394896D01*
G01Y398045D02*
Y398833D01*
G01Y392297D02*
Y393085D01*
G01D02*
Y392297D01*
G01Y398833D02*
Y398045D01*
G01Y394896D02*
Y394108D01*
G01Y397022D02*
Y396234D01*
G01Y402770D02*
Y401982D01*
G01Y400959D02*
Y400171D01*
G01Y406707D02*
Y405919D01*
G01Y404896D02*
Y404108D01*
G01Y410644D02*
Y409856D01*
G01Y408833D02*
Y408045D01*
G01X-984Y410644D02*
Y411982D01*
G01Y406707D02*
Y408045D01*
G01Y402770D02*
Y404108D01*
G01Y398833D02*
Y400171D01*
G01Y394896D02*
Y396234D01*
G01Y390959D02*
Y392297D01*
G01D02*
Y390959D01*
G01Y396234D02*
Y394896D01*
G01Y400171D02*
Y398833D01*
G01Y408045D02*
Y406707D01*
G01Y404108D02*
Y402770D01*
G01Y411982D02*
Y410644D01*
G01X-2251Y396982D02*
Y394148D01*
G01Y400919D02*
Y398085D01*
G01Y404856D02*
Y402022D01*
G01Y412730D02*
Y409896D01*
G01Y408793D02*
Y405959D01*
G01X-2520Y392730D02*
Y390526D01*
G01Y396667D02*
Y394463D01*
G01Y400604D02*
Y398400D01*
G01Y408478D02*
Y406274D01*
G01Y404541D02*
Y402337D01*
G01Y412416D02*
Y410211D01*
G01X15464Y410841D02*
X15962D01*
G01D02*
X15464D01*
G01X8523Y410644D02*
X15078D01*
G01X-984D02*
X0D01*
G01X8523D02*
X0D01*
G01X15078D02*
X-984D01*
G01X-1969Y409856D02*
X0D01*
G01D02*
X-1969D01*
G01Y408833D02*
X0D01*
G01X-1969D02*
X0D01*
G01X12601Y408045D02*
X15078D01*
G01X-984D02*
X15078D01*
G01X8523D02*
X12601D01*
G01X0D02*
X8523D01*
G01X0D02*
X-984D01*
G01X15464Y407849D02*
X15962D01*
G01D02*
X15464D01*
G01Y406904D02*
X15962D01*
G01D02*
X15464D01*
G01X8523Y406707D02*
X15078D01*
G01X-984D02*
X0D01*
G01X8523D02*
X0D01*
G01X15078D02*
X-984D01*
G01X-1969Y405919D02*
X0D01*
G01D02*
X-1969D01*
G01Y404896D02*
X0D01*
G01X-1969D02*
X0D01*
G01X12601Y404108D02*
X15078D01*
G01X-984D02*
X15078D01*
G01X8523D02*
X12601D01*
G01X0D02*
X8523D01*
G01X0D02*
X-984D01*
G01X15464Y403912D02*
X15962D01*
G01D02*
X15464D01*
G01Y402967D02*
X15962D01*
G01D02*
X15464D01*
G01X8523Y402770D02*
X15078D01*
G01X-984D02*
X0D01*
G01X8523D02*
X0D01*
G01X15078D02*
X-984D01*
G01X-1969Y401982D02*
X0D01*
G01D02*
X-1969D01*
G01Y400959D02*
X0D01*
G01X-1969D02*
X0D01*
G01X12601Y400171D02*
X15078D01*
G01X-984D02*
X15078D01*
G01X8523D02*
X12601D01*
G01X0D02*
X8523D01*
G01X0D02*
X-984D01*
G01X15464Y399975D02*
X15962D01*
G01D02*
X15464D01*
G01Y399030D02*
X15962D01*
G01D02*
X15464D01*
G01X8523Y398833D02*
X15078D01*
G01X-984D02*
X0D01*
G01X8523D02*
X0D01*
G01X15078D02*
X-984D01*
G01X-1969Y398045D02*
X0D01*
G01D02*
X-1969D01*
G01Y397022D02*
X0D01*
G01X-1969D02*
X0D01*
G01X12601Y396234D02*
X15078D01*
G01X-984D02*
X15078D01*
G01X8523D02*
X12601D01*
G01X0D02*
X8523D01*
G01X0D02*
X-984D01*
G01X15464Y396038D02*
X15962D01*
G01D02*
X15464D01*
G01Y395093D02*
X15962D01*
G01D02*
X15464D01*
G01X8523Y394896D02*
X15078D01*
G01X-984D02*
X0D01*
G01X8523D02*
X0D01*
G01X15078D02*
X-984D01*
G01X-1969Y394108D02*
X0D01*
G01D02*
X-1969D01*
G01Y393085D02*
X0D01*
G01X-1969D02*
X0D01*
G01X12601Y392297D02*
X15078D01*
G01X-984D02*
X15078D01*
G01X8523D02*
X12601D01*
G01X0D02*
X8523D01*
G01X0D02*
X-984D01*
G01X15464Y392101D02*
X15962D01*
G01D02*
X15464D01*
G01Y391156D02*
X15962D01*
G01D02*
X15464D01*
G01X8523Y390959D02*
X15078D01*
G01X-984D02*
X0D01*
G01X8523D02*
X0D01*
G01X15078D02*
X-984D01*
G01X-2196Y410250D02*
X-1969Y409856D01*
G01X-2196Y410250D02*
X-1969Y409856D01*
G01X-2196Y406313D02*
X-1969Y405919D01*
G01X-2196Y406313D02*
X-1969Y405919D01*
G01X-2196Y402376D02*
X-1969Y401982D01*
G01X-2196Y402376D02*
X-1969Y401982D01*
G01X-2196Y398439D02*
X-1969Y398045D01*
G01X-2196Y398439D02*
X-1969Y398045D01*
G01X15078Y408045D02*
X15962Y407849D01*
G01D02*
X15078Y408045D01*
G01X14580D02*
X15464Y407849D01*
G01X14580Y408045D02*
X15464Y407849D01*
G01X15078Y404108D02*
X15962Y403912D01*
G01D02*
X15078Y404108D01*
G01X14580D02*
X15464Y403912D01*
G01X14580Y404108D02*
X15464Y403912D01*
G01X15078Y400171D02*
X15962Y399975D01*
G01D02*
X15078Y400171D01*
G01X14580D02*
X15464Y399975D01*
G01X14580Y400171D02*
X15464Y399975D01*
G01X15078Y396234D02*
X15962Y396038D01*
G01D02*
X15078Y396234D01*
G01X14580D02*
X15464Y396038D01*
G01X14580Y396234D02*
X15464Y396038D01*
G01X15078Y392297D02*
X15962Y392101D01*
G01D02*
X15078Y392297D01*
G01X14580D02*
X15464Y392101D01*
G01X14580Y392297D02*
X15464Y392101D01*
G01X-2196Y394502D02*
X-1969Y394108D01*
G01X-2196Y394502D02*
X-1969Y394108D01*
G01X18701Y414829D02*
X15551Y413695D01*
G01X3937Y413583D02*
X2336Y411982D01*
G01X3937Y413583D02*
X2336Y411982D01*
G01X-1969Y412770D02*
X-2196Y412376D01*
G01X-1969Y412770D02*
X-2196Y412376D01*
G01X-1969Y424581D02*
X-2196Y424187D01*
G01X-1969Y424581D02*
X-2196Y424187D01*
G01X-1969Y428518D02*
X-2196Y428124D01*
G01X-1969Y428518D02*
X-2196Y428124D01*
G01X-1969Y432455D02*
X-2196Y432061D01*
G01X-1969Y432455D02*
X-2196Y432061D01*
G01X14580Y430329D02*
X15464Y430526D01*
G01X14580Y430329D02*
X15464Y430526D01*
G01X15078Y430329D02*
X15962Y430526D01*
G01D02*
X15078Y430329D01*
G01X14580Y426392D02*
X15464Y426589D01*
G01X14580Y426392D02*
X15464Y426589D01*
G01X15078Y426392D02*
X15962Y426589D01*
G01D02*
X15078Y426392D01*
G01X14580Y422455D02*
X15464Y422652D01*
G01X14580Y422455D02*
X15464Y422652D01*
G01X15078Y422455D02*
X15962Y422652D01*
G01D02*
X15078Y422455D01*
G01X15962Y430526D02*
Y431471D01*
G01Y426589D02*
Y427534D01*
G01Y422652D02*
Y423597D01*
G01D02*
Y422652D01*
G01Y427534D02*
Y426589D01*
G01Y431471D02*
Y430526D01*
G01X15551Y420703D02*
Y413695D01*
G01X15464Y430526D02*
Y431471D01*
G01Y426589D02*
Y427534D01*
G01Y422652D02*
Y423597D01*
G01D02*
Y422652D01*
G01Y431471D02*
Y430526D01*
G01Y427534D02*
Y426589D01*
G01X13424Y426392D02*
Y427730D01*
G01Y430329D02*
Y431667D01*
G01Y422455D02*
Y423793D01*
G01D02*
Y422455D01*
G01Y431667D02*
Y430329D01*
G01Y427730D02*
Y426392D01*
G01X12601Y430329D02*
Y431667D01*
G01Y426392D02*
Y427730D01*
G01Y422455D02*
Y423793D01*
G01D02*
Y422455D01*
G01Y431667D02*
Y430329D01*
G01Y427730D02*
Y426392D01*
G01X8523Y423793D02*
Y422455D01*
G01Y423793D02*
Y422455D01*
G01Y431667D02*
Y430329D01*
G01Y427730D02*
Y426392D01*
G01Y427730D02*
Y426392D01*
G01Y431667D02*
Y430329D01*
G01X0Y425000D02*
Y729916D01*
G01Y425000D02*
Y729916D01*
G01Y431667D02*
Y432455D01*
G01Y427730D02*
Y428518D01*
G01Y429541D02*
Y430329D01*
G01Y423793D02*
Y424581D01*
G01Y425604D02*
Y426392D01*
G01Y421667D02*
Y422455D01*
G01Y411982D02*
Y412770D01*
G01D02*
Y411982D01*
G01Y422455D02*
Y421667D01*
G01Y426392D02*
Y425604D01*
G01Y424581D02*
Y423793D01*
G01Y430329D02*
Y429541D01*
G01Y428518D02*
Y427730D01*
G01Y432455D02*
Y431667D01*
G01X-984Y430329D02*
Y431667D01*
G01Y426392D02*
Y427730D01*
G01Y422455D02*
Y423793D01*
G01D02*
Y422455D01*
G01Y431667D02*
Y430329D01*
G01Y427730D02*
Y426392D01*
G01X-2251Y424541D02*
Y421707D01*
G01Y428478D02*
Y425644D01*
G01Y432416D02*
Y429581D01*
G01X-2520Y424227D02*
Y422022D01*
G01Y428164D02*
Y425959D01*
G01Y432101D02*
Y429896D01*
G01X-1969Y432455D02*
X0D01*
G01X-1969D02*
X0D01*
G01X12601Y431667D02*
X15078D01*
G01X-984D02*
X15078D01*
G01X8523D02*
X12601D01*
G01X0D02*
X8523D01*
G01X0D02*
X-984D01*
G01X15464Y431471D02*
X15962D01*
G01D02*
X15464D01*
G01Y430526D02*
X15962D01*
G01D02*
X15464D01*
G01X8523Y430329D02*
X15078D01*
G01X-984D02*
X0D01*
G01X8523D02*
X0D01*
G01X15078D02*
X-984D01*
G01X-1969Y429541D02*
X0D01*
G01D02*
X-1969D01*
G01Y428518D02*
X0D01*
G01X-1969D02*
X0D01*
G01X12601Y427730D02*
X15078D01*
G01X-984D02*
X15078D01*
G01X8523D02*
X12601D01*
G01X0D02*
X8523D01*
G01X0D02*
X-984D01*
G01X15464Y427534D02*
X15962D01*
G01D02*
X15464D01*
G01Y426589D02*
X15962D01*
G01D02*
X15464D01*
G01X8523Y426392D02*
X15078D01*
G01X-984D02*
X0D01*
G01X8523D02*
X0D01*
G01X15078D02*
X-984D01*
G01X-1969Y425604D02*
X0D01*
G01D02*
X-1969D01*
G01Y424581D02*
X0D01*
G01X-1969D02*
X0D01*
G01X12601Y423793D02*
X15078D01*
G01X-984D02*
X15078D01*
G01X8523D02*
X12601D01*
G01X0D02*
X8523D01*
G01X0D02*
X-984D01*
G01X15464Y423597D02*
X15962D01*
G01D02*
X15464D01*
G01Y422652D02*
X15962D01*
G01D02*
X15464D01*
G01X8523Y422455D02*
X15078D01*
G01X-984D02*
X0D01*
G01X8523D02*
X0D01*
G01X15078D02*
X-984D01*
G01X-1969Y421667D02*
X0D01*
G01D02*
X-1969D01*
G01X3937Y421063D02*
X19882D01*
G01X3937D02*
X19882D01*
G01X0Y420703D02*
X15551D01*
G01X3937Y413695D02*
X0D01*
G01X15551D02*
X3937D01*
G01Y413583D02*
X19882D01*
G01X3937D02*
X19882D01*
G01X-1969Y412770D02*
X0D01*
G01X-1969D02*
X0D01*
G01X12601Y411982D02*
X15078D01*
G01X-984D02*
X15078D01*
G01X8523D02*
X12601D01*
G01X0D02*
X8523D01*
G01X0D02*
X-984D01*
G01X15464Y411786D02*
X15962D01*
G01D02*
X15464D01*
G01X15078Y431667D02*
X15962Y431471D01*
G01D02*
X15078Y431667D01*
G01X14580D02*
X15464Y431471D01*
G01X14580Y431667D02*
X15464Y431471D01*
G01X15078Y427730D02*
X15962Y427534D01*
G01D02*
X15078Y427730D01*
G01X14580D02*
X15464Y427534D01*
G01X14580Y427730D02*
X15464Y427534D01*
G01X15078Y423793D02*
X15962Y423597D01*
G01D02*
X15078Y423793D01*
G01X14580D02*
X15464Y423597D01*
G01X14580Y423793D02*
X15464Y423597D01*
G01X-2196Y429935D02*
X-1969Y429541D01*
G01X-2196Y429935D02*
X-1969Y429541D01*
G01X-2196Y425998D02*
X-1969Y425604D01*
G01X-2196Y425998D02*
X-1969Y425604D01*
G01X-2196Y422061D02*
X-1969Y421667D01*
G01X-2196Y422061D02*
X-1969Y421667D01*
G01X15551Y420703D02*
X18701Y419569D01*
G01X15078Y411982D02*
X15962Y411786D01*
G01D02*
X15078Y411982D01*
G01X14580D02*
X15464Y411786D01*
G01X14580Y411982D02*
X15464Y411786D01*
G01X2545Y422455D02*
X3937Y421063D01*
G01X0Y425000D02*
X1206Y423793D01*
G01X2545Y422455D02*
X3937Y421063D01*
G01X0Y425000D02*
X1206Y423793D01*
G01D02*
X2545Y422455D01*
G01X1206Y423793D02*
X2545Y422455D01*
G01X-1969Y436392D02*
X-2196Y435998D01*
G01X-1969Y436392D02*
X-2196Y435998D01*
G01X-1969Y440329D02*
X-2196Y439935D01*
G01X-1969Y440329D02*
X-2196Y439935D01*
G01X-1969Y444266D02*
X-2196Y443872D01*
G01X-1969Y444266D02*
X-2196Y443872D01*
G01X-1969Y448203D02*
X-2196Y447809D01*
G01X-1969Y448203D02*
X-2196Y447809D01*
G01X-1969Y452140D02*
X-2196Y451746D01*
G01X-1969Y452140D02*
X-2196Y451746D01*
G01X14580Y453951D02*
X15464Y454148D01*
G01X14580Y453951D02*
X15464Y454148D01*
G01X15078Y453951D02*
X15962Y454148D01*
G01D02*
X15078Y453951D01*
G01X14580Y450014D02*
X15464Y450211D01*
G01X14580Y450014D02*
X15464Y450211D01*
G01X15078Y450014D02*
X15962Y450211D01*
G01D02*
X15078Y450014D01*
G01X14580Y446077D02*
X15464Y446274D01*
G01X14580Y446077D02*
X15464Y446274D01*
G01X15078Y446077D02*
X15962Y446274D01*
G01D02*
X15078Y446077D01*
G01X14580Y442140D02*
X15464Y442337D01*
G01X14580Y442140D02*
X15464Y442337D01*
G01X15078Y442140D02*
X15962Y442337D01*
G01D02*
X15078Y442140D01*
G01X14580Y438203D02*
X15464Y438400D01*
G01X14580Y438203D02*
X15464Y438400D01*
G01X15078Y438203D02*
X15962Y438400D01*
G01D02*
X15078Y438203D01*
G01X14580Y434266D02*
X15464Y434463D01*
G01X14580Y434266D02*
X15464Y434463D01*
G01X15078Y434266D02*
X15962Y434463D01*
G01D02*
X15078Y434266D01*
G01X15962Y450211D02*
Y451156D01*
G01Y446274D02*
Y447219D01*
G01Y442337D02*
Y443282D01*
G01Y438400D02*
Y439345D01*
G01Y434463D02*
Y435408D01*
G01D02*
Y434463D01*
G01Y439345D02*
Y438400D01*
G01Y443282D02*
Y442337D01*
G01Y447219D02*
Y446274D01*
G01Y451156D02*
Y450211D01*
G01X15464D02*
Y451156D01*
G01Y446274D02*
Y447219D01*
G01Y442337D02*
Y443282D01*
G01Y438400D02*
Y439345D01*
G01Y434463D02*
Y435408D01*
G01D02*
Y434463D01*
G01Y439345D02*
Y438400D01*
G01Y443282D02*
Y442337D01*
G01Y447219D02*
Y446274D01*
G01Y451156D02*
Y450211D01*
G01X13424Y450014D02*
Y451353D01*
G01Y453951D02*
Y455290D01*
G01Y446077D02*
Y447416D01*
G01Y442140D02*
Y443478D01*
G01Y438203D02*
Y439541D01*
G01Y434266D02*
Y435604D01*
G01D02*
Y434266D01*
G01Y439541D02*
Y438203D01*
G01Y443478D02*
Y442140D01*
G01Y447416D02*
Y446077D01*
G01Y455290D02*
Y453951D01*
G01Y451353D02*
Y450014D01*
G01X12601D02*
Y451353D01*
G01Y453951D02*
Y455290D01*
G01Y446077D02*
Y447416D01*
G01Y442140D02*
Y443478D01*
G01Y438203D02*
Y439541D01*
G01Y434266D02*
Y435604D01*
G01D02*
Y434266D01*
G01Y439541D02*
Y438203D01*
G01Y443478D02*
Y442140D01*
G01Y447416D02*
Y446077D01*
G01Y455290D02*
Y453951D01*
G01Y451353D02*
Y450014D01*
G01X8523Y435604D02*
Y434266D01*
G01Y435604D02*
Y434266D01*
G01Y439541D02*
Y438203D01*
G01Y439541D02*
Y438203D01*
G01Y443478D02*
Y442140D01*
G01Y443478D02*
Y442140D01*
G01Y447416D02*
Y446077D01*
G01Y447416D02*
Y446077D01*
G01Y451353D02*
Y450014D01*
G01Y455290D02*
Y453951D01*
G01Y451353D02*
Y450014D01*
G01Y455290D02*
Y453951D01*
G01X0Y451353D02*
Y452140D01*
G01Y453164D02*
Y453951D01*
G01Y447416D02*
Y448203D01*
G01Y445290D02*
Y446077D01*
G01Y449227D02*
Y450014D01*
G01Y443478D02*
Y444266D01*
G01Y441353D02*
Y442140D01*
G01Y439541D02*
Y440329D01*
G01Y437416D02*
Y438203D01*
G01Y435604D02*
Y436392D01*
G01Y433478D02*
Y434266D01*
G01D02*
Y433478D01*
G01Y436392D02*
Y435604D01*
G01Y438203D02*
Y437416D01*
G01Y440329D02*
Y439541D01*
G01Y442140D02*
Y441353D01*
G01Y444266D02*
Y443478D01*
G01Y450014D02*
Y449227D01*
G01Y446077D02*
Y445290D01*
G01Y448203D02*
Y447416D01*
G01Y453951D02*
Y453164D01*
G01Y452140D02*
Y451353D01*
G01X-984Y453951D02*
Y455290D01*
G01Y450014D02*
Y451353D01*
G01Y446077D02*
Y447416D01*
G01Y442140D02*
Y443478D01*
G01Y438203D02*
Y439541D01*
G01Y434266D02*
Y435604D01*
G01D02*
Y434266D01*
G01Y439541D02*
Y438203D01*
G01Y443478D02*
Y442140D01*
G01Y447416D02*
Y446077D01*
G01Y455290D02*
Y453951D01*
G01Y451353D02*
Y450014D01*
G01X-2251Y436353D02*
Y433518D01*
G01Y440290D02*
Y437455D01*
G01Y444227D02*
Y441392D01*
G01Y448164D02*
Y445329D01*
G01Y452101D02*
Y449266D01*
G01Y456038D02*
Y453203D01*
G01X-2520Y436038D02*
Y433833D01*
G01Y439975D02*
Y437770D01*
G01Y443912D02*
Y441707D01*
G01Y447849D02*
Y445644D01*
G01Y451786D02*
Y449581D01*
G01Y455723D02*
Y453518D01*
G01X8523Y453951D02*
X15078D01*
G01X-984D02*
X0D01*
G01X8523D02*
X0D01*
G01X15078D02*
X-984D01*
G01X-1969Y453164D02*
X0D01*
G01D02*
X-1969D01*
G01Y452140D02*
X0D01*
G01X-1969D02*
X0D01*
G01X12601Y451353D02*
X15078D01*
G01X-984D02*
X15078D01*
G01X8523D02*
X12601D01*
G01X0D02*
X8523D01*
G01X0D02*
X-984D01*
G01X15464Y451156D02*
X15962D01*
G01D02*
X15464D01*
G01Y450211D02*
X15962D01*
G01D02*
X15464D01*
G01X8523Y450014D02*
X15078D01*
G01X-984D02*
X0D01*
G01X8523D02*
X0D01*
G01X15078D02*
X-984D01*
G01X-1969Y449227D02*
X0D01*
G01D02*
X-1969D01*
G01Y448203D02*
X0D01*
G01X-1969D02*
X0D01*
G01X12601Y447416D02*
X15078D01*
G01X-984D02*
X15078D01*
G01X8523D02*
X12601D01*
G01X0D02*
X8523D01*
G01X0D02*
X-984D01*
G01X15464Y447219D02*
X15962D01*
G01D02*
X15464D01*
G01Y446274D02*
X15962D01*
G01D02*
X15464D01*
G01X8523Y446077D02*
X15078D01*
G01X-984D02*
X0D01*
G01X8523D02*
X0D01*
G01X15078D02*
X-984D01*
G01X-1969Y445290D02*
X0D01*
G01D02*
X-1969D01*
G01Y444266D02*
X0D01*
G01X-1969D02*
X0D01*
G01X12601Y443478D02*
X15078D01*
G01X-984D02*
X15078D01*
G01X8523D02*
X12601D01*
G01X0D02*
X8523D01*
G01X0D02*
X-984D01*
G01X15464Y443282D02*
X15962D01*
G01D02*
X15464D01*
G01Y442337D02*
X15962D01*
G01D02*
X15464D01*
G01X8523Y442140D02*
X15078D01*
G01X-984D02*
X0D01*
G01X8523D02*
X0D01*
G01X15078D02*
X-984D01*
G01X-1969Y441353D02*
X0D01*
G01D02*
X-1969D01*
G01Y440329D02*
X0D01*
G01X-1969D02*
X0D01*
G01X12601Y439541D02*
X15078D01*
G01X-984D02*
X15078D01*
G01X8523D02*
X12601D01*
G01X0D02*
X8523D01*
G01X0D02*
X-984D01*
G01X15464Y439345D02*
X15962D01*
G01D02*
X15464D01*
G01Y438400D02*
X15962D01*
G01D02*
X15464D01*
G01X8523Y438203D02*
X15078D01*
G01X-984D02*
X0D01*
G01X8523D02*
X0D01*
G01X15078D02*
X-984D01*
G01X-1969Y437416D02*
X0D01*
G01D02*
X-1969D01*
G01Y436392D02*
X0D01*
G01X-1969D02*
X0D01*
G01X12601Y435604D02*
X15078D01*
G01X-984D02*
X15078D01*
G01X8523D02*
X12601D01*
G01X0D02*
X8523D01*
G01X0D02*
X-984D01*
G01X15464Y435408D02*
X15962D01*
G01D02*
X15464D01*
G01Y434463D02*
X15962D01*
G01D02*
X15464D01*
G01X8523Y434266D02*
X15078D01*
G01X-984D02*
X0D01*
G01X8523D02*
X0D01*
G01X15078D02*
X-984D01*
G01X-1969Y433478D02*
X0D01*
G01D02*
X-1969D01*
G01X15078Y451353D02*
X15962Y451156D01*
G01D02*
X15078Y451353D01*
G01X14580D02*
X15464Y451156D01*
G01X14580Y451353D02*
X15464Y451156D01*
G01X15078Y447416D02*
X15962Y447219D01*
G01D02*
X15078Y447416D01*
G01X14580D02*
X15464Y447219D01*
G01X14580Y447416D02*
X15464Y447219D01*
G01X15078Y443478D02*
X15962Y443282D01*
G01D02*
X15078Y443478D01*
G01X14580D02*
X15464Y443282D01*
G01X14580Y443478D02*
X15464Y443282D01*
G01X15078Y439541D02*
X15962Y439345D01*
G01D02*
X15078Y439541D01*
G01X14580D02*
X15464Y439345D01*
G01X14580Y439541D02*
X15464Y439345D01*
G01X15078Y435604D02*
X15962Y435408D01*
G01D02*
X15078Y435604D01*
G01X14580D02*
X15464Y435408D01*
G01X14580Y435604D02*
X15464Y435408D01*
G01X-2196Y453557D02*
X-1969Y453164D01*
G01X-2196Y453557D02*
X-1969Y453164D01*
G01X-2196Y449620D02*
X-1969Y449227D01*
G01X-2196Y449620D02*
X-1969Y449227D01*
G01X-2196Y445683D02*
X-1969Y445290D01*
G01X-2196Y445683D02*
X-1969Y445290D01*
G01X-2196Y441746D02*
X-1969Y441353D01*
G01X-2196Y441746D02*
X-1969Y441353D01*
G01X-2196Y437809D02*
X-1969Y437416D01*
G01X-2196Y437809D02*
X-1969Y437416D01*
G01X-2196Y433872D02*
X-1969Y433478D01*
G01X-2196Y433872D02*
X-1969Y433478D01*
G01Y456077D02*
X-2196Y455683D01*
G01X-1969Y456077D02*
X-2196Y455683D01*
G01X-1969Y460014D02*
X-2196Y459620D01*
G01X-1969Y460014D02*
X-2196Y459620D01*
G01X-1969Y463951D02*
X-2196Y463557D01*
G01X-1969Y463951D02*
X-2196Y463557D01*
G01X-1969Y467888D02*
X-2196Y467494D01*
G01X-1969Y467888D02*
X-2196Y467494D01*
G01X-1969Y471825D02*
X-2196Y471431D01*
G01X-1969Y471825D02*
X-2196Y471431D01*
G01X14580Y473636D02*
X15464Y473833D01*
G01X14580Y473636D02*
X15464Y473833D01*
G01X15078Y473636D02*
X15962Y473833D01*
G01D02*
X15078Y473636D01*
G01X14580Y469699D02*
X15464Y469896D01*
G01X14580Y469699D02*
X15464Y469896D01*
G01X15078Y469699D02*
X15962Y469896D01*
G01D02*
X15078Y469699D01*
G01X14580Y465762D02*
X15464Y465959D01*
G01X14580Y465762D02*
X15464Y465959D01*
G01X15078Y465762D02*
X15962Y465959D01*
G01D02*
X15078Y465762D01*
G01X14580Y461825D02*
X15464Y462022D01*
G01X14580Y461825D02*
X15464Y462022D01*
G01X15078Y461825D02*
X15962Y462022D01*
G01D02*
X15078Y461825D01*
G01X14580Y457888D02*
X15464Y458085D01*
G01X14580Y457888D02*
X15464Y458085D01*
G01X15078Y457888D02*
X15962Y458085D01*
G01D02*
X15078Y457888D01*
G01X12601Y474975D02*
X15078D01*
G01X-984D02*
X15078D01*
G01X8523D02*
X12601D01*
G01X0D02*
X8523D01*
G01X0D02*
X-984D01*
G01X15464Y474778D02*
X15962D01*
G01D02*
X15464D01*
G01Y473833D02*
X15962D01*
G01D02*
X15464D01*
G01X8523Y473636D02*
X15078D01*
G01X-984D02*
X0D01*
G01X8523D02*
X0D01*
G01X15078D02*
X-984D01*
G01X15962Y473833D02*
Y474778D01*
G01Y469896D02*
Y470841D01*
G01Y465959D02*
Y466904D01*
G01Y462022D02*
Y462967D01*
G01Y458085D02*
Y459030D01*
G01Y454148D02*
Y455093D01*
G01D02*
Y454148D01*
G01Y459030D02*
Y458085D01*
G01Y462967D02*
Y462022D01*
G01Y466904D02*
Y465959D01*
G01Y470841D02*
Y469896D01*
G01Y474778D02*
Y473833D01*
G01X15464D02*
Y474778D01*
G01Y469896D02*
Y470841D01*
G01Y465959D02*
Y466904D01*
G01Y462022D02*
Y462967D01*
G01Y458085D02*
Y459030D01*
G01Y454148D02*
Y455093D01*
G01D02*
Y454148D01*
G01Y459030D02*
Y458085D01*
G01Y462967D02*
Y462022D01*
G01Y466904D02*
Y465959D01*
G01Y470841D02*
Y469896D01*
G01Y474778D02*
Y473833D01*
G01X13424Y473636D02*
Y474975D01*
G01Y469699D02*
Y471038D01*
G01Y465762D02*
Y467101D01*
G01Y461825D02*
Y463164D01*
G01Y457888D02*
Y459227D01*
G01D02*
Y457888D01*
G01Y463164D02*
Y461825D01*
G01Y467101D02*
Y465762D01*
G01Y471038D02*
Y469699D01*
G01Y474975D02*
Y473636D01*
G01X12601D02*
Y474975D01*
G01Y469699D02*
Y471038D01*
G01Y465762D02*
Y467101D01*
G01Y461825D02*
Y463164D01*
G01Y457888D02*
Y459227D01*
G01D02*
Y457888D01*
G01Y463164D02*
Y461825D01*
G01Y467101D02*
Y465762D01*
G01Y471038D02*
Y469699D01*
G01Y474975D02*
Y473636D01*
G01X8523Y459227D02*
Y457888D01*
G01Y459227D02*
Y457888D01*
G01Y463164D02*
Y461825D01*
G01Y463164D02*
Y461825D01*
G01Y467101D02*
Y465762D01*
G01Y467101D02*
Y465762D01*
G01Y471038D02*
Y469699D01*
G01Y471038D02*
Y469699D01*
G01Y474975D02*
Y473636D01*
G01Y474975D02*
Y473636D01*
G01X0Y474975D02*
Y475762D01*
G01Y471038D02*
Y471825D01*
G01Y468912D02*
Y469699D01*
G01Y472849D02*
Y473636D01*
G01Y467101D02*
Y467888D01*
G01Y464975D02*
Y465762D01*
G01Y463164D02*
Y463951D01*
G01Y461038D02*
Y461825D01*
G01Y455290D02*
Y456077D01*
G01Y459227D02*
Y460014D01*
G01Y457101D02*
Y457888D01*
G01D02*
Y457101D01*
G01Y456077D02*
Y455290D01*
G01Y460014D02*
Y459227D01*
G01Y461825D02*
Y461038D01*
G01Y463951D02*
Y463164D01*
G01Y465762D02*
Y464975D01*
G01Y467888D02*
Y467101D01*
G01Y469699D02*
Y468912D01*
G01Y473636D02*
Y472849D01*
G01Y471825D02*
Y471038D01*
G01Y475762D02*
Y474975D01*
G01X-984Y473636D02*
Y474975D01*
G01Y469699D02*
Y471038D01*
G01Y465762D02*
Y467101D01*
G01Y461825D02*
Y463164D01*
G01Y457888D02*
Y459227D01*
G01D02*
Y457888D01*
G01Y463164D02*
Y461825D01*
G01Y467101D02*
Y465762D01*
G01Y471038D02*
Y469699D01*
G01Y474975D02*
Y473636D01*
G01X-2251Y459975D02*
Y457140D01*
G01Y463912D02*
Y461077D01*
G01Y467849D02*
Y465014D01*
G01Y471786D02*
Y468951D01*
G01Y475723D02*
Y472888D01*
G01X-2520Y459660D02*
Y457455D01*
G01Y463597D02*
Y461392D01*
G01Y467534D02*
Y465329D01*
G01Y471471D02*
Y469266D01*
G01Y475408D02*
Y473203D01*
G01X-1969Y472849D02*
X0D01*
G01D02*
X-1969D01*
G01Y471825D02*
X0D01*
G01X-1969D02*
X0D01*
G01X15078Y471038D02*
X12601D01*
G01X-984D02*
X15078D01*
G01X8523D02*
X12601D01*
G01X0D02*
X8523D01*
G01X0D02*
X-984D01*
G01X15464Y470841D02*
X15962D01*
G01D02*
X15464D01*
G01Y469896D02*
X15962D01*
G01D02*
X15464D01*
G01X8523Y469699D02*
X15078D01*
G01X-984D02*
X0D01*
G01X8523D02*
X0D01*
G01X15078D02*
X-984D01*
G01X-1969Y468912D02*
X0D01*
G01D02*
X-1969D01*
G01Y467888D02*
X0D01*
G01X-1969D02*
X0D01*
G01X12601Y467101D02*
X15078D01*
G01X-984D02*
X15078D01*
G01X8523D02*
X12601D01*
G01X0D02*
X8523D01*
G01X0D02*
X-984D01*
G01X15464Y466904D02*
X15962D01*
G01D02*
X15464D01*
G01Y465959D02*
X15962D01*
G01D02*
X15464D01*
G01X8523Y465762D02*
X15078D01*
G01X-984D02*
X0D01*
G01X8523D02*
X0D01*
G01X15078D02*
X-984D01*
G01X-1969Y464975D02*
X0D01*
G01D02*
X-1969D01*
G01Y463951D02*
X0D01*
G01X-1969D02*
X0D01*
G01X12601Y463164D02*
X15078D01*
G01X-984D02*
X15078D01*
G01X8523D02*
X12601D01*
G01X0D02*
X8523D01*
G01X0D02*
X-984D01*
G01X15464Y462967D02*
X15962D01*
G01D02*
X15464D01*
G01Y462022D02*
X15962D01*
G01D02*
X15464D01*
G01X8523Y461825D02*
X15078D01*
G01X-984D02*
X0D01*
G01X8523D02*
X0D01*
G01X15078D02*
X-984D01*
G01X-1969Y461038D02*
X0D01*
G01D02*
X-1969D01*
G01Y460014D02*
X0D01*
G01X-1969D02*
X0D01*
G01X12601Y459227D02*
X15078D01*
G01X-984D02*
X15078D01*
G01X8523D02*
X12601D01*
G01X0D02*
X8523D01*
G01X0D02*
X-984D01*
G01X15464Y459030D02*
X15962D01*
G01D02*
X15464D01*
G01Y458085D02*
X15962D01*
G01D02*
X15464D01*
G01X8523Y457888D02*
X15078D01*
G01X-984D02*
X0D01*
G01X8523D02*
X0D01*
G01X15078D02*
X-984D01*
G01X-1969Y457101D02*
X0D01*
G01D02*
X-1969D01*
G01Y456077D02*
X0D01*
G01X-1969D02*
X0D01*
G01X12601Y455290D02*
X15078D01*
G01X-984D02*
X15078D01*
G01X8523D02*
X12601D01*
G01X0D02*
X8523D01*
G01X0D02*
X-984D01*
G01X15464Y455093D02*
X15962D01*
G01D02*
X15464D01*
G01Y454148D02*
X15962D01*
G01D02*
X15464D01*
G01X15078Y474975D02*
X15962Y474778D01*
G01D02*
X15078Y474975D01*
G01X14580D02*
X15464Y474778D01*
G01X14580Y474975D02*
X15464Y474778D01*
G01X15078Y471038D02*
X15962Y470841D01*
G01D02*
X15078Y471038D01*
G01X14580D02*
X15464Y470841D01*
G01X14580Y471038D02*
X15464Y470841D01*
G01X15078Y467101D02*
X15962Y466904D01*
G01D02*
X15078Y467101D01*
G01X14580D02*
X15464Y466904D01*
G01X14580Y467101D02*
X15464Y466904D01*
G01X15078Y463164D02*
X15962Y462967D01*
G01D02*
X15078Y463164D01*
G01X14580D02*
X15464Y462967D01*
G01X14580Y463164D02*
X15464Y462967D01*
G01X15078Y459227D02*
X15962Y459030D01*
G01D02*
X15078Y459227D01*
G01X14580D02*
X15464Y459030D01*
G01X14580Y459227D02*
X15464Y459030D01*
G01X15078Y455290D02*
X15962Y455093D01*
G01D02*
X15078Y455290D01*
G01X14580D02*
X15464Y455093D01*
G01X14580Y455290D02*
X15464Y455093D01*
G01X-2196Y473242D02*
X-1969Y472849D01*
G01X-2196Y473242D02*
X-1969Y472849D01*
G01X-2196Y469305D02*
X-1969Y468912D01*
G01X-2196Y469305D02*
X-1969Y468912D01*
G01X-2196Y465368D02*
X-1969Y464975D01*
G01X-2196Y465368D02*
X-1969Y464975D01*
G01X-2196Y461431D02*
X-1969Y461038D01*
G01X-2196Y461431D02*
X-1969Y461038D01*
G01X-2196Y457494D02*
X-1969Y457101D01*
G01X-2196Y457494D02*
X-1969Y457101D01*
G01Y475762D02*
X-2196Y475368D01*
G01X-1969Y475762D02*
X-2196Y475368D01*
G01X-1969Y479699D02*
X-2196Y479305D01*
G01X-1969Y479699D02*
X-2196Y479305D01*
G01X-1969Y483636D02*
X-2196Y483242D01*
G01X-1969Y483636D02*
X-2196Y483242D01*
G01X-1969Y487573D02*
X-2196Y487179D01*
G01X-1969Y487573D02*
X-2196Y487179D01*
G01X-1969Y491510D02*
X-2196Y491116D01*
G01X-1969Y491510D02*
X-2196Y491116D01*
G01X-1969Y495447D02*
X-2196Y495053D01*
G01X-1969Y495447D02*
X-2196Y495053D01*
G01X14580Y493321D02*
X15464Y493518D01*
G01X14580Y493321D02*
X15464Y493518D01*
G01X15078Y493321D02*
X15962Y493518D01*
G01D02*
X15078Y493321D01*
G01X14580Y489384D02*
X15464Y489581D01*
G01X14580Y489384D02*
X15464Y489581D01*
G01X15078Y489384D02*
X15962Y489581D01*
G01D02*
X15078Y489384D01*
G01X14580Y485447D02*
X15464Y485644D01*
G01X14580Y485447D02*
X15464Y485644D01*
G01X15078Y485447D02*
X15962Y485644D01*
G01D02*
X15078Y485447D01*
G01X14580Y481510D02*
X15464Y481707D01*
G01X14580Y481510D02*
X15464Y481707D01*
G01X15078Y481510D02*
X15962Y481707D01*
G01D02*
X15078Y481510D01*
G01X14580Y477573D02*
X15464Y477770D01*
G01X14580Y477573D02*
X15464Y477770D01*
G01X15078Y477573D02*
X15962Y477770D01*
G01D02*
X15078Y477573D01*
G01X-1969Y495447D02*
X0D01*
G01X-1969D02*
X0D01*
G01X12601Y494660D02*
X15078D01*
G01X-984D02*
X15078D01*
G01X8523D02*
X12601D01*
G01X0D02*
X8523D01*
G01X0D02*
X-984D01*
G01X15464Y494463D02*
X15962D01*
G01D02*
X15464D01*
G01Y493518D02*
X15962D01*
G01D02*
X15464D01*
G01X8523Y493321D02*
X15078D01*
G01X-984D02*
X0D01*
G01X8523D02*
X0D01*
G01X15078D02*
X-984D01*
G01X-1969Y492534D02*
X0D01*
G01D02*
X-1969D01*
G01Y491510D02*
X0D01*
G01X-1969D02*
X0D01*
G01X12601Y490723D02*
X15078D01*
G01X-984D02*
X15078D01*
G01X8523D02*
X12601D01*
G01X0D02*
X8523D01*
G01X0D02*
X-984D01*
G01X15464Y490526D02*
X15962D01*
G01D02*
X15464D01*
G01Y489581D02*
X15962D01*
G01D02*
X15464D01*
G01X8523Y489384D02*
X15078D01*
G01X-984D02*
X0D01*
G01X8523D02*
X0D01*
G01X15078D02*
X-984D01*
G01X-1969Y488597D02*
X0D01*
G01D02*
X-1969D01*
G01Y487573D02*
X0D01*
G01X-1969D02*
X0D01*
G01X12601Y486786D02*
X15078D01*
G01X-984D02*
X15078D01*
G01X8523D02*
X12601D01*
G01X0D02*
X8523D01*
G01X0D02*
X-984D01*
G01X15464Y486589D02*
X15962D01*
G01D02*
X15464D01*
G01Y485644D02*
X15962D01*
G01D02*
X15464D01*
G01X8523Y485447D02*
X15078D01*
G01X-984D02*
X0D01*
G01X8523D02*
X0D01*
G01X15078D02*
X-984D01*
G01X-1969Y484660D02*
X0D01*
G01D02*
X-1969D01*
G01Y483636D02*
X0D01*
G01X-1969D02*
X0D01*
G01X12601Y482849D02*
X15078D01*
G01X-984D02*
X15078D01*
G01X8523D02*
X12601D01*
G01X0D02*
X8523D01*
G01X0D02*
X-984D01*
G01X15464Y482652D02*
X15962D01*
G01D02*
X15464D01*
G01Y481707D02*
X15962D01*
G01D02*
X15464D01*
G01X8523Y481510D02*
X15078D01*
G01X-984D02*
X0D01*
G01X8523D02*
X0D01*
G01X15078D02*
X-984D01*
G01X-1969Y480723D02*
X0D01*
G01D02*
X-1969D01*
G01Y479699D02*
X0D01*
G01X-1969D02*
X0D01*
G01X12601Y478912D02*
X15078D01*
G01X-984D02*
X15078D01*
G01X8523D02*
X12601D01*
G01X0D02*
X8523D01*
G01X0D02*
X-984D01*
G01X15464Y478715D02*
X15962D01*
G01D02*
X15464D01*
G01Y477770D02*
X15962D01*
G01D02*
X15464D01*
G01X8523Y477573D02*
X15078D01*
G01X-984D02*
X0D01*
G01X8523D02*
X0D01*
G01X15078D02*
X-984D01*
G01X-1969Y476786D02*
X0D01*
G01D02*
X-1969D01*
G01Y475762D02*
X0D01*
G01X-1969D02*
X0D01*
G01X15962Y493518D02*
Y494463D01*
G01Y489581D02*
Y490526D01*
G01Y485644D02*
Y486589D01*
G01Y481707D02*
Y482652D01*
G01Y477770D02*
Y478715D01*
G01D02*
Y477770D01*
G01Y482652D02*
Y481707D01*
G01Y486589D02*
Y485644D01*
G01Y490526D02*
Y489581D01*
G01Y494463D02*
Y493518D01*
G01X15464D02*
Y494463D01*
G01Y489581D02*
Y490526D01*
G01Y485644D02*
Y486589D01*
G01Y481707D02*
Y482652D01*
G01Y477770D02*
Y478715D01*
G01D02*
Y477770D01*
G01Y482652D02*
Y481707D01*
G01Y486589D02*
Y485644D01*
G01Y490526D02*
Y489581D01*
G01Y494463D02*
Y493518D01*
G01X13424Y493321D02*
Y494660D01*
G01Y489384D02*
Y490723D01*
G01Y485447D02*
Y486786D01*
G01Y477573D02*
Y478912D01*
G01Y481510D02*
Y482849D01*
G01D02*
Y481510D01*
G01Y478912D02*
Y477573D01*
G01Y486786D02*
Y485447D01*
G01Y490723D02*
Y489384D01*
G01Y494660D02*
Y493321D01*
G01X12601D02*
Y494660D01*
G01Y489384D02*
Y490723D01*
G01Y485447D02*
Y486786D01*
G01Y477573D02*
Y478912D01*
G01Y481510D02*
Y482849D01*
G01D02*
Y481510D01*
G01Y478912D02*
Y477573D01*
G01Y486786D02*
Y485447D01*
G01Y490723D02*
Y489384D01*
G01Y494660D02*
Y493321D01*
G01X8523Y478912D02*
Y477573D01*
G01Y482849D02*
Y481510D01*
G01Y478912D02*
Y477573D01*
G01Y482849D02*
Y481510D01*
G01Y486786D02*
Y485447D01*
G01Y486786D02*
Y485447D01*
G01Y490723D02*
Y489384D01*
G01Y490723D02*
Y489384D01*
G01Y494660D02*
Y493321D01*
G01Y494660D02*
Y493321D01*
G01X0Y494660D02*
Y495447D01*
G01Y492534D02*
Y493321D01*
G01Y490723D02*
Y491510D01*
G01Y488597D02*
Y489384D01*
G01Y482849D02*
Y483636D01*
G01Y486786D02*
Y487573D01*
G01Y484660D02*
Y485447D01*
G01Y478912D02*
Y479699D01*
G01Y480723D02*
Y481510D01*
G01Y476786D02*
Y477573D01*
G01D02*
Y476786D01*
G01Y481510D02*
Y480723D01*
G01Y479699D02*
Y478912D01*
G01Y485447D02*
Y484660D01*
G01Y483636D02*
Y482849D01*
G01Y487573D02*
Y486786D01*
G01Y489384D02*
Y488597D01*
G01Y491510D02*
Y490723D01*
G01Y493321D02*
Y492534D01*
G01Y495447D02*
Y494660D01*
G01X-984Y493321D02*
Y494660D01*
G01Y489384D02*
Y490723D01*
G01Y485447D02*
Y486786D01*
G01Y481510D02*
Y482849D01*
G01Y477573D02*
Y478912D01*
G01Y482849D02*
Y481510D01*
G01Y478912D02*
Y477573D01*
G01Y486786D02*
Y485447D01*
G01Y490723D02*
Y489384D01*
G01Y494660D02*
Y493321D01*
G01X-2251Y479660D02*
Y476825D01*
G01Y483597D02*
Y480762D01*
G01Y487534D02*
Y484699D01*
G01Y491471D02*
Y488636D01*
G01Y495408D02*
Y492573D01*
G01X-2520Y483282D02*
Y481077D01*
G01Y479345D02*
Y477140D01*
G01Y487219D02*
Y485014D01*
G01Y491156D02*
Y488951D01*
G01Y495093D02*
Y492888D01*
G01X15078Y494660D02*
X15962Y494463D01*
G01D02*
X15078Y494660D01*
G01X14580D02*
X15464Y494463D01*
G01X14580Y494660D02*
X15464Y494463D01*
G01X15078Y490723D02*
X15962Y490526D01*
G01D02*
X15078Y490723D01*
G01X14580D02*
X15464Y490526D01*
G01X14580Y490723D02*
X15464Y490526D01*
G01X15078Y486786D02*
X15962Y486589D01*
G01D02*
X15078Y486786D01*
G01X14580D02*
X15464Y486589D01*
G01X14580Y486786D02*
X15464Y486589D01*
G01X15078Y482849D02*
X15962Y482652D01*
G01D02*
X15078Y482849D01*
G01X14580D02*
X15464Y482652D01*
G01X14580Y482849D02*
X15464Y482652D01*
G01X15078Y478912D02*
X15962Y478715D01*
G01D02*
X15078Y478912D01*
G01X14580D02*
X15464Y478715D01*
G01X14580Y478912D02*
X15464Y478715D01*
G01X-2196Y492927D02*
X-1969Y492534D01*
G01X-2196Y492927D02*
X-1969Y492534D01*
G01X-2196Y488990D02*
X-1969Y488597D01*
G01X-2196Y488990D02*
X-1969Y488597D01*
G01X-2196Y485053D02*
X-1969Y484660D01*
G01X-2196Y485053D02*
X-1969Y484660D01*
G01X-2196Y481116D02*
X-1969Y480723D01*
G01X-2196Y481116D02*
X-1969Y480723D01*
G01X-2196Y477179D02*
X-1969Y476786D01*
G01X-2196Y477179D02*
X-1969Y476786D01*
G01Y499384D02*
X-2196Y498990D01*
G01X-1969Y499384D02*
X-2196Y498990D01*
G01X-1969Y503321D02*
X-2196Y502927D01*
G01X-1969Y503321D02*
X-2196Y502927D01*
G01X-1969Y507258D02*
X-2196Y506864D01*
G01X-1969Y507258D02*
X-2196Y506864D01*
G01X-1969Y511195D02*
X-2196Y510801D01*
G01X-1969Y511195D02*
X-2196Y510801D01*
G01X-1969Y515132D02*
X-2196Y514738D01*
G01X-1969Y515132D02*
X-2196Y514738D01*
G01X14580Y516943D02*
X15464Y517140D01*
G01X14580Y516943D02*
X15464Y517140D01*
G01X15078Y516943D02*
X15962Y517140D01*
G01D02*
X15078Y516943D01*
G01X14580Y513006D02*
X15464Y513203D01*
G01X14580Y513006D02*
X15464Y513203D01*
G01X15078Y513006D02*
X15962Y513203D01*
G01D02*
X15078Y513006D01*
G01X14580Y509069D02*
X15464Y509266D01*
G01X14580Y509069D02*
X15464Y509266D01*
G01X15078Y509069D02*
X15962Y509266D01*
G01D02*
X15078Y509069D01*
G01X14580Y505132D02*
X15464Y505329D01*
G01X14580Y505132D02*
X15464Y505329D01*
G01X15078Y505132D02*
X15962Y505329D01*
G01D02*
X15078Y505132D01*
G01X14580Y501195D02*
X15464Y501392D01*
G01X14580Y501195D02*
X15464Y501392D01*
G01X15078Y501195D02*
X15962Y501392D01*
G01D02*
X15078Y501195D01*
G01X14580Y497258D02*
X15464Y497455D01*
G01X14580Y497258D02*
X15464Y497455D01*
G01X15078Y497258D02*
X15962Y497455D01*
G01D02*
X15078Y497258D01*
G01X15464Y517140D02*
X15962D01*
G01D02*
X15464D01*
G01X8523Y516943D02*
X15078D01*
G01X-984D02*
X0D01*
G01X8523D02*
X0D01*
G01X15078D02*
X-984D01*
G01X-1969Y516156D02*
X0D01*
G01D02*
X-1969D01*
G01Y515132D02*
X0D01*
G01X-1969D02*
X0D01*
G01X12601Y514345D02*
X15078D01*
G01X-984D02*
X15078D01*
G01X8523D02*
X12601D01*
G01X0D02*
X8523D01*
G01X0D02*
X-984D01*
G01X15464Y514148D02*
X15962D01*
G01D02*
X15464D01*
G01Y513203D02*
X15962D01*
G01D02*
X15464D01*
G01X8523Y513006D02*
X15078D01*
G01X-984D02*
X0D01*
G01X8523D02*
X0D01*
G01X15078D02*
X-984D01*
G01X-1969Y512219D02*
X0D01*
G01D02*
X-1969D01*
G01Y511195D02*
X0D01*
G01X-1969D02*
X0D01*
G01X12601Y510408D02*
X15078D01*
G01X-984D02*
X15078D01*
G01X8523D02*
X12601D01*
G01X0D02*
X8523D01*
G01X0D02*
X-984D01*
G01X15464Y510211D02*
X15962D01*
G01D02*
X15464D01*
G01Y509266D02*
X15962D01*
G01D02*
X15464D01*
G01X8523Y509069D02*
X15078D01*
G01X-984D02*
X0D01*
G01X8523D02*
X0D01*
G01X15078D02*
X-984D01*
G01X-1969Y508282D02*
X0D01*
G01D02*
X-1969D01*
G01Y507258D02*
X0D01*
G01X-1969D02*
X0D01*
G01X12601Y506471D02*
X15078D01*
G01X-984D02*
X15078D01*
G01X8523D02*
X12601D01*
G01X0D02*
X8523D01*
G01X0D02*
X-984D01*
G01X15464Y506274D02*
X15962D01*
G01D02*
X15464D01*
G01Y505329D02*
X15962D01*
G01D02*
X15464D01*
G01X8523Y505132D02*
X15078D01*
G01X-984D02*
X0D01*
G01X8523D02*
X0D01*
G01X15078D02*
X-984D01*
G01X-1969Y504345D02*
X0D01*
G01D02*
X-1969D01*
G01Y503321D02*
X0D01*
G01X-1969D02*
X0D01*
G01X12601Y502534D02*
X15078D01*
G01X-984D02*
X15078D01*
G01X8523D02*
X12601D01*
G01X0D02*
X8523D01*
G01X0D02*
X-984D01*
G01X15464Y502337D02*
X15962D01*
G01D02*
X15464D01*
G01Y501392D02*
X15962D01*
G01D02*
X15464D01*
G01X8523Y501195D02*
X15078D01*
G01X-984D02*
X0D01*
G01X8523D02*
X0D01*
G01X15078D02*
X-984D01*
G01X-1969Y500408D02*
X0D01*
G01D02*
X-1969D01*
G01Y499384D02*
X0D01*
G01X-1969D02*
X0D01*
G01X12601Y498597D02*
X15078D01*
G01X-984D02*
X15078D01*
G01X8523D02*
X12601D01*
G01X0D02*
X8523D01*
G01X0D02*
X-984D01*
G01X15464Y498400D02*
X15962D01*
G01D02*
X15464D01*
G01Y497455D02*
X15962D01*
G01D02*
X15464D01*
G01X8523Y497258D02*
X15078D01*
G01X-984D02*
X0D01*
G01X8523D02*
X0D01*
G01X15078D02*
X-984D01*
G01X-1969Y496471D02*
X0D01*
G01D02*
X-1969D01*
G01X15962Y517140D02*
Y518085D01*
G01Y513203D02*
Y514148D01*
G01Y509266D02*
Y510211D01*
G01Y505329D02*
Y506274D01*
G01Y501392D02*
Y502337D01*
G01Y497455D02*
Y498400D01*
G01D02*
Y497455D01*
G01Y502337D02*
Y501392D01*
G01Y506274D02*
Y505329D01*
G01Y510211D02*
Y509266D01*
G01Y514148D02*
Y513203D01*
G01Y518085D02*
Y517140D01*
G01X15464D02*
Y518085D01*
G01Y513203D02*
Y514148D01*
G01Y509266D02*
Y510211D01*
G01Y505329D02*
Y506274D01*
G01Y501392D02*
Y502337D01*
G01Y497455D02*
Y498400D01*
G01D02*
Y497455D01*
G01Y506274D02*
Y505329D01*
G01Y502337D02*
Y501392D01*
G01Y510211D02*
Y509266D01*
G01Y514148D02*
Y513203D01*
G01Y518085D02*
Y517140D01*
G01X13424Y516943D02*
Y518282D01*
G01Y513006D02*
Y514345D01*
G01Y509069D02*
Y510408D01*
G01Y501195D02*
Y502534D01*
G01Y505132D02*
Y506471D01*
G01Y497258D02*
Y498597D01*
G01D02*
Y497258D01*
G01Y506471D02*
Y505132D01*
G01Y502534D02*
Y501195D01*
G01Y510408D02*
Y509069D01*
G01Y514345D02*
Y513006D01*
G01Y518282D02*
Y516943D01*
G01X12601D02*
Y518282D01*
G01Y513006D02*
Y514345D01*
G01Y509069D02*
Y510408D01*
G01Y505132D02*
Y506471D01*
G01Y501195D02*
Y502534D01*
G01Y497258D02*
Y498597D01*
G01D02*
Y497258D01*
G01Y506471D02*
Y505132D01*
G01Y502534D02*
Y501195D01*
G01Y510408D02*
Y509069D01*
G01Y514345D02*
Y513006D01*
G01Y518282D02*
Y516943D01*
G01X8523Y498597D02*
Y497258D01*
G01Y498597D02*
Y497258D01*
G01Y506471D02*
Y505132D01*
G01Y502534D02*
Y501195D01*
G01Y502534D02*
Y501195D01*
G01Y506471D02*
Y505132D01*
G01Y510408D02*
Y509069D01*
G01Y510408D02*
Y509069D01*
G01Y514345D02*
Y513006D01*
G01Y514345D02*
Y513006D01*
G01Y518282D02*
Y516943D01*
G01Y518282D02*
Y516943D01*
G01X0Y516156D02*
Y516943D01*
G01Y514345D02*
Y515132D01*
G01Y512219D02*
Y513006D01*
G01Y510408D02*
Y511195D01*
G01Y506471D02*
Y507258D01*
G01Y508282D02*
Y509069D01*
G01Y502534D02*
Y503321D01*
G01Y504345D02*
Y505132D01*
G01Y498597D02*
Y499384D01*
G01Y500408D02*
Y501195D01*
G01Y496471D02*
Y497258D01*
G01D02*
Y496471D01*
G01Y501195D02*
Y500408D01*
G01Y499384D02*
Y498597D01*
G01Y505132D02*
Y504345D01*
G01Y503321D02*
Y502534D01*
G01Y509069D02*
Y508282D01*
G01Y507258D02*
Y506471D01*
G01Y511195D02*
Y510408D01*
G01Y513006D02*
Y512219D01*
G01Y515132D02*
Y514345D01*
G01Y516943D02*
Y516156D01*
G01X-984Y516943D02*
Y518282D01*
G01Y513006D02*
Y514345D01*
G01Y509069D02*
Y510408D01*
G01Y505132D02*
Y506471D01*
G01Y501195D02*
Y502534D01*
G01Y497258D02*
Y498597D01*
G01D02*
Y497258D01*
G01Y506471D02*
Y505132D01*
G01Y502534D02*
Y501195D01*
G01Y510408D02*
Y509069D01*
G01Y514345D02*
Y513006D01*
G01Y518282D02*
Y516943D01*
G01X-2251Y499345D02*
Y496510D01*
G01Y503282D02*
Y500447D01*
G01Y507219D02*
Y504384D01*
G01Y511156D02*
Y508321D01*
G01Y515093D02*
Y512258D01*
G01Y519030D02*
Y516195D01*
G01X-2520Y499030D02*
Y496825D01*
G01Y506904D02*
Y504699D01*
G01Y502967D02*
Y500762D01*
G01Y510841D02*
Y508636D01*
G01Y514778D02*
Y512573D01*
G01Y518715D02*
Y516510D01*
G01X15078Y514345D02*
X15962Y514148D01*
G01D02*
X15078Y514345D01*
G01X14580D02*
X15464Y514148D01*
G01X14580Y514345D02*
X15464Y514148D01*
G01X15078Y510408D02*
X15962Y510211D01*
G01D02*
X15078Y510408D01*
G01X14580D02*
X15464Y510211D01*
G01X14580Y510408D02*
X15464Y510211D01*
G01X15078Y506471D02*
X15962Y506274D01*
G01D02*
X15078Y506471D01*
G01X14580D02*
X15464Y506274D01*
G01X14580Y506471D02*
X15464Y506274D01*
G01X15078Y502534D02*
X15962Y502337D01*
G01D02*
X15078Y502534D01*
G01X14580D02*
X15464Y502337D01*
G01X14580Y502534D02*
X15464Y502337D01*
G01X15078Y498597D02*
X15962Y498400D01*
G01D02*
X15078Y498597D01*
G01X14580D02*
X15464Y498400D01*
G01X14580Y498597D02*
X15464Y498400D01*
G01X-2196Y516549D02*
X-1969Y516156D01*
G01X-2196Y516549D02*
X-1969Y516156D01*
G01X-2196Y512612D02*
X-1969Y512219D01*
G01X-2196Y512612D02*
X-1969Y512219D01*
G01X-2196Y508675D02*
X-1969Y508282D01*
G01X-2196Y508675D02*
X-1969Y508282D01*
G01X-2196Y504738D02*
X-1969Y504345D01*
G01X-2196Y504738D02*
X-1969Y504345D01*
G01X-2196Y500801D02*
X-1969Y500408D01*
G01X-2196Y500801D02*
X-1969Y500408D01*
G01X-2196Y496864D02*
X-1969Y496471D01*
G01X-2196Y496864D02*
X-1969Y496471D01*
G01Y519069D02*
X-2196Y518675D01*
G01X-1969Y519069D02*
X-2196Y518675D01*
G01X-1969Y523006D02*
X-2196Y522612D01*
G01X-1969Y523006D02*
X-2196Y522612D01*
G01X-1969Y526943D02*
X-2196Y526549D01*
G01X-1969Y526943D02*
X-2196Y526549D01*
G01X-1969Y530880D02*
X-2196Y530486D01*
G01X-1969Y530880D02*
X-2196Y530486D01*
G01X-1969Y534817D02*
X-2196Y534423D01*
G01X-1969Y534817D02*
X-2196Y534423D01*
G01X-1969Y538754D02*
X-2196Y538360D01*
G01X-1969Y538754D02*
X-2196Y538360D01*
G01X14580Y536628D02*
X15464Y536825D01*
G01X14580Y536628D02*
X15464Y536825D01*
G01X15078Y536628D02*
X15962Y536825D01*
G01D02*
X15078Y536628D01*
G01X14580Y532691D02*
X15464Y532888D01*
G01X14580Y532691D02*
X15464Y532888D01*
G01X15078Y532691D02*
X15962Y532888D01*
G01D02*
X15078Y532691D01*
G01X14580Y528754D02*
X15464Y528951D01*
G01X14580Y528754D02*
X15464Y528951D01*
G01X15078Y528754D02*
X15962Y528951D01*
G01D02*
X15078Y528754D01*
G01X14580Y524817D02*
X15464Y525014D01*
G01X14580Y524817D02*
X15464Y525014D01*
G01X15078Y524817D02*
X15962Y525014D01*
G01D02*
X15078Y524817D01*
G01X14580Y520880D02*
X15464Y521077D01*
G01X14580Y520880D02*
X15464Y521077D01*
G01X15078Y520880D02*
X15962Y521077D01*
G01D02*
X15078Y520880D01*
G01X12601Y537967D02*
X15078D01*
G01X-984D02*
X15078D01*
G01X8523D02*
X12601D01*
G01X0D02*
X8523D01*
G01X0D02*
X-984D01*
G01X15464Y537770D02*
X15962D01*
G01D02*
X15464D01*
G01Y536825D02*
X15962D01*
G01D02*
X15464D01*
G01X8523Y536628D02*
X15078D01*
G01X-984D02*
X0D01*
G01X8523D02*
X0D01*
G01X15078D02*
X-984D01*
G01X-1969Y535841D02*
X0D01*
G01D02*
X-1969D01*
G01Y534817D02*
X0D01*
G01X-1969D02*
X0D01*
G01X12601Y534030D02*
X15078D01*
G01X-984D02*
X15078D01*
G01X8523D02*
X12601D01*
G01X0D02*
X8523D01*
G01X0D02*
X-984D01*
G01X15464Y533833D02*
X15962D01*
G01D02*
X15464D01*
G01Y532888D02*
X15962D01*
G01D02*
X15464D01*
G01X8523Y532691D02*
X15078D01*
G01X-984D02*
X0D01*
G01X8523D02*
X0D01*
G01X15078D02*
X-984D01*
G01X-1969Y531904D02*
X0D01*
G01D02*
X-1969D01*
G01Y530880D02*
X0D01*
G01X-1969D02*
X0D01*
G01X12601Y530093D02*
X15078D01*
G01X-984D02*
X15078D01*
G01X8523D02*
X12601D01*
G01X0D02*
X8523D01*
G01X0D02*
X-984D01*
G01X15464Y529896D02*
X15962D01*
G01D02*
X15464D01*
G01Y528951D02*
X15962D01*
G01D02*
X15464D01*
G01X8523Y528754D02*
X15078D01*
G01X-984D02*
X0D01*
G01X8523D02*
X0D01*
G01X15078D02*
X-984D01*
G01X-1969Y527967D02*
X0D01*
G01D02*
X-1969D01*
G01Y526943D02*
X0D01*
G01X-1969D02*
X0D01*
G01X12601Y526156D02*
X15078D01*
G01X-984D02*
X15078D01*
G01X8523D02*
X12601D01*
G01X0D02*
X8523D01*
G01X0D02*
X-984D01*
G01X15464Y525959D02*
X15962D01*
G01D02*
X15464D01*
G01Y525014D02*
X15962D01*
G01D02*
X15464D01*
G01X8523Y524817D02*
X15078D01*
G01X-984D02*
X0D01*
G01X8523D02*
X0D01*
G01X15078D02*
X-984D01*
G01X-1969Y524030D02*
X0D01*
G01D02*
X-1969D01*
G01Y523006D02*
X0D01*
G01X-1969D02*
X0D01*
G01X12601Y522219D02*
X15078D01*
G01X-984D02*
X15078D01*
G01X8523D02*
X12601D01*
G01X0D02*
X8523D01*
G01X0D02*
X-984D01*
G01X15464Y522022D02*
X15962D01*
G01D02*
X15464D01*
G01Y521077D02*
X15962D01*
G01D02*
X15464D01*
G01X8523Y520880D02*
X15078D01*
G01X-984D02*
X0D01*
G01X8523D02*
X0D01*
G01X15078D02*
X-984D01*
G01X-1969Y520093D02*
X0D01*
G01D02*
X-1969D01*
G01Y519069D02*
X0D01*
G01X-1969D02*
X0D01*
G01X12601Y518282D02*
X15078D01*
G01X-984D02*
X15078D01*
G01X8523D02*
X12601D01*
G01X0D02*
X8523D01*
G01X0D02*
X-984D01*
G01X15464Y518085D02*
X15962D01*
G01D02*
X15464D01*
G01X15962Y536825D02*
Y537770D01*
G01Y532888D02*
Y533833D01*
G01Y528951D02*
Y529896D01*
G01Y525014D02*
Y525959D01*
G01Y521077D02*
Y522022D01*
G01D02*
Y521077D01*
G01Y525959D02*
Y525014D01*
G01Y529896D02*
Y528951D01*
G01Y533833D02*
Y532888D01*
G01Y537770D02*
Y536825D01*
G01X15464D02*
Y537770D01*
G01Y532888D02*
Y533833D01*
G01Y528951D02*
Y529896D01*
G01Y525014D02*
Y525959D01*
G01Y521077D02*
Y522022D01*
G01D02*
Y521077D01*
G01Y529896D02*
Y528951D01*
G01Y525959D02*
Y525014D01*
G01Y533833D02*
Y532888D01*
G01Y537770D02*
Y536825D01*
G01X13424Y536628D02*
Y537967D01*
G01Y532691D02*
Y534030D01*
G01Y524817D02*
Y526156D01*
G01Y528754D02*
Y530093D01*
G01Y520880D02*
Y522219D01*
G01D02*
Y520880D01*
G01Y530093D02*
Y528754D01*
G01Y526156D02*
Y524817D01*
G01Y534030D02*
Y532691D01*
G01Y537967D02*
Y536628D01*
G01X12601D02*
Y537967D01*
G01Y532691D02*
Y534030D01*
G01Y528754D02*
Y530093D01*
G01Y524817D02*
Y526156D01*
G01Y520880D02*
Y522219D01*
G01D02*
Y520880D01*
G01Y530093D02*
Y528754D01*
G01Y526156D02*
Y524817D01*
G01Y534030D02*
Y532691D01*
G01Y537967D02*
Y536628D01*
G01X8523Y522219D02*
Y520880D01*
G01Y522219D02*
Y520880D01*
G01Y530093D02*
Y528754D01*
G01Y526156D02*
Y524817D01*
G01Y526156D02*
Y524817D01*
G01Y530093D02*
Y528754D01*
G01Y534030D02*
Y532691D01*
G01Y534030D02*
Y532691D01*
G01Y537967D02*
Y536628D01*
G01Y537967D02*
Y536628D01*
G01X0Y537967D02*
Y538754D01*
G01Y535841D02*
Y536628D01*
G01Y534030D02*
Y534817D01*
G01Y530093D02*
Y530880D01*
G01Y531904D02*
Y532691D01*
G01Y526156D02*
Y526943D01*
G01Y527967D02*
Y528754D01*
G01Y522219D02*
Y523006D01*
G01Y524030D02*
Y524817D01*
G01Y518282D02*
Y519069D01*
G01Y520093D02*
Y520880D01*
G01D02*
Y520093D01*
G01Y519069D02*
Y518282D01*
G01Y524817D02*
Y524030D01*
G01Y523006D02*
Y522219D01*
G01Y528754D02*
Y527967D01*
G01Y526943D02*
Y526156D01*
G01Y532691D02*
Y531904D01*
G01Y530880D02*
Y530093D01*
G01Y534817D02*
Y534030D01*
G01Y536628D02*
Y535841D01*
G01Y538754D02*
Y537967D01*
G01X-984Y536628D02*
Y537967D01*
G01Y532691D02*
Y534030D01*
G01Y528754D02*
Y530093D01*
G01Y524817D02*
Y526156D01*
G01Y520880D02*
Y522219D01*
G01D02*
Y520880D01*
G01Y530093D02*
Y528754D01*
G01Y526156D02*
Y524817D01*
G01Y534030D02*
Y532691D01*
G01Y537967D02*
Y536628D01*
G01X-2251Y522967D02*
Y520132D01*
G01Y526904D02*
Y524069D01*
G01Y530841D02*
Y528006D01*
G01Y534778D02*
Y531943D01*
G01Y538715D02*
Y535880D01*
G01X-2520Y522652D02*
Y520447D01*
G01Y526589D02*
Y524384D01*
G01Y534463D02*
Y532258D01*
G01Y530526D02*
Y528321D01*
G01Y538400D02*
Y536195D01*
G01X15078Y537967D02*
X15962Y537770D01*
G01D02*
X15078Y537967D01*
G01X14580D02*
X15464Y537770D01*
G01X14580Y537967D02*
X15464Y537770D01*
G01X15078Y534030D02*
X15962Y533833D01*
G01D02*
X15078Y534030D01*
G01X14580D02*
X15464Y533833D01*
G01X14580Y534030D02*
X15464Y533833D01*
G01X15078Y530093D02*
X15962Y529896D01*
G01D02*
X15078Y530093D01*
G01X14580D02*
X15464Y529896D01*
G01X14580Y530093D02*
X15464Y529896D01*
G01X15078Y526156D02*
X15962Y525959D01*
G01D02*
X15078Y526156D01*
G01X14580D02*
X15464Y525959D01*
G01X14580Y526156D02*
X15464Y525959D01*
G01X15078Y522219D02*
X15962Y522022D01*
G01D02*
X15078Y522219D01*
G01X14580D02*
X15464Y522022D01*
G01X14580Y522219D02*
X15464Y522022D01*
G01X15078Y518282D02*
X15962Y518085D01*
G01D02*
X15078Y518282D01*
G01X14580D02*
X15464Y518085D01*
G01X14580Y518282D02*
X15464Y518085D01*
G01X-2196Y536234D02*
X-1969Y535841D01*
G01X-2196Y536234D02*
X-1969Y535841D01*
G01X-2196Y532297D02*
X-1969Y531904D01*
G01X-2196Y532297D02*
X-1969Y531904D01*
G01X-2196Y528360D02*
X-1969Y527967D01*
G01X-2196Y528360D02*
X-1969Y527967D01*
G01X-2196Y524423D02*
X-1969Y524030D01*
G01X-2196Y524423D02*
X-1969Y524030D01*
G01X-2196Y520486D02*
X-1969Y520093D01*
G01X-2196Y520486D02*
X-1969Y520093D01*
G01Y542691D02*
X-2196Y542297D01*
G01X-1969Y542691D02*
X-2196Y542297D01*
G01X-1969Y546628D02*
X-2196Y546234D01*
G01X-1969Y546628D02*
X-2196Y546234D01*
G01X-1969Y550565D02*
X-2196Y550171D01*
G01X-1969Y550565D02*
X-2196Y550171D01*
G01X-1969Y554502D02*
X-2196Y554108D01*
G01X-1969Y554502D02*
X-2196Y554108D01*
G01X-1969Y558439D02*
X-2196Y558045D01*
G01X-1969Y558439D02*
X-2196Y558045D01*
G01X14580Y556313D02*
X15464Y556510D01*
G01X14580Y556313D02*
X15464Y556510D01*
G01X15078Y556313D02*
X15962Y556510D01*
G01D02*
X15078Y556313D01*
G01X14580Y552376D02*
X15464Y552573D01*
G01X14580Y552376D02*
X15464Y552573D01*
G01X15078Y552376D02*
X15962Y552573D01*
G01D02*
X15078Y552376D01*
G01X14580Y548439D02*
X15464Y548636D01*
G01X14580Y548439D02*
X15464Y548636D01*
G01X15078Y548439D02*
X15962Y548636D01*
G01D02*
X15078Y548439D01*
G01X14580Y544502D02*
X15464Y544699D01*
G01X14580Y544502D02*
X15464Y544699D01*
G01X15078Y544502D02*
X15962Y544699D01*
G01D02*
X15078Y544502D01*
G01X14580Y540565D02*
X15464Y540762D01*
G01X14580Y540565D02*
X15464Y540762D01*
G01X15078Y540565D02*
X15962Y540762D01*
G01D02*
X15078Y540565D01*
G01X-1969Y559463D02*
X0D01*
G01D02*
X-1969D01*
G01Y558439D02*
X0D01*
G01X-1969D02*
X0D01*
G01X12601Y557652D02*
X15078D01*
G01X-984D02*
X15078D01*
G01X8523D02*
X12601D01*
G01X0D02*
X8523D01*
G01X0D02*
X-984D01*
G01X15464Y557455D02*
X15962D01*
G01D02*
X15464D01*
G01Y556510D02*
X15962D01*
G01D02*
X15464D01*
G01X8523Y556313D02*
X15078D01*
G01X-984D02*
X0D01*
G01X8523D02*
X0D01*
G01X15078D02*
X-984D01*
G01X-1969Y555526D02*
X0D01*
G01D02*
X-1969D01*
G01Y554502D02*
X0D01*
G01X-1969D02*
X0D01*
G01X12601Y553715D02*
X15078D01*
G01X-984D02*
X15078D01*
G01X8523D02*
X12601D01*
G01X0D02*
X8523D01*
G01X0D02*
X-984D01*
G01X15464Y553518D02*
X15962D01*
G01D02*
X15464D01*
G01Y552573D02*
X15962D01*
G01D02*
X15464D01*
G01X8523Y552376D02*
X15078D01*
G01X-984D02*
X0D01*
G01X8523D02*
X0D01*
G01X15078D02*
X-984D01*
G01X-1969Y551589D02*
X0D01*
G01D02*
X-1969D01*
G01Y550565D02*
X0D01*
G01X-1969D02*
X0D01*
G01X12601Y549778D02*
X15078D01*
G01X-984D02*
X15078D01*
G01X8523D02*
X12601D01*
G01X0D02*
X8523D01*
G01X0D02*
X-984D01*
G01X15464Y549581D02*
X15962D01*
G01D02*
X15464D01*
G01Y548636D02*
X15962D01*
G01D02*
X15464D01*
G01X8523Y548439D02*
X15078D01*
G01X-984D02*
X0D01*
G01X8523D02*
X0D01*
G01X15078D02*
X-984D01*
G01X-1969Y547652D02*
X0D01*
G01D02*
X-1969D01*
G01Y546628D02*
X0D01*
G01X-1969D02*
X0D01*
G01X12601Y545841D02*
X15078D01*
G01X-984D02*
X15078D01*
G01X8523D02*
X12601D01*
G01X0D02*
X8523D01*
G01X0D02*
X-984D01*
G01X15464Y545644D02*
X15962D01*
G01D02*
X15464D01*
G01Y544699D02*
X15962D01*
G01D02*
X15464D01*
G01X8523Y544502D02*
X15078D01*
G01X-984D02*
X0D01*
G01X8523D02*
X0D01*
G01X15078D02*
X-984D01*
G01X-1969Y543715D02*
X0D01*
G01D02*
X-1969D01*
G01Y542691D02*
X0D01*
G01X-1969D02*
X0D01*
G01X12601Y541904D02*
X15078D01*
G01X-984D02*
X15078D01*
G01X8523D02*
X12601D01*
G01X0D02*
X8523D01*
G01X0D02*
X-984D01*
G01X15464Y541707D02*
X15962D01*
G01D02*
X15464D01*
G01Y540762D02*
X15962D01*
G01D02*
X15464D01*
G01X8523Y540565D02*
X15078D01*
G01X-984D02*
X0D01*
G01X8523D02*
X0D01*
G01X15078D02*
X-984D01*
G01X-1969Y539778D02*
X0D01*
G01D02*
X-1969D01*
G01Y538754D02*
X0D01*
G01X-1969D02*
X0D01*
G01X15962Y556510D02*
Y557455D01*
G01Y548636D02*
Y549581D01*
G01Y552573D02*
Y553518D01*
G01Y544699D02*
Y545644D01*
G01Y540762D02*
Y541707D01*
G01D02*
Y540762D01*
G01Y545644D02*
Y544699D01*
G01Y549581D02*
Y548636D01*
G01Y553518D02*
Y552573D01*
G01Y557455D02*
Y556510D01*
G01X15464D02*
Y557455D01*
G01Y552573D02*
Y553518D01*
G01Y548636D02*
Y549581D01*
G01Y544699D02*
Y545644D01*
G01Y540762D02*
Y541707D01*
G01D02*
Y540762D01*
G01Y545644D02*
Y544699D01*
G01Y549581D02*
Y548636D01*
G01Y553518D02*
Y552573D01*
G01Y557455D02*
Y556510D01*
G01X13424Y556313D02*
Y557652D01*
G01Y548439D02*
Y549778D01*
G01Y552376D02*
Y553715D01*
G01Y544502D02*
Y545841D01*
G01Y540565D02*
Y541904D01*
G01D02*
Y540565D01*
G01Y545841D02*
Y544502D01*
G01Y553715D02*
Y552376D01*
G01Y549778D02*
Y548439D01*
G01Y557652D02*
Y556313D01*
G01X12601D02*
Y557652D01*
G01Y548439D02*
Y549778D01*
G01Y552376D02*
Y553715D01*
G01Y544502D02*
Y545841D01*
G01Y540565D02*
Y541904D01*
G01D02*
Y540565D01*
G01Y545841D02*
Y544502D01*
G01Y553715D02*
Y552376D01*
G01Y549778D02*
Y548439D01*
G01Y557652D02*
Y556313D01*
G01X8523Y541904D02*
Y540565D01*
G01Y541904D02*
Y540565D01*
G01Y545841D02*
Y544502D01*
G01Y545841D02*
Y544502D01*
G01Y549778D02*
Y548439D01*
G01Y553715D02*
Y552376D01*
G01Y549778D02*
Y548439D01*
G01Y553715D02*
Y552376D01*
G01Y557652D02*
Y556313D01*
G01Y557652D02*
Y556313D01*
G01X0Y557652D02*
Y558439D01*
G01Y559463D02*
Y560250D01*
G01Y553715D02*
Y554502D01*
G01Y555526D02*
Y556313D01*
G01Y549778D02*
Y550565D01*
G01Y551589D02*
Y552376D01*
G01Y545841D02*
Y546628D01*
G01Y543715D02*
Y544502D01*
G01Y547652D02*
Y548439D01*
G01Y541904D02*
Y542691D01*
G01Y539778D02*
Y540565D01*
G01D02*
Y539778D01*
G01Y542691D02*
Y541904D01*
G01Y544502D02*
Y543715D01*
G01Y548439D02*
Y547652D01*
G01Y546628D02*
Y545841D01*
G01Y552376D02*
Y551589D01*
G01Y550565D02*
Y549778D01*
G01Y556313D02*
Y555526D01*
G01Y554502D02*
Y553715D01*
G01Y560250D02*
Y559463D01*
G01Y558439D02*
Y557652D01*
G01X-984Y556313D02*
Y557652D01*
G01Y552376D02*
Y553715D01*
G01Y548439D02*
Y549778D01*
G01Y544502D02*
Y545841D01*
G01Y540565D02*
Y541904D01*
G01D02*
Y540565D01*
G01Y545841D02*
Y544502D01*
G01Y553715D02*
Y552376D01*
G01Y549778D02*
Y548439D01*
G01Y557652D02*
Y556313D01*
G01X-2251Y542652D02*
Y539817D01*
G01Y546589D02*
Y543754D01*
G01Y550526D02*
Y547691D01*
G01Y554463D02*
Y551628D01*
G01Y558400D02*
Y555565D01*
G01Y562337D02*
Y559502D01*
G01X-2520Y542337D02*
Y540132D01*
G01Y546274D02*
Y544069D01*
G01Y550211D02*
Y548006D01*
G01Y558085D02*
Y555880D01*
G01Y554148D02*
Y551943D01*
G01X15078Y557652D02*
X15962Y557455D01*
G01D02*
X15078Y557652D01*
G01X14580D02*
X15464Y557455D01*
G01X14580Y557652D02*
X15464Y557455D01*
G01X15078Y553715D02*
X15962Y553518D01*
G01D02*
X15078Y553715D01*
G01X14580D02*
X15464Y553518D01*
G01X14580Y553715D02*
X15464Y553518D01*
G01X15078Y549778D02*
X15962Y549581D01*
G01D02*
X15078Y549778D01*
G01X14580D02*
X15464Y549581D01*
G01X14580Y549778D02*
X15464Y549581D01*
G01X15078Y545841D02*
X15962Y545644D01*
G01D02*
X15078Y545841D01*
G01X14580D02*
X15464Y545644D01*
G01X14580Y545841D02*
X15464Y545644D01*
G01X15078Y541904D02*
X15962Y541707D01*
G01D02*
X15078Y541904D01*
G01X14580D02*
X15464Y541707D01*
G01X14580Y541904D02*
X15464Y541707D01*
G01X-2196Y559856D02*
X-1969Y559463D01*
G01X-2196Y559856D02*
X-1969Y559463D01*
G01X-2196Y555919D02*
X-1969Y555526D01*
G01X-2196Y555919D02*
X-1969Y555526D01*
G01X-2196Y551982D02*
X-1969Y551589D01*
G01X-2196Y551982D02*
X-1969Y551589D01*
G01X-2196Y548045D02*
X-1969Y547652D01*
G01X-2196Y548045D02*
X-1969Y547652D01*
G01X-2196Y544108D02*
X-1969Y543715D01*
G01X-2196Y544108D02*
X-1969Y543715D01*
G01X-2196Y540171D02*
X-1969Y539778D01*
G01X-2196Y540171D02*
X-1969Y539778D01*
G01Y562376D02*
X-2196Y561982D01*
G01X-1969Y562376D02*
X-2196Y561982D01*
G01X-1969Y566313D02*
X-2196Y565919D01*
G01X-1969Y566313D02*
X-2196Y565919D01*
G01X-1969Y570250D02*
X-2196Y569856D01*
G01X-1969Y570250D02*
X-2196Y569856D01*
G01X-1969Y574187D02*
X-2196Y573793D01*
G01X-1969Y574187D02*
X-2196Y573793D01*
G01X-1969Y578124D02*
X-2196Y577730D01*
G01X-1969Y578124D02*
X-2196Y577730D01*
G01X14580Y579935D02*
X15464Y580132D01*
G01X14580Y579935D02*
X15464Y580132D01*
G01X15078Y579935D02*
X15962Y580132D01*
G01D02*
X15078Y579935D01*
G01X14580Y575998D02*
X15464Y576195D01*
G01X14580Y575998D02*
X15464Y576195D01*
G01X15078Y575998D02*
X15962Y576195D01*
G01D02*
X15078Y575998D01*
G01X14580Y572061D02*
X15464Y572258D01*
G01X14580Y572061D02*
X15464Y572258D01*
G01X15078Y572061D02*
X15962Y572258D01*
G01D02*
X15078Y572061D01*
G01X14580Y568124D02*
X15464Y568321D01*
G01X14580Y568124D02*
X15464Y568321D01*
G01X15078Y568124D02*
X15962Y568321D01*
G01D02*
X15078Y568124D01*
G01X14580Y564187D02*
X15464Y564384D01*
G01X14580Y564187D02*
X15464Y564384D01*
G01X15078Y564187D02*
X15962Y564384D01*
G01D02*
X15078Y564187D01*
G01X14580Y560250D02*
X15464Y560447D01*
G01X14580Y560250D02*
X15464Y560447D01*
G01X15078Y560250D02*
X15962Y560447D01*
G01D02*
X15078Y560250D01*
G01X15464Y580132D02*
X15962D01*
G01D02*
X15464D01*
G01X8523Y579935D02*
X15078D01*
G01X-984D02*
X0D01*
G01X8523D02*
X0D01*
G01X15078D02*
X-984D01*
G01X-1969Y579148D02*
X0D01*
G01D02*
X-1969D01*
G01Y578124D02*
X0D01*
G01X-1969D02*
X0D01*
G01X12601Y577337D02*
X15078D01*
G01X-984D02*
X15078D01*
G01X8523D02*
X12601D01*
G01X0D02*
X8523D01*
G01X0D02*
X-984D01*
G01X15464Y577140D02*
X15962D01*
G01D02*
X15464D01*
G01Y576195D02*
X15962D01*
G01D02*
X15464D01*
G01X8523Y575998D02*
X15078D01*
G01X-984D02*
X0D01*
G01X8523D02*
X0D01*
G01X15078D02*
X-984D01*
G01X-1969Y575211D02*
X0D01*
G01D02*
X-1969D01*
G01Y574187D02*
X0D01*
G01X-1969D02*
X0D01*
G01X12601Y573400D02*
X15078D01*
G01X-984D02*
X15078D01*
G01X8523D02*
X12601D01*
G01X0D02*
X8523D01*
G01X0D02*
X-984D01*
G01X15464Y573203D02*
X15962D01*
G01D02*
X15464D01*
G01Y572258D02*
X15962D01*
G01D02*
X15464D01*
G01X8523Y572061D02*
X15078D01*
G01X-984D02*
X0D01*
G01X8523D02*
X0D01*
G01X15078D02*
X-984D01*
G01X-1969Y571274D02*
X0D01*
G01D02*
X-1969D01*
G01Y570250D02*
X0D01*
G01X-1969D02*
X0D01*
G01X12601Y569463D02*
X15078D01*
G01X-984D02*
X15078D01*
G01X8523D02*
X12601D01*
G01X0D02*
X8523D01*
G01X0D02*
X-984D01*
G01X15464Y569266D02*
X15962D01*
G01D02*
X15464D01*
G01Y568321D02*
X15962D01*
G01D02*
X15464D01*
G01X8523Y568124D02*
X15078D01*
G01X-984D02*
X0D01*
G01X8523D02*
X0D01*
G01X15078D02*
X-984D01*
G01X-1969Y567337D02*
X0D01*
G01D02*
X-1969D01*
G01Y566313D02*
X0D01*
G01X-1969D02*
X0D01*
G01X12601Y565526D02*
X15078D01*
G01X-984D02*
X15078D01*
G01X8523D02*
X12601D01*
G01X0D02*
X8523D01*
G01X0D02*
X-984D01*
G01X15464Y565329D02*
X15962D01*
G01D02*
X15464D01*
G01Y564384D02*
X15962D01*
G01D02*
X15464D01*
G01X8523Y564187D02*
X15078D01*
G01X-984D02*
X0D01*
G01X8523D02*
X0D01*
G01X15078D02*
X-984D01*
G01X-1969Y563400D02*
X0D01*
G01D02*
X-1969D01*
G01Y562376D02*
X0D01*
G01X-1969D02*
X0D01*
G01X12601Y561589D02*
X15078D01*
G01X-984D02*
X15078D01*
G01X8523D02*
X12601D01*
G01X0D02*
X8523D01*
G01X0D02*
X-984D01*
G01X15464Y561392D02*
X15962D01*
G01D02*
X15464D01*
G01Y560447D02*
X15962D01*
G01D02*
X15464D01*
G01X8523Y560250D02*
X15078D01*
G01X-984D02*
X0D01*
G01X8523D02*
X0D01*
G01X15078D02*
X-984D01*
G01X15078Y577337D02*
X15962Y577140D01*
G01D02*
X15078Y577337D01*
G01X14580D02*
X15464Y577140D01*
G01X14580Y577337D02*
X15464Y577140D01*
G01X15078Y573400D02*
X15962Y573203D01*
G01D02*
X15078Y573400D01*
G01X14580D02*
X15464Y573203D01*
G01X14580Y573400D02*
X15464Y573203D01*
G01X15962Y580132D02*
Y581077D01*
G01Y576195D02*
Y577140D01*
G01Y572258D02*
Y573203D01*
G01Y568321D02*
Y569266D01*
G01Y564384D02*
Y565329D01*
G01Y560447D02*
Y561392D01*
G01D02*
Y560447D01*
G01Y565329D02*
Y564384D01*
G01Y569266D02*
Y568321D01*
G01Y577140D02*
Y576195D01*
G01Y573203D02*
Y572258D01*
G01Y581077D02*
Y580132D01*
G01X15464D02*
Y581077D01*
G01Y576195D02*
Y577140D01*
G01Y572258D02*
Y573203D01*
G01Y568321D02*
Y569266D01*
G01Y564384D02*
Y565329D01*
G01Y560447D02*
Y561392D01*
G01D02*
Y560447D01*
G01Y565329D02*
Y564384D01*
G01Y569266D02*
Y568321D01*
G01Y577140D02*
Y576195D01*
G01Y573203D02*
Y572258D01*
G01Y581077D02*
Y580132D01*
G01X13424Y579935D02*
Y581274D01*
G01Y575998D02*
Y577337D01*
G01Y572061D02*
Y573400D01*
G01Y568124D02*
Y569463D01*
G01Y564187D02*
Y565526D01*
G01Y560250D02*
Y561589D01*
G01D02*
Y560250D01*
G01Y565526D02*
Y564187D01*
G01Y569463D02*
Y568124D01*
G01Y573400D02*
Y572061D01*
G01Y581274D02*
Y579935D01*
G01Y577337D02*
Y575998D01*
G01X12601Y579935D02*
Y581274D01*
G01Y575998D02*
Y577337D01*
G01Y572061D02*
Y573400D01*
G01Y568124D02*
Y569463D01*
G01Y564187D02*
Y565526D01*
G01Y560250D02*
Y561589D01*
G01D02*
Y560250D01*
G01Y565526D02*
Y564187D01*
G01Y569463D02*
Y568124D01*
G01Y573400D02*
Y572061D01*
G01Y581274D02*
Y579935D01*
G01Y577337D02*
Y575998D01*
G01X8523Y561589D02*
Y560250D01*
G01Y561589D02*
Y560250D01*
G01Y565526D02*
Y564187D01*
G01Y565526D02*
Y564187D01*
G01Y569463D02*
Y568124D01*
G01Y569463D02*
Y568124D01*
G01Y573400D02*
Y572061D01*
G01Y573400D02*
Y572061D01*
G01Y581274D02*
Y579935D01*
G01Y577337D02*
Y575998D01*
G01Y581274D02*
Y579935D01*
G01Y577337D02*
Y575998D01*
G01X0Y577337D02*
Y578124D01*
G01Y579148D02*
Y579935D01*
G01Y573400D02*
Y574187D01*
G01Y575211D02*
Y575998D01*
G01Y569463D02*
Y570250D01*
G01Y567337D02*
Y568124D01*
G01Y571274D02*
Y572061D01*
G01Y565526D02*
Y566313D01*
G01Y563400D02*
Y564187D01*
G01Y561589D02*
Y562376D01*
G01D02*
Y561589D01*
G01Y564187D02*
Y563400D01*
G01Y566313D02*
Y565526D01*
G01Y568124D02*
Y567337D01*
G01Y572061D02*
Y571274D01*
G01Y570250D02*
Y569463D01*
G01Y575998D02*
Y575211D01*
G01Y574187D02*
Y573400D01*
G01Y579935D02*
Y579148D01*
G01Y578124D02*
Y577337D01*
G01X-984Y579935D02*
Y581274D01*
G01Y575998D02*
Y577337D01*
G01Y572061D02*
Y573400D01*
G01Y568124D02*
Y569463D01*
G01Y564187D02*
Y565526D01*
G01Y560250D02*
Y561589D01*
G01D02*
Y560250D01*
G01Y565526D02*
Y564187D01*
G01Y569463D02*
Y568124D01*
G01Y573400D02*
Y572061D01*
G01Y581274D02*
Y579935D01*
G01Y577337D02*
Y575998D01*
G01X-2251Y566274D02*
Y563439D01*
G01Y570211D02*
Y567376D01*
G01Y574148D02*
Y571313D01*
G01Y578085D02*
Y575250D01*
G01Y582022D02*
Y579187D01*
G01X-2520Y562022D02*
Y559817D01*
G01Y565959D02*
Y563754D01*
G01Y569896D02*
Y567691D01*
G01Y573833D02*
Y571628D01*
G01Y581707D02*
Y579502D01*
G01Y577770D02*
Y575565D01*
G01X15078Y569463D02*
X15962Y569266D01*
G01D02*
X15078Y569463D01*
G01X14580D02*
X15464Y569266D01*
G01X14580Y569463D02*
X15464Y569266D01*
G01X15078Y565526D02*
X15962Y565329D01*
G01D02*
X15078Y565526D01*
G01X14580D02*
X15464Y565329D01*
G01X14580Y565526D02*
X15464Y565329D01*
G01X15078Y561589D02*
X15962Y561392D01*
G01D02*
X15078Y561589D01*
G01X14580D02*
X15464Y561392D01*
G01X14580Y561589D02*
X15464Y561392D01*
G01X-2196Y579541D02*
X-1969Y579148D01*
G01X-2196Y579541D02*
X-1969Y579148D01*
G01X-2196Y575604D02*
X-1969Y575211D01*
G01X-2196Y575604D02*
X-1969Y575211D01*
G01X-2196Y571667D02*
X-1969Y571274D01*
G01X-2196Y571667D02*
X-1969Y571274D01*
G01X-2196Y567730D02*
X-1969Y567337D01*
G01X-2196Y567730D02*
X-1969Y567337D01*
G01X-2196Y563793D02*
X-1969Y563400D01*
G01X-2196Y563793D02*
X-1969Y563400D01*
G01X14580Y599620D02*
X15464Y599817D01*
G01X14580Y599620D02*
X15464Y599817D01*
G01X15078Y599620D02*
X15962Y599817D01*
G01D02*
X15078Y599620D01*
G01X14580Y595683D02*
X15464Y595880D01*
G01X14580Y595683D02*
X15464Y595880D01*
G01X15078Y595683D02*
X15962Y595880D01*
G01D02*
X15078Y595683D01*
G01X14580Y591746D02*
X15464Y591943D01*
G01X14580Y591746D02*
X15464Y591943D01*
G01X15078Y591746D02*
X15962Y591943D01*
G01D02*
X15078Y591746D01*
G01X14580Y587809D02*
X15464Y588006D01*
G01X14580Y587809D02*
X15464Y588006D01*
G01X15078Y587809D02*
X15962Y588006D01*
G01D02*
X15078Y587809D01*
G01X14580Y583872D02*
X15464Y584069D01*
G01X14580Y583872D02*
X15464Y584069D01*
G01X15078Y583872D02*
X15962Y584069D01*
G01D02*
X15078Y583872D01*
G01X-1969Y582061D02*
X-2196Y581667D01*
G01X-1969Y582061D02*
X-2196Y581667D01*
G01X-1969Y585998D02*
X-2196Y585604D01*
G01X-1969Y585998D02*
X-2196Y585604D01*
G01X-1969Y589935D02*
X-2196Y589541D01*
G01X-1969Y589935D02*
X-2196Y589541D01*
G01X-1969Y593872D02*
X-2196Y593478D01*
G01X-1969Y593872D02*
X-2196Y593478D01*
G01X-1969Y597809D02*
X-2196Y597416D01*
G01X-1969Y597809D02*
X-2196Y597416D01*
G01X-1969Y601746D02*
X-2196Y601353D01*
G01X-1969Y601746D02*
X-2196Y601353D01*
G01X-1969Y601746D02*
X0D01*
G01X-1969D02*
X0D01*
G01X12601Y600959D02*
X15078D01*
G01X-984D02*
X15078D01*
G01X8523D02*
X12601D01*
G01X0D02*
X8523D01*
G01X0D02*
X-984D01*
G01X15464Y600762D02*
X15962D01*
G01D02*
X15464D01*
G01Y599817D02*
X15962D01*
G01D02*
X15464D01*
G01X8523Y599620D02*
X15078D01*
G01X-984D02*
X0D01*
G01X8523D02*
X0D01*
G01X15078D02*
X-984D01*
G01X-1969Y598833D02*
X0D01*
G01D02*
X-1969D01*
G01Y597809D02*
X0D01*
G01X-1969D02*
X0D01*
G01X12601Y597022D02*
X15078D01*
G01X-984D02*
X15078D01*
G01X8523D02*
X12601D01*
G01X0D02*
X8523D01*
G01X0D02*
X-984D01*
G01X15464Y596825D02*
X15962D01*
G01D02*
X15464D01*
G01Y595880D02*
X15962D01*
G01D02*
X15464D01*
G01X8523Y595683D02*
X15078D01*
G01X-984D02*
X0D01*
G01X8523D02*
X0D01*
G01X15078D02*
X-984D01*
G01X-1969Y594896D02*
X0D01*
G01D02*
X-1969D01*
G01Y593872D02*
X0D01*
G01X-1969D02*
X0D01*
G01X12601Y593085D02*
X15078D01*
G01X-984D02*
X15078D01*
G01X8523D02*
X12601D01*
G01X0D02*
X8523D01*
G01X0D02*
X-984D01*
G01X15464Y592888D02*
X15962D01*
G01D02*
X15464D01*
G01Y591943D02*
X15962D01*
G01D02*
X15464D01*
G01X8523Y591746D02*
X15078D01*
G01X-984D02*
X0D01*
G01X8523D02*
X0D01*
G01X15078D02*
X-984D01*
G01X-1969Y590959D02*
X0D01*
G01D02*
X-1969D01*
G01Y589935D02*
X0D01*
G01X-1969D02*
X0D01*
G01X12601Y589148D02*
X15078D01*
G01X-984D02*
X15078D01*
G01X8523D02*
X12601D01*
G01X0D02*
X8523D01*
G01X0D02*
X-984D01*
G01X15464Y588951D02*
X15962D01*
G01D02*
X15464D01*
G01Y588006D02*
X15962D01*
G01D02*
X15464D01*
G01X8523Y587809D02*
X15078D01*
G01X-984D02*
X0D01*
G01X8523D02*
X0D01*
G01X15078D02*
X-984D01*
G01X-1969Y587022D02*
X0D01*
G01D02*
X-1969D01*
G01Y585998D02*
X0D01*
G01X-1969D02*
X0D01*
G01X12601Y585211D02*
X15078D01*
G01X-984D02*
X15078D01*
G01X8523D02*
X12601D01*
G01X0D02*
X8523D01*
G01X0D02*
X-984D01*
G01X15464Y585014D02*
X15962D01*
G01D02*
X15464D01*
G01Y584069D02*
X15962D01*
G01D02*
X15464D01*
G01X8523Y583872D02*
X15078D01*
G01X-984D02*
X0D01*
G01X8523D02*
X0D01*
G01X15078D02*
X-984D01*
G01X-1969Y583085D02*
X0D01*
G01D02*
X-1969D01*
G01Y582061D02*
X0D01*
G01X-1969D02*
X0D01*
G01X12601Y581274D02*
X15078D01*
G01X-984D02*
X15078D01*
G01X8523D02*
X12601D01*
G01X0D02*
X8523D01*
G01X0D02*
X-984D01*
G01X15464Y581077D02*
X15962D01*
G01D02*
X15464D01*
G01X15078Y600959D02*
X15962Y600762D01*
G01D02*
X15078Y600959D01*
G01X14580D02*
X15464Y600762D01*
G01X14580Y600959D02*
X15464Y600762D01*
G01X15078Y597022D02*
X15962Y596825D01*
G01D02*
X15078Y597022D01*
G01X14580D02*
X15464Y596825D01*
G01X14580Y597022D02*
X15464Y596825D01*
G01X15078Y593085D02*
X15962Y592888D01*
G01D02*
X15078Y593085D01*
G01X14580D02*
X15464Y592888D01*
G01X14580Y593085D02*
X15464Y592888D01*
G01X15078Y589148D02*
X15962Y588951D01*
G01D02*
X15078Y589148D01*
G01X14580D02*
X15464Y588951D01*
G01X14580Y589148D02*
X15464Y588951D01*
G01X15078Y585211D02*
X15962Y585014D01*
G01D02*
X15078Y585211D01*
G01X14580D02*
X15464Y585014D01*
G01X14580Y585211D02*
X15464Y585014D01*
G01X15078Y581274D02*
X15962Y581077D01*
G01D02*
X15078Y581274D01*
G01X14580D02*
X15464Y581077D01*
G01X14580Y581274D02*
X15464Y581077D01*
G01X15962Y599817D02*
Y600762D01*
G01Y595880D02*
Y596825D01*
G01Y591943D02*
Y592888D01*
G01Y588006D02*
Y588951D01*
G01Y584069D02*
Y585014D01*
G01D02*
Y584069D01*
G01Y588951D02*
Y588006D01*
G01Y592888D02*
Y591943D01*
G01Y596825D02*
Y595880D01*
G01Y600762D02*
Y599817D01*
G01X15464D02*
Y600762D01*
G01Y595880D02*
Y596825D01*
G01Y591943D02*
Y592888D01*
G01Y588006D02*
Y588951D01*
G01Y584069D02*
Y585014D01*
G01D02*
Y584069D01*
G01Y588951D02*
Y588006D01*
G01Y592888D02*
Y591943D01*
G01Y596825D02*
Y595880D01*
G01Y600762D02*
Y599817D01*
G01X13424Y599620D02*
Y600959D01*
G01Y595683D02*
Y597022D01*
G01Y591746D02*
Y593085D01*
G01Y587809D02*
Y589148D01*
G01Y583872D02*
Y585211D01*
G01D02*
Y583872D01*
G01Y589148D02*
Y587809D01*
G01Y593085D02*
Y591746D01*
G01Y597022D02*
Y595683D01*
G01Y600959D02*
Y599620D01*
G01X12601D02*
Y600959D01*
G01Y595683D02*
Y597022D01*
G01Y591746D02*
Y593085D01*
G01Y587809D02*
Y589148D01*
G01Y583872D02*
Y585211D01*
G01D02*
Y583872D01*
G01Y589148D02*
Y587809D01*
G01Y593085D02*
Y591746D01*
G01Y597022D02*
Y595683D01*
G01Y600959D02*
Y599620D01*
G01X8523Y585211D02*
Y583872D01*
G01Y585211D02*
Y583872D01*
G01Y589148D02*
Y587809D01*
G01Y589148D02*
Y587809D01*
G01Y593085D02*
Y591746D01*
G01Y593085D02*
Y591746D01*
G01Y597022D02*
Y595683D01*
G01Y597022D02*
Y595683D01*
G01Y600959D02*
Y599620D01*
G01Y600959D02*
Y599620D01*
G01X0Y600959D02*
Y601746D01*
G01Y597022D02*
Y597809D01*
G01Y598833D02*
Y599620D01*
G01Y593085D02*
Y593872D01*
G01Y590959D02*
Y591746D01*
G01Y594896D02*
Y595683D01*
G01Y589148D02*
Y589935D01*
G01Y587022D02*
Y587809D01*
G01Y581274D02*
Y582061D01*
G01Y585211D02*
Y585998D01*
G01Y583085D02*
Y583872D01*
G01D02*
Y583085D01*
G01Y582061D02*
Y581274D01*
G01Y585998D02*
Y585211D01*
G01Y587809D02*
Y587022D01*
G01Y589935D02*
Y589148D01*
G01Y591746D02*
Y590959D01*
G01Y595683D02*
Y594896D01*
G01Y593872D02*
Y593085D01*
G01Y599620D02*
Y598833D01*
G01Y597809D02*
Y597022D01*
G01Y601746D02*
Y600959D01*
G01X-984Y599620D02*
Y600959D01*
G01Y595683D02*
Y597022D01*
G01Y591746D02*
Y593085D01*
G01Y587809D02*
Y589148D01*
G01Y583872D02*
Y585211D01*
G01D02*
Y583872D01*
G01Y589148D02*
Y587809D01*
G01Y593085D02*
Y591746D01*
G01Y597022D02*
Y595683D01*
G01Y600959D02*
Y599620D01*
G01X-2251Y585959D02*
Y583124D01*
G01Y589896D02*
Y587061D01*
G01Y593833D02*
Y590998D01*
G01Y597770D02*
Y594935D01*
G01Y601707D02*
Y598872D01*
G01X-2520Y585644D02*
Y583439D01*
G01Y589581D02*
Y587376D01*
G01Y593518D02*
Y591313D01*
G01Y597455D02*
Y595250D01*
G01Y601392D02*
Y599187D01*
G01X-2196Y599227D02*
X-1969Y598833D01*
G01X-2196Y599227D02*
X-1969Y598833D01*
G01X-2196Y595290D02*
X-1969Y594896D01*
G01X-2196Y595290D02*
X-1969Y594896D01*
G01X-2196Y591353D02*
X-1969Y590959D01*
G01X-2196Y591353D02*
X-1969Y590959D01*
G01X-2196Y587416D02*
X-1969Y587022D01*
G01X-2196Y587416D02*
X-1969Y587022D01*
G01X-2196Y583478D02*
X-1969Y583085D01*
G01X-2196Y583478D02*
X-1969Y583085D01*
G01X14580Y619305D02*
X15464Y619502D01*
G01X14580Y619305D02*
X15464Y619502D01*
G01X15078Y619305D02*
X15962Y619502D01*
G01D02*
X15078Y619305D01*
G01X14580Y615368D02*
X15464Y615565D01*
G01X14580Y615368D02*
X15464Y615565D01*
G01X15078Y615368D02*
X15962Y615565D01*
G01D02*
X15078Y615368D01*
G01X14580Y611431D02*
X15464Y611628D01*
G01X14580Y611431D02*
X15464Y611628D01*
G01X15078Y611431D02*
X15962Y611628D01*
G01D02*
X15078Y611431D01*
G01X14580Y607494D02*
X15464Y607691D01*
G01X14580Y607494D02*
X15464Y607691D01*
G01X15078Y607494D02*
X15962Y607691D01*
G01D02*
X15078Y607494D01*
G01X14580Y603557D02*
X15464Y603754D01*
G01X14580Y603557D02*
X15464Y603754D01*
G01X15078Y603557D02*
X15962Y603754D01*
G01D02*
X15078Y603557D01*
G01X-1969Y605683D02*
X-2196Y605290D01*
G01X-1969Y605683D02*
X-2196Y605290D01*
G01X-1969Y609620D02*
X-2196Y609227D01*
G01X-1969Y609620D02*
X-2196Y609227D01*
G01X-1969Y613557D02*
X-2196Y613164D01*
G01X-1969Y613557D02*
X-2196Y613164D01*
G01X-1969Y617494D02*
X-2196Y617101D01*
G01X-1969Y617494D02*
X-2196Y617101D01*
G01X-1969Y621431D02*
X-2196Y621038D01*
G01X-1969Y621431D02*
X-2196Y621038D01*
G01X-1969Y622455D02*
X0D01*
G01D02*
X-1969D01*
G01Y621431D02*
X0D01*
G01X-1969D02*
X0D01*
G01X12601Y620644D02*
X15078D01*
G01X-984D02*
X15078D01*
G01X8523D02*
X12601D01*
G01X0D02*
X8523D01*
G01X0D02*
X-984D01*
G01X15464Y620447D02*
X15962D01*
G01D02*
X15464D01*
G01Y619502D02*
X15962D01*
G01D02*
X15464D01*
G01X8523Y619305D02*
X15078D01*
G01X-984D02*
X0D01*
G01X8523D02*
X0D01*
G01X15078D02*
X-984D01*
G01X-1969Y618518D02*
X0D01*
G01D02*
X-1969D01*
G01Y617494D02*
X0D01*
G01X-1969D02*
X0D01*
G01X12601Y616707D02*
X15078D01*
G01X-984D02*
X15078D01*
G01X8523D02*
X12601D01*
G01X0D02*
X8523D01*
G01X0D02*
X-984D01*
G01X15464Y616510D02*
X15962D01*
G01D02*
X15464D01*
G01Y615565D02*
X15962D01*
G01D02*
X15464D01*
G01X8523Y615368D02*
X15078D01*
G01X-984D02*
X0D01*
G01X8523D02*
X0D01*
G01X15078D02*
X-984D01*
G01X-1969Y614581D02*
X0D01*
G01D02*
X-1969D01*
G01Y613557D02*
X0D01*
G01X-1969D02*
X0D01*
G01X12601Y612770D02*
X15078D01*
G01X-984D02*
X15078D01*
G01X8523D02*
X12601D01*
G01X0D02*
X8523D01*
G01X0D02*
X-984D01*
G01X15464Y612573D02*
X15962D01*
G01D02*
X15464D01*
G01Y611628D02*
X15962D01*
G01D02*
X15464D01*
G01X8523Y611431D02*
X15078D01*
G01X-984D02*
X0D01*
G01X8523D02*
X0D01*
G01X15078D02*
X-984D01*
G01X-1969Y610644D02*
X0D01*
G01D02*
X-1969D01*
G01Y609620D02*
X0D01*
G01X-1969D02*
X0D01*
G01X12601Y608833D02*
X15078D01*
G01X-984D02*
X15078D01*
G01X8523D02*
X12601D01*
G01X0D02*
X8523D01*
G01X0D02*
X-984D01*
G01X15464Y608636D02*
X15962D01*
G01D02*
X15464D01*
G01Y607691D02*
X15962D01*
G01D02*
X15464D01*
G01X8523Y607494D02*
X15078D01*
G01X-984D02*
X0D01*
G01X8523D02*
X0D01*
G01X15078D02*
X-984D01*
G01X-1969Y606707D02*
X0D01*
G01D02*
X-1969D01*
G01Y605683D02*
X0D01*
G01X-1969D02*
X0D01*
G01X12601Y604896D02*
X15078D01*
G01X-984D02*
X15078D01*
G01X8523D02*
X12601D01*
G01X0D02*
X8523D01*
G01X0D02*
X-984D01*
G01X15464Y604699D02*
X15962D01*
G01D02*
X15464D01*
G01Y603754D02*
X15962D01*
G01D02*
X15464D01*
G01X8523Y603557D02*
X15078D01*
G01X-984D02*
X0D01*
G01X8523D02*
X0D01*
G01X15078D02*
X-984D01*
G01X-1969Y602770D02*
X0D01*
G01D02*
X-1969D01*
G01X15078Y620644D02*
X15962Y620447D01*
G01D02*
X15078Y620644D01*
G01X14580D02*
X15464Y620447D01*
G01X14580Y620644D02*
X15464Y620447D01*
G01X15078Y616707D02*
X15962Y616510D01*
G01D02*
X15078Y616707D01*
G01X14580D02*
X15464Y616510D01*
G01X14580Y616707D02*
X15464Y616510D01*
G01X15078Y612770D02*
X15962Y612573D01*
G01D02*
X15078Y612770D01*
G01X14580D02*
X15464Y612573D01*
G01X14580Y612770D02*
X15464Y612573D01*
G01X15078Y608833D02*
X15962Y608636D01*
G01D02*
X15078Y608833D01*
G01X14580D02*
X15464Y608636D01*
G01X14580Y608833D02*
X15464Y608636D01*
G01X15078Y604896D02*
X15962Y604699D01*
G01D02*
X15078Y604896D01*
G01X14580D02*
X15464Y604699D01*
G01X14580Y604896D02*
X15464Y604699D01*
G01X15962Y619502D02*
Y620447D01*
G01Y615565D02*
Y616510D01*
G01Y611628D02*
Y612573D01*
G01Y607691D02*
Y608636D01*
G01Y603754D02*
Y604699D01*
G01D02*
Y603754D01*
G01Y608636D02*
Y607691D01*
G01Y612573D02*
Y611628D01*
G01Y616510D02*
Y615565D01*
G01Y620447D02*
Y619502D01*
G01X15464D02*
Y620447D01*
G01Y615565D02*
Y616510D01*
G01Y611628D02*
Y612573D01*
G01Y607691D02*
Y608636D01*
G01Y603754D02*
Y604699D01*
G01D02*
Y603754D01*
G01Y608636D02*
Y607691D01*
G01Y612573D02*
Y611628D01*
G01Y616510D02*
Y615565D01*
G01Y620447D02*
Y619502D01*
G01X13424Y619305D02*
Y620644D01*
G01Y615368D02*
Y616707D01*
G01Y611431D02*
Y612770D01*
G01Y607494D02*
Y608833D01*
G01Y603557D02*
Y604896D01*
G01D02*
Y603557D01*
G01Y608833D02*
Y607494D01*
G01Y612770D02*
Y611431D01*
G01Y616707D02*
Y615368D01*
G01Y620644D02*
Y619305D01*
G01X12601D02*
Y620644D01*
G01Y615368D02*
Y616707D01*
G01Y611431D02*
Y612770D01*
G01Y607494D02*
Y608833D01*
G01Y603557D02*
Y604896D01*
G01D02*
Y603557D01*
G01Y608833D02*
Y607494D01*
G01Y612770D02*
Y611431D01*
G01Y616707D02*
Y615368D01*
G01Y620644D02*
Y619305D01*
G01X8523Y604896D02*
Y603557D01*
G01Y604896D02*
Y603557D01*
G01Y608833D02*
Y607494D01*
G01Y608833D02*
Y607494D01*
G01Y612770D02*
Y611431D01*
G01Y612770D02*
Y611431D01*
G01Y616707D02*
Y615368D01*
G01Y616707D02*
Y615368D01*
G01Y620644D02*
Y619305D01*
G01Y620644D02*
Y619305D01*
G01X0Y620644D02*
Y621431D01*
G01Y618518D02*
Y619305D01*
G01Y622455D02*
Y623242D01*
G01Y616707D02*
Y617494D01*
G01Y614581D02*
Y615368D01*
G01Y612770D02*
Y613557D01*
G01Y610644D02*
Y611431D01*
G01Y604896D02*
Y605683D01*
G01Y608833D02*
Y609620D01*
G01Y606707D02*
Y607494D01*
G01Y602770D02*
Y603557D01*
G01D02*
Y602770D01*
G01Y607494D02*
Y606707D01*
G01Y605683D02*
Y604896D01*
G01Y609620D02*
Y608833D01*
G01Y611431D02*
Y610644D01*
G01Y613557D02*
Y612770D01*
G01Y615368D02*
Y614581D01*
G01Y617494D02*
Y616707D01*
G01Y619305D02*
Y618518D01*
G01Y623242D02*
Y622455D01*
G01Y621431D02*
Y620644D01*
G01X-984Y619305D02*
Y620644D01*
G01Y615368D02*
Y616707D01*
G01Y611431D02*
Y612770D01*
G01Y607494D02*
Y608833D01*
G01Y603557D02*
Y604896D01*
G01D02*
Y603557D01*
G01Y608833D02*
Y607494D01*
G01Y612770D02*
Y611431D01*
G01Y616707D02*
Y615368D01*
G01Y620644D02*
Y619305D01*
G01X-2251Y605644D02*
Y602809D01*
G01Y609581D02*
Y606746D01*
G01Y613518D02*
Y610683D01*
G01Y617455D02*
Y614620D01*
G01Y621392D02*
Y618557D01*
G01Y625329D02*
Y622494D01*
G01X-2520Y609266D02*
Y607061D01*
G01Y605329D02*
Y603124D01*
G01Y613203D02*
Y610998D01*
G01Y617140D02*
Y614935D01*
G01Y621077D02*
Y618872D01*
G01Y625014D02*
Y622809D01*
G01X-2196Y622849D02*
X-1969Y622455D01*
G01X-2196Y622849D02*
X-1969Y622455D01*
G01X-2196Y618912D02*
X-1969Y618518D01*
G01X-2196Y618912D02*
X-1969Y618518D01*
G01X-2196Y614975D02*
X-1969Y614581D01*
G01X-2196Y614975D02*
X-1969Y614581D01*
G01X-2196Y611038D02*
X-1969Y610644D01*
G01X-2196Y611038D02*
X-1969Y610644D01*
G01X-2196Y607101D02*
X-1969Y606707D01*
G01X-2196Y607101D02*
X-1969Y606707D01*
G01X-2196Y603164D02*
X-1969Y602770D01*
G01X-2196Y603164D02*
X-1969Y602770D01*
G01X14580Y642927D02*
X15464Y643124D01*
G01X14580Y642927D02*
X15464Y643124D01*
G01X15078Y642927D02*
X15962Y643124D01*
G01D02*
X15078Y642927D01*
G01X14580Y638990D02*
X15464Y639187D01*
G01X14580Y638990D02*
X15464Y639187D01*
G01X15078Y638990D02*
X15962Y639187D01*
G01D02*
X15078Y638990D01*
G01X14580Y635053D02*
X15464Y635250D01*
G01X14580Y635053D02*
X15464Y635250D01*
G01X15078Y635053D02*
X15962Y635250D01*
G01D02*
X15078Y635053D01*
G01X14580Y631116D02*
X15464Y631313D01*
G01X14580Y631116D02*
X15464Y631313D01*
G01X15078Y631116D02*
X15962Y631313D01*
G01D02*
X15078Y631116D01*
G01X14580Y627179D02*
X15464Y627376D01*
G01X14580Y627179D02*
X15464Y627376D01*
G01X15078Y627179D02*
X15962Y627376D01*
G01D02*
X15078Y627179D01*
G01X14580Y623242D02*
X15464Y623439D01*
G01X14580Y623242D02*
X15464Y623439D01*
G01X15078Y623242D02*
X15962Y623439D01*
G01D02*
X15078Y623242D01*
G01X-1969Y625368D02*
X-2196Y624975D01*
G01X-1969Y625368D02*
X-2196Y624975D01*
G01X-1969Y629305D02*
X-2196Y628912D01*
G01X-1969Y629305D02*
X-2196Y628912D01*
G01X-1969Y633242D02*
X-2196Y632849D01*
G01X-1969Y633242D02*
X-2196Y632849D01*
G01X-1969Y637179D02*
X-2196Y636786D01*
G01X-1969Y637179D02*
X-2196Y636786D01*
G01X-1969Y641116D02*
X-2196Y640723D01*
G01X-1969Y641116D02*
X-2196Y640723D01*
G01X12601Y644266D02*
X15078D01*
G01X-984D02*
X15078D01*
G01X8523D02*
X12601D01*
G01X0D02*
X8523D01*
G01X0D02*
X-984D01*
G01X15464Y644069D02*
X15962D01*
G01D02*
X15464D01*
G01Y643124D02*
X15962D01*
G01D02*
X15464D01*
G01X8523Y642927D02*
X15078D01*
G01X-984D02*
X0D01*
G01X8523D02*
X0D01*
G01X15078D02*
X-984D01*
G01X-1969Y642140D02*
X0D01*
G01D02*
X-1969D01*
G01Y641116D02*
X0D01*
G01X-1969D02*
X0D01*
G01X12601Y640329D02*
X15078D01*
G01X-984D02*
X15078D01*
G01X8523D02*
X12601D01*
G01X0D02*
X8523D01*
G01X0D02*
X-984D01*
G01X15464Y640132D02*
X15962D01*
G01D02*
X15464D01*
G01Y639187D02*
X15962D01*
G01D02*
X15464D01*
G01X8523Y638990D02*
X15078D01*
G01X-984D02*
X0D01*
G01X8523D02*
X0D01*
G01X15078D02*
X-984D01*
G01X-1969Y638203D02*
X0D01*
G01D02*
X-1969D01*
G01Y637179D02*
X0D01*
G01X-1969D02*
X0D01*
G01X12601Y636392D02*
X15078D01*
G01X-984D02*
X15078D01*
G01X8523D02*
X12601D01*
G01X0D02*
X8523D01*
G01X0D02*
X-984D01*
G01X15464Y636195D02*
X15962D01*
G01D02*
X15464D01*
G01Y635250D02*
X15962D01*
G01D02*
X15464D01*
G01X8523Y635053D02*
X15078D01*
G01X-984D02*
X0D01*
G01X8523D02*
X0D01*
G01X15078D02*
X-984D01*
G01X-1969Y634266D02*
X0D01*
G01D02*
X-1969D01*
G01Y633242D02*
X0D01*
G01X-1969D02*
X0D01*
G01X12601Y632455D02*
X15078D01*
G01X-984D02*
X15078D01*
G01X8523D02*
X12601D01*
G01X0D02*
X8523D01*
G01X0D02*
X-984D01*
G01X15464Y632258D02*
X15962D01*
G01D02*
X15464D01*
G01Y631313D02*
X15962D01*
G01D02*
X15464D01*
G01X8523Y631116D02*
X15078D01*
G01X-984D02*
X0D01*
G01X8523D02*
X0D01*
G01X15078D02*
X-984D01*
G01X-1969Y630329D02*
X0D01*
G01D02*
X-1969D01*
G01Y629305D02*
X0D01*
G01X-1969D02*
X0D01*
G01X12601Y628518D02*
X15078D01*
G01X-984D02*
X15078D01*
G01X8523D02*
X12601D01*
G01X0D02*
X8523D01*
G01X0D02*
X-984D01*
G01X15464Y628321D02*
X15962D01*
G01D02*
X15464D01*
G01Y627376D02*
X15962D01*
G01D02*
X15464D01*
G01X8523Y627179D02*
X15078D01*
G01X-984D02*
X0D01*
G01X8523D02*
X0D01*
G01X15078D02*
X-984D01*
G01X-1969Y626392D02*
X0D01*
G01D02*
X-1969D01*
G01Y625368D02*
X0D01*
G01X-1969D02*
X0D01*
G01X12601Y624581D02*
X15078D01*
G01X-984D02*
X15078D01*
G01X8523D02*
X12601D01*
G01X0D02*
X8523D01*
G01X0D02*
X-984D01*
G01X15464Y624384D02*
X15962D01*
G01D02*
X15464D01*
G01Y623439D02*
X15962D01*
G01D02*
X15464D01*
G01X8523Y623242D02*
X15078D01*
G01X-984D02*
X0D01*
G01X8523D02*
X0D01*
G01X15078D02*
X-984D01*
G01X15078Y644266D02*
X15962Y644069D01*
G01D02*
X15078Y644266D01*
G01X14580D02*
X15464Y644069D01*
G01X14580Y644266D02*
X15464Y644069D01*
G01X15078Y640329D02*
X15962Y640132D01*
G01D02*
X15078Y640329D01*
G01X14580D02*
X15464Y640132D01*
G01X14580Y640329D02*
X15464Y640132D01*
G01X15078Y636392D02*
X15962Y636195D01*
G01D02*
X15078Y636392D01*
G01X14580D02*
X15464Y636195D01*
G01X14580Y636392D02*
X15464Y636195D01*
G01X15078Y632455D02*
X15962Y632258D01*
G01D02*
X15078Y632455D01*
G01X14580D02*
X15464Y632258D01*
G01X14580Y632455D02*
X15464Y632258D01*
G01X15078Y628518D02*
X15962Y628321D01*
G01D02*
X15078Y628518D01*
G01X14580D02*
X15464Y628321D01*
G01X14580Y628518D02*
X15464Y628321D01*
G01X15078Y624581D02*
X15962Y624384D01*
G01D02*
X15078Y624581D01*
G01X14580D02*
X15464Y624384D01*
G01X14580Y624581D02*
X15464Y624384D01*
G01X15962Y643124D02*
Y644069D01*
G01Y639187D02*
Y640132D01*
G01Y635250D02*
Y636195D01*
G01Y631313D02*
Y632258D01*
G01Y623439D02*
Y624384D01*
G01Y627376D02*
Y628321D01*
G01Y624384D02*
Y623439D01*
G01Y628321D02*
Y627376D01*
G01Y632258D02*
Y631313D01*
G01Y636195D02*
Y635250D01*
G01Y640132D02*
Y639187D01*
G01Y644069D02*
Y643124D01*
G01X15464D02*
Y644069D01*
G01Y639187D02*
Y640132D01*
G01Y635250D02*
Y636195D01*
G01Y631313D02*
Y632258D01*
G01Y627376D02*
Y628321D01*
G01Y623439D02*
Y624384D01*
G01D02*
Y623439D01*
G01Y628321D02*
Y627376D01*
G01Y632258D02*
Y631313D01*
G01Y636195D02*
Y635250D01*
G01Y640132D02*
Y639187D01*
G01Y644069D02*
Y643124D01*
G01X13424Y642927D02*
Y644266D01*
G01Y638990D02*
Y640329D01*
G01Y635053D02*
Y636392D01*
G01Y631116D02*
Y632455D01*
G01Y623242D02*
Y624581D01*
G01Y627179D02*
Y628518D01*
G01D02*
Y627179D01*
G01Y624581D02*
Y623242D01*
G01Y632455D02*
Y631116D01*
G01Y636392D02*
Y635053D01*
G01Y640329D02*
Y638990D01*
G01Y644266D02*
Y642927D01*
G01X12601D02*
Y644266D01*
G01Y638990D02*
Y640329D01*
G01Y635053D02*
Y636392D01*
G01Y631116D02*
Y632455D01*
G01Y623242D02*
Y624581D01*
G01Y627179D02*
Y628518D01*
G01D02*
Y627179D01*
G01Y624581D02*
Y623242D01*
G01Y632455D02*
Y631116D01*
G01Y636392D02*
Y635053D01*
G01Y640329D02*
Y638990D01*
G01Y644266D02*
Y642927D01*
G01X8523Y624581D02*
Y623242D01*
G01Y628518D02*
Y627179D01*
G01Y624581D02*
Y623242D01*
G01Y628518D02*
Y627179D01*
G01Y632455D02*
Y631116D01*
G01Y632455D02*
Y631116D01*
G01Y636392D02*
Y635053D01*
G01Y636392D02*
Y635053D01*
G01Y640329D02*
Y638990D01*
G01Y640329D02*
Y638990D01*
G01Y644266D02*
Y642927D01*
G01Y644266D02*
Y642927D01*
G01X0Y644266D02*
Y645053D01*
G01Y642140D02*
Y642927D01*
G01Y640329D02*
Y641116D01*
G01Y638203D02*
Y638990D01*
G01Y636392D02*
Y637179D01*
G01Y634266D02*
Y635053D01*
G01Y628518D02*
Y629305D01*
G01Y632455D02*
Y633242D01*
G01Y630329D02*
Y631116D01*
G01Y624581D02*
Y625368D01*
G01Y626392D02*
Y627179D01*
G01D02*
Y626392D01*
G01Y625368D02*
Y624581D01*
G01Y631116D02*
Y630329D01*
G01Y629305D02*
Y628518D01*
G01Y633242D02*
Y632455D01*
G01Y635053D02*
Y634266D01*
G01Y637179D02*
Y636392D01*
G01Y638990D02*
Y638203D01*
G01Y641116D02*
Y640329D01*
G01Y642927D02*
Y642140D01*
G01Y645053D02*
Y644266D01*
G01X-984Y642927D02*
Y644266D01*
G01Y638990D02*
Y640329D01*
G01Y635053D02*
Y636392D01*
G01Y631116D02*
Y632455D01*
G01Y627179D02*
Y628518D01*
G01Y623242D02*
Y624581D01*
G01Y628518D02*
Y627179D01*
G01Y624581D02*
Y623242D01*
G01Y632455D02*
Y631116D01*
G01Y636392D02*
Y635053D01*
G01Y640329D02*
Y638990D01*
G01Y644266D02*
Y642927D01*
G01X-2251Y629266D02*
Y626431D01*
G01Y633203D02*
Y630368D01*
G01Y637140D02*
Y634305D01*
G01Y641077D02*
Y638242D01*
G01Y645014D02*
Y642179D01*
G01X-2520Y632888D02*
Y630683D01*
G01Y628951D02*
Y626746D01*
G01Y636825D02*
Y634620D01*
G01Y640762D02*
Y638557D01*
G01Y644699D02*
Y642494D01*
G01X-2196Y642534D02*
X-1969Y642140D01*
G01X-2196Y642534D02*
X-1969Y642140D01*
G01X-2196Y638597D02*
X-1969Y638203D01*
G01X-2196Y638597D02*
X-1969Y638203D01*
G01X-2196Y634660D02*
X-1969Y634266D01*
G01X-2196Y634660D02*
X-1969Y634266D01*
G01X-2196Y630723D02*
X-1969Y630329D01*
G01X-2196Y630723D02*
X-1969Y630329D01*
G01X-2196Y626786D02*
X-1969Y626392D01*
G01X-2196Y626786D02*
X-1969Y626392D01*
G01X14580Y662612D02*
X15464Y662809D01*
G01X14580Y662612D02*
X15464Y662809D01*
G01X15078Y662612D02*
X15962Y662809D01*
G01D02*
X15078Y662612D01*
G01X14580Y658675D02*
X15464Y658872D01*
G01X14580Y658675D02*
X15464Y658872D01*
G01X15078Y658675D02*
X15962Y658872D01*
G01D02*
X15078Y658675D01*
G01X14580Y654738D02*
X15464Y654935D01*
G01X14580Y654738D02*
X15464Y654935D01*
G01X15078Y654738D02*
X15962Y654935D01*
G01D02*
X15078Y654738D01*
G01X14580Y650801D02*
X15464Y650998D01*
G01X14580Y650801D02*
X15464Y650998D01*
G01X15078Y650801D02*
X15962Y650998D01*
G01D02*
X15078Y650801D01*
G01X14580Y646864D02*
X15464Y647061D01*
G01X14580Y646864D02*
X15464Y647061D01*
G01X15078Y646864D02*
X15962Y647061D01*
G01D02*
X15078Y646864D01*
G01X-1969Y645053D02*
X-2196Y644660D01*
G01X-1969Y645053D02*
X-2196Y644660D01*
G01X-1969Y648990D02*
X-2196Y648597D01*
G01X-1969Y648990D02*
X-2196Y648597D01*
G01X-1969Y652927D02*
X-2196Y652534D01*
G01X-1969Y652927D02*
X-2196Y652534D01*
G01X-1969Y656864D02*
X-2196Y656471D01*
G01X-1969Y656864D02*
X-2196Y656471D01*
G01X-1969Y660801D02*
X-2196Y660408D01*
G01X-1969Y660801D02*
X-2196Y660408D01*
G01X-1969Y664738D02*
X-2196Y664345D01*
G01X-1969Y664738D02*
X-2196Y664345D01*
G01X-1969Y664738D02*
X0D01*
G01X-1969D02*
X0D01*
G01X12601Y663951D02*
X15078D01*
G01X-984D02*
X15078D01*
G01X8523D02*
X12601D01*
G01X0D02*
X8523D01*
G01X0D02*
X-984D01*
G01X15464Y663754D02*
X15962D01*
G01D02*
X15464D01*
G01Y662809D02*
X15962D01*
G01D02*
X15464D01*
G01X8523Y662612D02*
X15078D01*
G01X-984D02*
X0D01*
G01X8523D02*
X0D01*
G01X15078D02*
X-984D01*
G01X-1969Y661825D02*
X0D01*
G01D02*
X-1969D01*
G01Y660801D02*
X0D01*
G01X-1969D02*
X0D01*
G01X12601Y660014D02*
X15078D01*
G01X-984D02*
X15078D01*
G01X8523D02*
X12601D01*
G01X0D02*
X8523D01*
G01X0D02*
X-984D01*
G01X15464Y659817D02*
X15962D01*
G01D02*
X15464D01*
G01Y658872D02*
X15962D01*
G01D02*
X15464D01*
G01X8523Y658675D02*
X15078D01*
G01X-984D02*
X0D01*
G01X8523D02*
X0D01*
G01X15078D02*
X-984D01*
G01X-1969Y657888D02*
X0D01*
G01D02*
X-1969D01*
G01Y656864D02*
X0D01*
G01X-1969D02*
X0D01*
G01X12601Y656077D02*
X15078D01*
G01X-984D02*
X15078D01*
G01X8523D02*
X12601D01*
G01X0D02*
X8523D01*
G01X0D02*
X-984D01*
G01X15464Y655880D02*
X15962D01*
G01D02*
X15464D01*
G01Y654935D02*
X15962D01*
G01D02*
X15464D01*
G01X8523Y654738D02*
X15078D01*
G01X-984D02*
X0D01*
G01X8523D02*
X0D01*
G01X15078D02*
X-984D01*
G01X-1969Y653951D02*
X0D01*
G01D02*
X-1969D01*
G01Y652927D02*
X0D01*
G01X-1969D02*
X0D01*
G01X12601Y652140D02*
X15078D01*
G01X-984D02*
X15078D01*
G01X8523D02*
X12601D01*
G01X0D02*
X8523D01*
G01X0D02*
X-984D01*
G01X15464Y651943D02*
X15962D01*
G01D02*
X15464D01*
G01Y650998D02*
X15962D01*
G01D02*
X15464D01*
G01X8523Y650801D02*
X15078D01*
G01X-984D02*
X0D01*
G01X8523D02*
X0D01*
G01X15078D02*
X-984D01*
G01X-1969Y650014D02*
X0D01*
G01D02*
X-1969D01*
G01Y648990D02*
X0D01*
G01X-1969D02*
X0D01*
G01X12601Y648203D02*
X15078D01*
G01X-984D02*
X15078D01*
G01X8523D02*
X12601D01*
G01X0D02*
X8523D01*
G01X0D02*
X-984D01*
G01X15464Y648006D02*
X15962D01*
G01D02*
X15464D01*
G01Y647061D02*
X15962D01*
G01D02*
X15464D01*
G01X8523Y646864D02*
X15078D01*
G01X-984D02*
X0D01*
G01X8523D02*
X0D01*
G01X15078D02*
X-984D01*
G01X-1969Y646077D02*
X0D01*
G01D02*
X-1969D01*
G01Y645053D02*
X0D01*
G01X-1969D02*
X0D01*
G01X15078Y663951D02*
X15962Y663754D01*
G01D02*
X15078Y663951D01*
G01X14580D02*
X15464Y663754D01*
G01X14580Y663951D02*
X15464Y663754D01*
G01X15078Y660014D02*
X15962Y659817D01*
G01D02*
X15078Y660014D01*
G01X14580D02*
X15464Y659817D01*
G01X14580Y660014D02*
X15464Y659817D01*
G01X15078Y656077D02*
X15962Y655880D01*
G01D02*
X15078Y656077D01*
G01X14580D02*
X15464Y655880D01*
G01X14580Y656077D02*
X15464Y655880D01*
G01X15078Y652140D02*
X15962Y651943D01*
G01D02*
X15078Y652140D01*
G01X14580D02*
X15464Y651943D01*
G01X14580Y652140D02*
X15464Y651943D01*
G01X15078Y648203D02*
X15962Y648006D01*
G01D02*
X15078Y648203D01*
G01X14580D02*
X15464Y648006D01*
G01X14580Y648203D02*
X15464Y648006D01*
G01X15962Y662809D02*
Y663754D01*
G01Y658872D02*
Y659817D01*
G01Y654935D02*
Y655880D01*
G01Y647061D02*
Y648006D01*
G01Y650998D02*
Y651943D01*
G01Y648006D02*
Y647061D01*
G01Y651943D02*
Y650998D01*
G01Y655880D02*
Y654935D01*
G01Y659817D02*
Y658872D01*
G01Y663754D02*
Y662809D01*
G01X15464D02*
Y663754D01*
G01Y658872D02*
Y659817D01*
G01Y654935D02*
Y655880D01*
G01Y650998D02*
Y651943D01*
G01Y647061D02*
Y648006D01*
G01D02*
Y647061D01*
G01Y651943D02*
Y650998D01*
G01Y655880D02*
Y654935D01*
G01Y659817D02*
Y658872D01*
G01Y663754D02*
Y662809D01*
G01X13424Y662612D02*
Y663951D01*
G01Y658675D02*
Y660014D01*
G01Y650801D02*
Y652140D01*
G01Y654738D02*
Y656077D01*
G01Y646864D02*
Y648203D01*
G01D02*
Y646864D01*
G01Y656077D02*
Y654738D01*
G01Y652140D02*
Y650801D01*
G01Y660014D02*
Y658675D01*
G01Y663951D02*
Y662612D01*
G01X12601D02*
Y663951D01*
G01Y658675D02*
Y660014D01*
G01Y650801D02*
Y652140D01*
G01Y654738D02*
Y656077D01*
G01Y646864D02*
Y648203D01*
G01D02*
Y646864D01*
G01Y656077D02*
Y654738D01*
G01Y652140D02*
Y650801D01*
G01Y660014D02*
Y658675D01*
G01Y663951D02*
Y662612D01*
G01X8523Y648203D02*
Y646864D01*
G01Y648203D02*
Y646864D01*
G01Y652140D02*
Y650801D01*
G01Y656077D02*
Y654738D01*
G01Y652140D02*
Y650801D01*
G01Y656077D02*
Y654738D01*
G01Y660014D02*
Y658675D01*
G01Y660014D02*
Y658675D01*
G01Y663951D02*
Y662612D01*
G01Y663951D02*
Y662612D01*
G01X0Y663951D02*
Y664738D01*
G01Y661825D02*
Y662612D01*
G01Y660014D02*
Y660801D01*
G01Y656077D02*
Y656864D01*
G01Y657888D02*
Y658675D01*
G01Y652140D02*
Y652927D01*
G01Y653951D02*
Y654738D01*
G01Y648203D02*
Y648990D01*
G01Y650014D02*
Y650801D01*
G01Y646077D02*
Y646864D01*
G01D02*
Y646077D01*
G01Y650801D02*
Y650014D01*
G01Y648990D02*
Y648203D01*
G01Y654738D02*
Y653951D01*
G01Y652927D02*
Y652140D01*
G01Y658675D02*
Y657888D01*
G01Y660801D02*
Y660014D01*
G01Y656864D02*
Y656077D01*
G01Y662612D02*
Y661825D01*
G01Y664738D02*
Y663951D01*
G01X-984Y662612D02*
Y663951D01*
G01Y658675D02*
Y660014D01*
G01Y654738D02*
Y656077D01*
G01Y650801D02*
Y652140D01*
G01Y646864D02*
Y648203D01*
G01D02*
Y646864D01*
G01Y656077D02*
Y654738D01*
G01Y652140D02*
Y650801D01*
G01Y660014D02*
Y658675D01*
G01Y663951D02*
Y662612D01*
G01X-2251Y648951D02*
Y646116D01*
G01Y652888D02*
Y650053D01*
G01Y656825D02*
Y653990D01*
G01Y660762D02*
Y657927D01*
G01Y664699D02*
Y661864D01*
G01X-2520Y648636D02*
Y646431D01*
G01Y656510D02*
Y654305D01*
G01Y652573D02*
Y650368D01*
G01Y660447D02*
Y658242D01*
G01Y664384D02*
Y662179D01*
G01X-2196Y662219D02*
X-1969Y661825D01*
G01X-2196Y662219D02*
X-1969Y661825D01*
G01X-2196Y658282D02*
X-1969Y657888D01*
G01X-2196Y658282D02*
X-1969Y657888D01*
G01X-2196Y654345D02*
X-1969Y653951D01*
G01X-2196Y654345D02*
X-1969Y653951D01*
G01X-2196Y650408D02*
X-1969Y650014D01*
G01X-2196Y650408D02*
X-1969Y650014D01*
G01X-2196Y646471D02*
X-1969Y646077D01*
G01X-2196Y646471D02*
X-1969Y646077D01*
G01X14580Y686234D02*
X15464Y686431D01*
G01X14580Y686234D02*
X15464Y686431D01*
G01X15078Y686234D02*
X15962Y686431D01*
G01D02*
X15078Y686234D01*
G01X14580Y682297D02*
X15464Y682494D01*
G01X14580Y682297D02*
X15464Y682494D01*
G01X15078Y682297D02*
X15962Y682494D01*
G01D02*
X15078Y682297D01*
G01X14580Y678360D02*
X15464Y678557D01*
G01X14580Y678360D02*
X15464Y678557D01*
G01X15078Y678360D02*
X15962Y678557D01*
G01D02*
X15078Y678360D01*
G01X14580Y674423D02*
X15464Y674620D01*
G01X14580Y674423D02*
X15464Y674620D01*
G01X15078Y674423D02*
X15962Y674620D01*
G01D02*
X15078Y674423D01*
G01X14580Y670486D02*
X15464Y670683D01*
G01X14580Y670486D02*
X15464Y670683D01*
G01X15078Y670486D02*
X15962Y670683D01*
G01D02*
X15078Y670486D01*
G01X14580Y666549D02*
X15464Y666746D01*
G01X14580Y666549D02*
X15464Y666746D01*
G01X15078Y666549D02*
X15962Y666746D01*
G01D02*
X15078Y666549D01*
G01X-1969Y668675D02*
X-2196Y668282D01*
G01X-1969Y668675D02*
X-2196Y668282D01*
G01X-1969Y672612D02*
X-2196Y672219D01*
G01X-1969Y672612D02*
X-2196Y672219D01*
G01X-1969Y676549D02*
X-2196Y676156D01*
G01X-1969Y676549D02*
X-2196Y676156D01*
G01X-1969Y680486D02*
X-2196Y680093D01*
G01X-1969Y680486D02*
X-2196Y680093D01*
G01X15464Y686431D02*
X15962D01*
G01D02*
X15464D01*
G01X8523Y686234D02*
X15078D01*
G01X-984D02*
X0D01*
G01X8523D02*
X0D01*
G01X15078D02*
X-984D01*
G01X-1969Y685447D02*
X0D01*
G01D02*
X-1969D01*
G01Y684423D02*
X0D01*
G01X-1969D02*
X0D01*
G01X12601Y683636D02*
X15078D01*
G01X-984D02*
X15078D01*
G01X8523D02*
X12601D01*
G01X0D02*
X8523D01*
G01X0D02*
X-984D01*
G01X15464Y683439D02*
X15962D01*
G01D02*
X15464D01*
G01Y682494D02*
X15962D01*
G01D02*
X15464D01*
G01X8523Y682297D02*
X15078D01*
G01X-984D02*
X0D01*
G01X8523D02*
X0D01*
G01X15078D02*
X-984D01*
G01X-1969Y681510D02*
X0D01*
G01D02*
X-1969D01*
G01Y680486D02*
X0D01*
G01X-1969D02*
X0D01*
G01X12601Y679699D02*
X15078D01*
G01X-984D02*
X15078D01*
G01X8523D02*
X12601D01*
G01X0D02*
X8523D01*
G01X0D02*
X-984D01*
G01X15464Y679502D02*
X15962D01*
G01D02*
X15464D01*
G01Y678557D02*
X15962D01*
G01D02*
X15464D01*
G01X8523Y678360D02*
X15078D01*
G01X-984D02*
X0D01*
G01X8523D02*
X0D01*
G01X15078D02*
X-984D01*
G01X-1969Y677573D02*
X0D01*
G01D02*
X-1969D01*
G01Y676549D02*
X0D01*
G01X-1969D02*
X0D01*
G01X12601Y675762D02*
X15078D01*
G01X-984D02*
X15078D01*
G01X8523D02*
X12601D01*
G01X0D02*
X8523D01*
G01X0D02*
X-984D01*
G01X15464Y675565D02*
X15962D01*
G01D02*
X15464D01*
G01Y674620D02*
X15962D01*
G01D02*
X15464D01*
G01X8523Y674423D02*
X15078D01*
G01X-984D02*
X0D01*
G01X8523D02*
X0D01*
G01X15078D02*
X-984D01*
G01X-1969Y673636D02*
X0D01*
G01D02*
X-1969D01*
G01Y672612D02*
X0D01*
G01X-1969D02*
X0D01*
G01X12601Y671825D02*
X15078D01*
G01X-984D02*
X15078D01*
G01X8523D02*
X12601D01*
G01X0D02*
X8523D01*
G01X0D02*
X-984D01*
G01X15464Y671628D02*
X15962D01*
G01D02*
X15464D01*
G01Y670683D02*
X15962D01*
G01D02*
X15464D01*
G01X8523Y670486D02*
X15078D01*
G01X-984D02*
X0D01*
G01X8523D02*
X0D01*
G01X15078D02*
X-984D01*
G01X-1969Y669699D02*
X0D01*
G01D02*
X-1969D01*
G01Y668675D02*
X0D01*
G01X-1969D02*
X0D01*
G01X12601Y667888D02*
X15078D01*
G01X-984D02*
X15078D01*
G01X8523D02*
X12601D01*
G01X0D02*
X8523D01*
G01X0D02*
X-984D01*
G01X15464Y667691D02*
X15962D01*
G01D02*
X15464D01*
G01Y666746D02*
X15962D01*
G01D02*
X15464D01*
G01X8523Y666549D02*
X15078D01*
G01X-984D02*
X0D01*
G01X8523D02*
X0D01*
G01X15078D02*
X-984D01*
G01X-1969Y665762D02*
X0D01*
G01D02*
X-1969D01*
G01Y684423D02*
X-2196Y684030D01*
G01X-1969Y684423D02*
X-2196Y684030D01*
G01X15078Y683636D02*
X15962Y683439D01*
G01D02*
X15078Y683636D01*
G01X14580D02*
X15464Y683439D01*
G01X14580Y683636D02*
X15464Y683439D01*
G01X15078Y679699D02*
X15962Y679502D01*
G01D02*
X15078Y679699D01*
G01X14580D02*
X15464Y679502D01*
G01X14580Y679699D02*
X15464Y679502D01*
G01X15078Y675762D02*
X15962Y675565D01*
G01D02*
X15078Y675762D01*
G01X14580D02*
X15464Y675565D01*
G01X14580Y675762D02*
X15464Y675565D01*
G01X15078Y671825D02*
X15962Y671628D01*
G01D02*
X15078Y671825D01*
G01X14580D02*
X15464Y671628D01*
G01X14580Y671825D02*
X15464Y671628D01*
G01X15078Y667888D02*
X15962Y667691D01*
G01D02*
X15078Y667888D01*
G01X14580D02*
X15464Y667691D01*
G01X14580Y667888D02*
X15464Y667691D01*
G01X15962Y686431D02*
Y687376D01*
G01Y682494D02*
Y683439D01*
G01Y674620D02*
Y675565D01*
G01Y678557D02*
Y679502D01*
G01Y670683D02*
Y671628D01*
G01Y666746D02*
Y667691D01*
G01D02*
Y666746D01*
G01Y671628D02*
Y670683D01*
G01Y675565D02*
Y674620D01*
G01Y679502D02*
Y678557D01*
G01Y683439D02*
Y682494D01*
G01Y687376D02*
Y686431D01*
G01X15464D02*
Y687376D01*
G01Y682494D02*
Y683439D01*
G01Y678557D02*
Y679502D01*
G01Y674620D02*
Y675565D01*
G01Y670683D02*
Y671628D01*
G01Y666746D02*
Y667691D01*
G01D02*
Y666746D01*
G01Y671628D02*
Y670683D01*
G01Y675565D02*
Y674620D01*
G01Y679502D02*
Y678557D01*
G01Y683439D02*
Y682494D01*
G01Y687376D02*
Y686431D01*
G01X13424Y686234D02*
Y687573D01*
G01Y682297D02*
Y683636D01*
G01Y674423D02*
Y675762D01*
G01Y678360D02*
Y679699D01*
G01Y670486D02*
Y671825D01*
G01Y666549D02*
Y667888D01*
G01D02*
Y666549D01*
G01Y671825D02*
Y670486D01*
G01Y679699D02*
Y678360D01*
G01Y675762D02*
Y674423D01*
G01Y683636D02*
Y682297D01*
G01Y687573D02*
Y686234D01*
G01X12601D02*
Y687573D01*
G01Y682297D02*
Y683636D01*
G01Y674423D02*
Y675762D01*
G01Y678360D02*
Y679699D01*
G01Y670486D02*
Y671825D01*
G01Y666549D02*
Y667888D01*
G01D02*
Y666549D01*
G01Y671825D02*
Y670486D01*
G01Y679699D02*
Y678360D01*
G01Y675762D02*
Y674423D01*
G01Y683636D02*
Y682297D01*
G01Y687573D02*
Y686234D01*
G01X8523Y667888D02*
Y666549D01*
G01Y667888D02*
Y666549D01*
G01Y671825D02*
Y670486D01*
G01Y671825D02*
Y670486D01*
G01Y675762D02*
Y674423D01*
G01Y679699D02*
Y678360D01*
G01Y675762D02*
Y674423D01*
G01Y679699D02*
Y678360D01*
G01Y683636D02*
Y682297D01*
G01Y683636D02*
Y682297D01*
G01Y687573D02*
Y686234D01*
G01Y687573D02*
Y686234D01*
G01X0Y685447D02*
Y686234D01*
G01Y679699D02*
Y680486D01*
G01Y683636D02*
Y684423D01*
G01Y681510D02*
Y682297D01*
G01Y675762D02*
Y676549D01*
G01Y677573D02*
Y678360D01*
G01Y671825D02*
Y672612D01*
G01Y673636D02*
Y674423D01*
G01Y667888D02*
Y668675D01*
G01Y665762D02*
Y666549D01*
G01Y669699D02*
Y670486D01*
G01Y666549D02*
Y665762D01*
G01Y670486D02*
Y669699D01*
G01Y668675D02*
Y667888D01*
G01Y674423D02*
Y673636D01*
G01Y672612D02*
Y671825D01*
G01Y678360D02*
Y677573D01*
G01Y676549D02*
Y675762D01*
G01Y682297D02*
Y681510D01*
G01Y680486D02*
Y679699D01*
G01Y684423D02*
Y683636D01*
G01Y686234D02*
Y685447D01*
G01X-984Y686234D02*
Y687573D01*
G01Y682297D02*
Y683636D01*
G01Y678360D02*
Y679699D01*
G01Y674423D02*
Y675762D01*
G01Y670486D02*
Y671825D01*
G01Y666549D02*
Y667888D01*
G01D02*
Y666549D01*
G01Y671825D02*
Y670486D01*
G01Y679699D02*
Y678360D01*
G01Y675762D02*
Y674423D01*
G01Y683636D02*
Y682297D01*
G01Y687573D02*
Y686234D01*
G01X-2251Y668636D02*
Y665801D01*
G01Y672573D02*
Y669738D01*
G01Y676510D02*
Y673675D01*
G01Y680447D02*
Y677612D01*
G01Y684384D02*
Y681549D01*
G01Y688321D02*
Y685486D01*
G01X-2520Y668321D02*
Y666116D01*
G01Y672258D02*
Y670053D01*
G01Y676195D02*
Y673990D01*
G01Y684069D02*
Y681864D01*
G01Y680132D02*
Y677927D01*
G01Y688006D02*
Y685801D01*
G01X-2196Y685841D02*
X-1969Y685447D01*
G01X-2196Y685841D02*
X-1969Y685447D01*
G01X-2196Y681904D02*
X-1969Y681510D01*
G01X-2196Y681904D02*
X-1969Y681510D01*
G01X-2196Y677967D02*
X-1969Y677573D01*
G01X-2196Y677967D02*
X-1969Y677573D01*
G01X-2196Y674030D02*
X-1969Y673636D01*
G01X-2196Y674030D02*
X-1969Y673636D01*
G01X-2196Y670093D02*
X-1969Y669699D01*
G01X-2196Y670093D02*
X-1969Y669699D01*
G01X-2196Y666156D02*
X-1969Y665762D01*
G01X-2196Y666156D02*
X-1969Y665762D01*
G01X14580Y698045D02*
X15464Y698242D01*
G01X14580Y698045D02*
X15464Y698242D01*
G01X15078Y698045D02*
X15962Y698242D01*
G01D02*
X15078Y698045D01*
G01X14580Y694108D02*
X15464Y694305D01*
G01X14580Y694108D02*
X15464Y694305D01*
G01X15078Y694108D02*
X15962Y694305D01*
G01D02*
X15078Y694108D01*
G01X14580Y690171D02*
X15464Y690368D01*
G01X14580Y690171D02*
X15464Y690368D01*
G01X15078Y690171D02*
X15962Y690368D01*
G01D02*
X15078Y690171D01*
G01X0Y704325D02*
X24803D01*
G01X-1969Y700171D02*
X0D01*
G01X-1969D02*
X0D01*
G01X12601Y699384D02*
X15078D01*
G01X-984D02*
X15078D01*
G01X8523D02*
X12601D01*
G01X0D02*
X8523D01*
G01X0D02*
X-984D01*
G01X15464Y699187D02*
X15962D01*
G01D02*
X15464D01*
G01Y698242D02*
X15962D01*
G01D02*
X15464D01*
G01X8523Y698045D02*
X15078D01*
G01X-984D02*
X0D01*
G01X8523D02*
X0D01*
G01X15078D02*
X-984D01*
G01X-1969Y697258D02*
X0D01*
G01D02*
X-1969D01*
G01Y696234D02*
X0D01*
G01X-1969D02*
X0D01*
G01X12601Y695447D02*
X15078D01*
G01X-984D02*
X15078D01*
G01X8523D02*
X12601D01*
G01X0D02*
X8523D01*
G01X0D02*
X-984D01*
G01X15464Y695250D02*
X15962D01*
G01D02*
X15464D01*
G01Y694305D02*
X15962D01*
G01D02*
X15464D01*
G01X8523Y694108D02*
X15078D01*
G01X-984D02*
X0D01*
G01X8523D02*
X0D01*
G01X15078D02*
X-984D01*
G01X-1969Y693321D02*
X0D01*
G01D02*
X-1969D01*
G01Y692297D02*
X0D01*
G01X-1969D02*
X0D01*
G01X12601Y691510D02*
X15078D01*
G01X-984D02*
X15078D01*
G01X8523D02*
X12601D01*
G01X0D02*
X8523D01*
G01X0D02*
X-984D01*
G01X15464Y691313D02*
X15962D01*
G01D02*
X15464D01*
G01Y690368D02*
X15962D01*
G01D02*
X15464D01*
G01X8523Y690171D02*
X15078D01*
G01X-984D02*
X0D01*
G01X8523D02*
X0D01*
G01X15078D02*
X-984D01*
G01X-1969Y689384D02*
X0D01*
G01D02*
X-1969D01*
G01Y688360D02*
X0D01*
G01X-1969D02*
X0D01*
G01X12601Y687573D02*
X15078D01*
G01X-984D02*
X15078D01*
G01X8523D02*
X12601D01*
G01X0D02*
X8523D01*
G01X0D02*
X-984D01*
G01X15464Y687376D02*
X15962D01*
G01D02*
X15464D01*
G01X-1969Y688360D02*
X-2196Y687967D01*
G01X-1969Y688360D02*
X-2196Y687967D01*
G01X-1969Y692297D02*
X-2196Y691904D01*
G01X-1969Y692297D02*
X-2196Y691904D01*
G01X-1969Y696234D02*
X-2196Y695841D01*
G01X-1969Y696234D02*
X-2196Y695841D01*
G01X-1969Y700171D02*
X-2196Y699778D01*
G01X-1969Y700171D02*
X-2196Y699778D01*
G01X15078Y699384D02*
X15962Y699187D01*
G01D02*
X15078Y699384D01*
G01X14580D02*
X15464Y699187D01*
G01X14580Y699384D02*
X15464Y699187D01*
G01X15078Y695447D02*
X15962Y695250D01*
G01D02*
X15078Y695447D01*
G01X14580D02*
X15464Y695250D01*
G01X14580Y695447D02*
X15464Y695250D01*
G01X15078Y691510D02*
X15962Y691313D01*
G01D02*
X15078Y691510D01*
G01X14580D02*
X15464Y691313D01*
G01X14580Y691510D02*
X15464Y691313D01*
G01X15078Y687573D02*
X15962Y687376D01*
G01D02*
X15078Y687573D01*
G01X14580D02*
X15464Y687376D01*
G01X14580Y687573D02*
X15464Y687376D01*
G01X15962Y698242D02*
Y699187D01*
G01Y694305D02*
Y695250D01*
G01Y690368D02*
Y691313D01*
G01D02*
Y690368D01*
G01Y695250D02*
Y694305D01*
G01Y699187D02*
Y698242D01*
G01X15464D02*
Y699187D01*
G01Y694305D02*
Y695250D01*
G01Y690368D02*
Y691313D01*
G01D02*
Y690368D01*
G01Y695250D02*
Y694305D01*
G01Y699187D02*
Y698242D01*
G01X13424Y698045D02*
Y699384D01*
G01Y694108D02*
Y695447D01*
G01Y690171D02*
Y691510D01*
G01D02*
Y690171D01*
G01Y695447D02*
Y694108D01*
G01Y699384D02*
Y698045D01*
G01X12601D02*
Y699384D01*
G01Y694108D02*
Y695447D01*
G01Y690171D02*
Y691510D01*
G01D02*
Y690171D01*
G01Y695447D02*
Y694108D01*
G01Y699384D02*
Y698045D01*
G01X8523Y691510D02*
Y690171D01*
G01Y691510D02*
Y690171D01*
G01Y695447D02*
Y694108D01*
G01Y695447D02*
Y694108D01*
G01Y699384D02*
Y698045D01*
G01Y699384D02*
Y698045D01*
G01X0Y699384D02*
Y700171D01*
G01Y695447D02*
Y696234D01*
G01Y697258D02*
Y698045D01*
G01Y691510D02*
Y692297D01*
G01Y689384D02*
Y690171D01*
G01Y693321D02*
Y694108D01*
G01Y687573D02*
Y688360D01*
G01D02*
Y687573D01*
G01Y690171D02*
Y689384D01*
G01Y694108D02*
Y693321D01*
G01Y692297D02*
Y691510D01*
G01Y698045D02*
Y697258D01*
G01Y696234D02*
Y695447D01*
G01Y700171D02*
Y699384D01*
G01X-984Y698045D02*
Y699384D01*
G01Y694108D02*
Y695447D01*
G01Y690171D02*
Y691510D01*
G01D02*
Y690171D01*
G01Y695447D02*
Y694108D01*
G01Y699384D02*
Y698045D01*
G01X-2251Y692258D02*
Y689423D01*
G01Y696195D02*
Y693360D01*
G01Y700132D02*
Y697297D01*
G01X-2520Y691943D02*
Y689738D01*
G01Y695880D02*
Y693675D01*
G01Y699817D02*
Y697612D01*
G01X-2196Y697652D02*
X-1969Y697258D01*
G01X-2196Y697652D02*
X-1969Y697258D01*
G01X-2196Y693715D02*
X-1969Y693321D01*
G01X-2196Y693715D02*
X-1969Y693321D01*
G01X-2196Y689778D02*
X-1969Y689384D01*
G01X-2196Y689778D02*
X-1969Y689384D01*
G01X13779Y717711D02*
G03I-3937J0D01*
G01X14370D02*
G03I-4528J0D01*
G01X0Y729916D02*
Y710624D01*
G01Y748433D02*
X26771D01*
G01Y731884D02*
X0D01*
G01Y729916D02*
Y750402D01*
G01Y729916D02*
Y750402D01*
G01X13779Y762606D02*
G03I-3937J0D01*
G01X14370D02*
G03I-4528J0D01*
G01X0Y769693D02*
Y868118D01*
G01Y750402D02*
Y819095D01*
G01Y750402D02*
Y819095D01*
G01Y750402D02*
Y769693D01*
G01X10329Y781081D02*
X10530Y781147D01*
G01X10262Y781475D02*
X10463Y781541D01*
G01X9190Y781147D02*
X8989Y781081D01*
G01X8922Y781475D02*
X9123Y781541D01*
G01X15464Y788792D02*
X14689Y788595D01*
G01X15473D02*
X16249Y788792D01*
G01X15464Y784855D02*
X14689Y784658D01*
G01X15473D02*
X16249Y784855D01*
G01X15464Y780918D02*
X14689Y780721D01*
G01X15473D02*
X16249Y780918D01*
G01X9994Y781278D02*
X10262Y781475D01*
G01X8654Y781278D02*
X8922Y781475D01*
G01X9001Y789934D02*
X12829D01*
G01X-984D02*
X0D01*
G01X15473D02*
X12829D01*
G01X0D02*
X9001D01*
G01X16249Y789737D02*
X15464D01*
G01X16249Y788792D02*
X15464D01*
G01X12829Y788595D02*
X9001D01*
G01X0D02*
X-984D01*
G01X9001D02*
X0D01*
G01X15473D02*
X12829D01*
G01X9001Y785997D02*
X12829D01*
G01X-984D02*
X0D01*
G01X15473D02*
X12829D01*
G01X0D02*
X9001D01*
G01X16249Y785800D02*
X15464D01*
G01X16249Y784855D02*
X15464D01*
G01X12829Y784658D02*
X9001D01*
G01X0D02*
X-984D01*
G01X9001D02*
X0D01*
G01X15473D02*
X12829D01*
G01X8386Y782853D02*
X11535D01*
G01Y782459D02*
X8922D01*
G01X9391Y782066D02*
X8855D01*
G01X9001Y782060D02*
X12829D01*
G01X-984D02*
X0D01*
G01X15473D02*
X12829D01*
G01X0D02*
X9001D01*
G01X16249Y781863D02*
X15464D01*
G01X10463Y781541D02*
X10798D01*
G01X9123D02*
X9391D01*
G01X10530Y781147D02*
X10731D01*
G01X9324D02*
X9190D01*
G01X16249Y780918D02*
X15464D01*
G01X12829Y780721D02*
X9001D01*
G01X0D02*
X-984D01*
G01X9001D02*
X0D01*
G01X15473D02*
X12829D01*
G01X8788Y779506D02*
X9726D01*
G01X11133D02*
X10128D01*
G01X11535Y779113D02*
X8386D01*
G01X10195Y780950D02*
X10329Y781081D01*
G01X8989D02*
X8855Y780950D01*
G01X24803Y775992D02*
X0D01*
G01X8453Y781016D02*
X8654Y781278D01*
G01X10798Y781541D02*
X10999Y781475D01*
G01X10731Y781147D02*
X10932Y781081D01*
G01X9391Y781541D02*
X9592Y781475D01*
G01X9525Y781081D02*
X9324Y781147D01*
G01X16249Y789737D02*
X15473Y789934D01*
G01X14689D02*
X15464Y789737D01*
G01X16249Y785800D02*
X15473Y785997D01*
G01X14689D02*
X15464Y785800D01*
G01X16249Y781863D02*
X15473Y782060D01*
G01X14689D02*
X15464Y781863D01*
G01X-1983Y782823D02*
X-2196Y782453D01*
G01X-1983Y786760D02*
X-2196Y786390D01*
G01X-1983Y790697D02*
X-2196Y790327D01*
G01X9927Y781147D02*
X9994Y781278D01*
G01X10128Y780753D02*
X10195Y780950D01*
G01X8855D02*
X8788Y780753D01*
G01X10932Y781081D02*
X11066Y780950D01*
G01X9659D02*
X9525Y781081D01*
G01X8922Y782459D02*
X9391Y782066D01*
G01X8855D02*
X8386Y782459D01*
G01X10999Y781475D02*
X11267Y781278D01*
G01X9592Y781475D02*
X9860Y781278D01*
G01X8386Y780688D02*
X8453Y781016D01*
G01X16249Y788792D02*
Y789737D01*
G01Y784855D02*
Y785800D01*
G01Y780918D02*
Y781863D01*
G01X15464D02*
Y780918D01*
G01Y785800D02*
Y784855D01*
G01Y789737D02*
Y788792D01*
G01X13614Y782060D02*
Y780721D01*
G01Y785997D02*
Y784658D01*
G01Y789934D02*
Y788595D01*
G01X12829D02*
Y789934D01*
G01Y784658D02*
Y785997D01*
G01Y780721D02*
Y782060D01*
G01X11535Y782853D02*
Y782459D01*
G01Y780688D02*
Y779113D01*
G01X11133Y780753D02*
Y779506D01*
G01X10128D02*
Y780753D01*
G01X9726Y779506D02*
Y780753D01*
G01X9001Y782060D02*
Y780721D01*
G01Y785997D02*
Y784658D01*
G01Y789934D02*
Y788595D01*
G01X8788Y780753D02*
Y779506D01*
G01X8386Y782459D02*
Y782853D01*
G01Y779113D02*
Y780688D01*
G01X197Y782060D02*
Y780721D01*
G01Y785997D02*
Y784658D01*
G01Y789934D02*
Y788595D01*
G01X-984Y782060D02*
Y780721D01*
G01Y785997D02*
Y784658D01*
G01Y789934D02*
Y788595D01*
G01X-2251Y782823D02*
Y779988D01*
G01Y786760D02*
Y783925D01*
G01Y794634D02*
Y791799D01*
G01Y790697D02*
Y787862D01*
G01X-2520Y782508D02*
Y780303D01*
G01Y786445D02*
Y784240D01*
G01Y790382D02*
Y788177D01*
G01Y794319D02*
Y792114D01*
G01X11468Y781016D02*
X11535Y780688D01*
G01X11066Y780950D02*
X11133Y780753D01*
G01X9726D02*
X9659Y780950D01*
G01X9860Y781278D02*
X9927Y781147D01*
G01X-2196Y792138D02*
X-2000Y791799D01*
G01X-2196Y788201D02*
X-2000Y787862D01*
G01X-2196Y784264D02*
X-2000Y783925D01*
G01X-2196Y780327D02*
X-2000Y779988D01*
G01X11267Y781278D02*
X11468Y781016D01*
G01X15464Y812414D02*
X14689Y812217D01*
G01X15473D02*
X16249Y812414D01*
G01X15464Y808477D02*
X14689Y808280D01*
G01X15473D02*
X16249Y808477D01*
G01X15464Y804540D02*
X14689Y804343D01*
G01X15473D02*
X16249Y804540D01*
G01X15464Y800603D02*
X14689Y800406D01*
G01X15473D02*
X16249Y800603D01*
G01X15464Y796666D02*
X14689Y796469D01*
G01X15473D02*
X16249Y796666D01*
G01X15464Y792729D02*
X14689Y792532D01*
G01X15473D02*
X16249Y792729D01*
G01Y813359D02*
X15464D01*
G01X16249Y812414D02*
X15464D01*
G01X12829Y812217D02*
X9001D01*
G01X0D02*
X-984D01*
G01X9001D02*
X0D01*
G01X15473D02*
X12829D01*
G01X9001Y809619D02*
X12829D01*
G01X-984D02*
X0D01*
G01X15473D02*
X12829D01*
G01X0D02*
X9001D01*
G01X16249Y809422D02*
X15464D01*
G01X16249Y808477D02*
X15464D01*
G01X12829Y808280D02*
X9001D01*
G01X0D02*
X-984D01*
G01X9001D02*
X0D01*
G01X15473D02*
X12829D01*
G01X9001Y805682D02*
X12829D01*
G01X-984D02*
X0D01*
G01X15473D02*
X12829D01*
G01X0D02*
X9001D01*
G01X16249Y805485D02*
X15464D01*
G01X16249Y804540D02*
X15464D01*
G01X12829Y804343D02*
X9001D01*
G01X0D02*
X-984D01*
G01X9001D02*
X0D01*
G01X15473D02*
X12829D01*
G01X9001Y801745D02*
X12829D01*
G01X-984D02*
X0D01*
G01X15473D02*
X12829D01*
G01X0D02*
X9001D01*
G01X16249Y801548D02*
X15464D01*
G01X16249Y800603D02*
X15464D01*
G01X12829Y800406D02*
X9001D01*
G01X0D02*
X-984D01*
G01X9001D02*
X0D01*
G01X15473D02*
X12829D01*
G01X9001Y797808D02*
X12829D01*
G01X-984D02*
X0D01*
G01X15473D02*
X12829D01*
G01X0D02*
X9001D01*
G01X16249Y797611D02*
X15464D01*
G01X16249Y796666D02*
X15464D01*
G01X12829Y796469D02*
X9001D01*
G01X0D02*
X-984D01*
G01X9001D02*
X0D01*
G01X15473D02*
X12829D01*
G01X9001Y793871D02*
X12829D01*
G01X-984D02*
X0D01*
G01X15473D02*
X12829D01*
G01X0D02*
X9001D01*
G01X16249Y793674D02*
X15464D01*
G01X16249Y792729D02*
X15464D01*
G01X12829Y792532D02*
X9001D01*
G01X0D02*
X-984D01*
G01X9001D02*
X0D01*
G01X15473D02*
X12829D01*
G01X16249Y813359D02*
X15473Y813556D01*
G01X14689D02*
X15464Y813359D01*
G01X16249Y809422D02*
X15473Y809619D01*
G01X14689D02*
X15464Y809422D01*
G01X16249Y805485D02*
X15473Y805682D01*
G01X14689D02*
X15464Y805485D01*
G01X16249Y801548D02*
X15473Y801745D01*
G01X14689D02*
X15464Y801548D01*
G01X16249Y797611D02*
X15473Y797808D01*
G01X14689D02*
X15464Y797611D01*
G01X16249Y793674D02*
X15473Y793871D01*
G01X14689D02*
X15464Y793674D01*
G01X-1983Y794634D02*
X-2196Y794264D01*
G01X-1983Y798571D02*
X-2196Y798201D01*
G01X-1983Y802508D02*
X-2196Y802138D01*
G01X-1983Y806445D02*
X-2196Y806075D01*
G01X-1983Y810382D02*
X-2196Y810012D01*
G01X16249Y812414D02*
Y813359D01*
G01Y808477D02*
Y809422D01*
G01Y804540D02*
Y805485D01*
G01Y796666D02*
Y797611D01*
G01Y800603D02*
Y801548D01*
G01Y792729D02*
Y793674D01*
G01X15464D02*
Y792729D01*
G01Y801548D02*
Y800603D01*
G01Y797611D02*
Y796666D01*
G01Y805485D02*
Y804540D01*
G01Y809422D02*
Y808477D01*
G01Y813359D02*
Y812414D01*
G01X13614Y793871D02*
Y792532D01*
G01Y801745D02*
Y800406D01*
G01Y797808D02*
Y796469D01*
G01Y805682D02*
Y804343D01*
G01Y809619D02*
Y808280D01*
G01Y813556D02*
Y812217D01*
G01X12829D02*
Y813556D01*
G01Y808280D02*
Y809619D01*
G01Y804343D02*
Y805682D01*
G01Y796469D02*
Y797808D01*
G01Y800406D02*
Y801745D01*
G01Y792532D02*
Y793871D01*
G01X9001D02*
Y792532D01*
G01Y797808D02*
Y796469D01*
G01Y801745D02*
Y800406D01*
G01Y805682D02*
Y804343D01*
G01Y809619D02*
Y808280D01*
G01Y813556D02*
Y812217D01*
G01X197Y793871D02*
Y792532D01*
G01Y797808D02*
Y796469D01*
G01Y801745D02*
Y800406D01*
G01Y805682D02*
Y804343D01*
G01Y809619D02*
Y808280D01*
G01Y813556D02*
Y812217D01*
G01X-984Y793871D02*
Y792532D01*
G01Y797808D02*
Y796469D01*
G01Y801745D02*
Y800406D01*
G01Y805682D02*
Y804343D01*
G01Y809619D02*
Y808280D01*
G01Y813556D02*
Y812217D01*
G01X-2251Y798571D02*
Y795736D01*
G01Y802508D02*
Y799673D01*
G01Y806445D02*
Y803610D01*
G01Y810382D02*
Y807547D01*
G01Y814319D02*
Y811484D01*
G01X-2520Y798256D02*
Y796051D01*
G01Y802193D02*
Y799988D01*
G01Y806130D02*
Y803925D01*
G01Y810067D02*
Y807862D01*
G01Y814004D02*
Y811799D01*
G01X-2196Y811823D02*
X-2000Y811484D01*
G01X-2196Y807886D02*
X-2000Y807547D01*
G01X-2196Y803949D02*
X-2000Y803610D01*
G01X-2196Y800012D02*
X-2000Y799673D01*
G01X-2196Y796075D02*
X-2000Y795736D01*
G01X15464Y832099D02*
X14689Y831902D01*
G01X15473D02*
X16249Y832099D01*
G01X15464Y820288D02*
X14689Y820091D01*
G01X15473D02*
X16249Y820288D01*
G01X15464Y816351D02*
X14689Y816154D01*
G01X15473D02*
X16249Y816351D01*
G01X15551Y823286D02*
X18701Y824420D01*
G01X9001Y833241D02*
X12829D01*
G01X-984D02*
X0D01*
G01X15473D02*
X12829D01*
G01X0D02*
X9001D01*
G01X16249Y833044D02*
X15464D01*
G01X16249Y832099D02*
X15464D01*
G01X0Y831902D02*
X-984D01*
G01X12829D02*
X9001D01*
G01D02*
X0D01*
G01X15473D02*
X12829D01*
G01X3937Y830512D02*
X19882D01*
G01X3937D02*
X19882D01*
G01X0Y830294D02*
X15551D01*
G01X0Y823286D02*
X15551D01*
G01X3937Y823032D02*
X19882D01*
G01X3937D02*
X19882D01*
G01X9001Y821430D02*
X12829D01*
G01X-984D02*
X0D01*
G01X15473D02*
X12829D01*
G01X0D02*
X9001D01*
G01X16249Y821233D02*
X15464D01*
G01X16249Y820288D02*
X15464D01*
G01X12829Y820091D02*
X9001D01*
G01X0D02*
X-984D01*
G01X9001D02*
X0D01*
G01X15473D02*
X12829D01*
G01X9001Y817493D02*
X12829D01*
G01X-984D02*
X0D01*
G01X15473D02*
X12829D01*
G01X0D02*
X9001D01*
G01X16249Y817296D02*
X15464D01*
G01X16249Y816351D02*
X15464D01*
G01X12829Y816154D02*
X9001D01*
G01X0D02*
X-984D01*
G01X9001D02*
X0D01*
G01X15473D02*
X12829D01*
G01X9001Y813556D02*
X12829D01*
G01X-984D02*
X0D01*
G01X15473D02*
X12829D01*
G01X0D02*
X9001D01*
G01X16249Y833044D02*
X15473Y833241D01*
G01X14689D02*
X15464Y833044D01*
G01X16249Y821233D02*
X15473Y821430D01*
G01X14689D02*
X15464Y821233D01*
G01X996Y820091D02*
X0Y819095D01*
G01X996Y820091D02*
X0Y819095D01*
G01X2335Y821430D02*
X996Y820091D01*
G01X2335Y821430D02*
X996Y820091D01*
G01X3937Y823032D02*
X2335Y821430D01*
G01X3937Y823032D02*
X2335Y821430D01*
G01X15551Y830294D02*
X18701Y829160D01*
G01X16249Y817296D02*
X15473Y817493D01*
G01X14689D02*
X15464Y817296D01*
G01X-1983Y814319D02*
X-2196Y813949D01*
G01X-1983Y818256D02*
X-2196Y817886D01*
G01X-1983Y822193D02*
X-2196Y821823D01*
G01X-1983Y834004D02*
X-2196Y833634D01*
G01X2547Y831902D02*
X3937Y830512D01*
G01X0Y834449D02*
X1371Y833077D01*
G01X2547Y831902D02*
X3937Y830512D01*
G01X0Y834449D02*
X1371Y833077D01*
G01D02*
X2547Y831902D01*
G01X1371Y833077D02*
X2547Y831902D01*
G01X16249Y832099D02*
Y833044D01*
G01Y820288D02*
Y821233D01*
G01Y816351D02*
Y817296D01*
G01X15551Y830294D02*
Y823286D01*
G01X15464Y817296D02*
Y816351D01*
G01Y821233D02*
Y820288D01*
G01Y833044D02*
Y832099D01*
G01X13614Y817493D02*
Y816154D01*
G01Y821430D02*
Y820091D01*
G01Y833241D02*
Y831902D01*
G01X12829D02*
Y833241D01*
G01Y820091D02*
Y821430D01*
G01Y816154D02*
Y817493D01*
G01X9001D02*
Y816154D01*
G01Y821430D02*
Y820091D01*
G01Y833241D02*
Y831902D01*
G01X197Y817493D02*
Y816154D01*
G01Y821430D02*
Y820091D01*
G01Y833241D02*
Y831902D01*
G01X0Y834449D02*
Y887410D01*
G01Y834449D02*
Y887410D01*
G01X-984Y817493D02*
Y816154D01*
G01Y821430D02*
Y820091D01*
G01Y833241D02*
Y831902D01*
G01X-2251Y818256D02*
Y815421D01*
G01Y822193D02*
Y819358D01*
G01Y834004D02*
Y831169D01*
G01X-2520Y817941D02*
Y815736D01*
G01Y821878D02*
Y819673D01*
G01Y833689D02*
Y831484D01*
G01X-2196Y831508D02*
X-2000Y831169D01*
G01X-2196Y819697D02*
X-2000Y819358D01*
G01X-2196Y815760D02*
X-2000Y815421D01*
G01X15464Y855721D02*
X14689Y855524D01*
G01X15473D02*
X16249Y855721D01*
G01X15464Y851784D02*
X14689Y851587D01*
G01X15473D02*
X16249Y851784D01*
G01X15464Y847847D02*
X14689Y847650D01*
G01X15473D02*
X16249Y847847D01*
G01X15464Y843910D02*
X14689Y843713D01*
G01X15473D02*
X16249Y843910D01*
G01X15464Y839973D02*
X14689Y839776D01*
G01X15473D02*
X16249Y839973D01*
G01X15464Y836036D02*
X14689Y835839D01*
G01X15473D02*
X16249Y836036D01*
G01Y855721D02*
X15464D01*
G01X12829Y855524D02*
X9001D01*
G01X0D02*
X-984D01*
G01X9001D02*
X0D01*
G01X15473D02*
X12829D01*
G01X9001Y852926D02*
X12829D01*
G01X-984D02*
X0D01*
G01X15473D02*
X12829D01*
G01X0D02*
X9001D01*
G01X16249Y852729D02*
X15464D01*
G01X16249Y851784D02*
X15464D01*
G01X12829Y851587D02*
X9001D01*
G01X0D02*
X-984D01*
G01X9001D02*
X0D01*
G01X15473D02*
X12829D01*
G01X9001Y848989D02*
X12829D01*
G01X-984D02*
X0D01*
G01X15473D02*
X12829D01*
G01X0D02*
X9001D01*
G01X16249Y848792D02*
X15464D01*
G01X16249Y847847D02*
X15464D01*
G01X12829Y847650D02*
X9001D01*
G01X0D02*
X-984D01*
G01X9001D02*
X0D01*
G01X15473D02*
X12829D01*
G01X9001Y845052D02*
X12829D01*
G01X-984D02*
X0D01*
G01X15473D02*
X12829D01*
G01X0D02*
X9001D01*
G01X16249Y844855D02*
X15464D01*
G01X16249Y843910D02*
X15464D01*
G01X12829Y843713D02*
X9001D01*
G01X0D02*
X-984D01*
G01X9001D02*
X0D01*
G01X15473D02*
X12829D01*
G01X9001Y841115D02*
X12829D01*
G01X-984D02*
X0D01*
G01X15473D02*
X12829D01*
G01X0D02*
X9001D01*
G01X16249Y840918D02*
X15464D01*
G01X16249Y839973D02*
X15464D01*
G01X12829Y839776D02*
X9001D01*
G01X0D02*
X-984D01*
G01X9001D02*
X0D01*
G01X15473D02*
X12829D01*
G01X9001Y837178D02*
X12829D01*
G01X-984D02*
X0D01*
G01X15473D02*
X12829D01*
G01X0D02*
X9001D01*
G01X16249Y836981D02*
X15464D01*
G01X16249Y836036D02*
X15464D01*
G01X12829Y835839D02*
X9001D01*
G01X0D02*
X-984D01*
G01X9001D02*
X0D01*
G01X15473D02*
X12829D01*
G01X16249Y852729D02*
X15473Y852926D01*
G01X14689D02*
X15464Y852729D01*
G01X16249Y848792D02*
X15473Y848989D01*
G01X14689D02*
X15464Y848792D01*
G01X16249Y844855D02*
X15473Y845052D01*
G01X14689D02*
X15464Y844855D01*
G01X16249Y840918D02*
X15473Y841115D01*
G01X14689D02*
X15464Y840918D01*
G01X16249Y836981D02*
X15473Y837178D01*
G01X14689D02*
X15464Y836981D01*
G01X-1983Y837941D02*
X-2196Y837571D01*
G01X-1983Y841878D02*
X-2196Y841508D01*
G01X-1983Y845815D02*
X-2196Y845445D01*
G01X-1983Y849752D02*
X-2196Y849382D01*
G01X-1983Y853689D02*
X-2196Y853319D01*
G01Y855130D02*
X-2000Y854791D01*
G01X16249Y855721D02*
Y856666D01*
G01Y851784D02*
Y852729D01*
G01Y847847D02*
Y848792D01*
G01Y843910D02*
Y844855D01*
G01Y839973D02*
Y840918D01*
G01Y836036D02*
Y836981D01*
G01X15464D02*
Y836036D01*
G01Y840918D02*
Y839973D01*
G01Y844855D02*
Y843910D01*
G01Y852729D02*
Y851784D01*
G01Y848792D02*
Y847847D01*
G01Y856666D02*
Y855721D01*
G01X13614Y837178D02*
Y835839D01*
G01Y841115D02*
Y839776D01*
G01Y845052D02*
Y843713D01*
G01Y848989D02*
Y847650D01*
G01Y852926D02*
Y851587D01*
G01Y856863D02*
Y855524D01*
G01X12829D02*
Y856863D01*
G01Y851587D02*
Y852926D01*
G01Y847650D02*
Y848989D01*
G01Y843713D02*
Y845052D01*
G01Y839776D02*
Y841115D01*
G01Y835839D02*
Y837178D01*
G01X9001D02*
Y835839D01*
G01Y841115D02*
Y839776D01*
G01Y845052D02*
Y843713D01*
G01Y852926D02*
Y851587D01*
G01Y848989D02*
Y847650D01*
G01Y856863D02*
Y855524D01*
G01X197Y837178D02*
Y835839D01*
G01Y841115D02*
Y839776D01*
G01Y845052D02*
Y843713D01*
G01Y852926D02*
Y851587D01*
G01Y848989D02*
Y847650D01*
G01Y856863D02*
Y855524D01*
G01X-984Y837178D02*
Y835839D01*
G01Y841115D02*
Y839776D01*
G01Y845052D02*
Y843713D01*
G01Y852926D02*
Y851587D01*
G01Y848989D02*
Y847650D01*
G01Y856863D02*
Y855524D01*
G01X-2251Y837941D02*
Y835106D01*
G01Y841878D02*
Y839043D01*
G01Y845815D02*
Y842980D01*
G01Y849752D02*
Y846917D01*
G01Y853689D02*
Y850854D01*
G01Y857626D02*
Y854791D01*
G01X-2520Y837626D02*
Y835421D01*
G01Y841563D02*
Y839358D01*
G01Y845500D02*
Y843295D01*
G01Y849437D02*
Y847232D01*
G01Y853374D02*
Y851169D01*
G01Y857311D02*
Y855106D01*
G01X-2196Y851193D02*
X-2000Y850854D01*
G01X-2196Y847256D02*
X-2000Y846917D01*
G01X-2196Y843319D02*
X-2000Y842980D01*
G01X-2196Y839382D02*
X-2000Y839043D01*
G01X-2196Y835445D02*
X-2000Y835106D01*
G01X13779Y875205D02*
G03I-3937J0D01*
G01X14370D02*
G03I-4528J0D01*
G01X24803Y861819D02*
X0D01*
G01X9001Y856863D02*
X12829D01*
G01X-984D02*
X0D01*
G01X15473D02*
X12829D01*
G01X0D02*
X9001D01*
G01X16249Y856666D02*
X15464D01*
G01X16249D02*
X15473Y856863D01*
G01X14689D02*
X15464Y856666D01*
G01X-1983Y857626D02*
X-2196Y857256D01*
G01X0Y868118D02*
Y887410D01*
G01Y889378D02*
X26771D01*
G01X0Y887410D02*
Y1325191D01*
G01Y887410D02*
Y1325191D01*
G01X45275Y1029528D02*
G03I-15748J0D01*
G01X13779Y1337396D02*
G03I-3937J0D01*
G01X14370D02*
G03I-4528J0D01*
G01X0Y1323223D02*
X26771D01*
G01X0Y1325191D02*
Y1393898D01*
G01Y1325191D02*
Y1393898D01*
G01Y1325191D02*
Y1344482D01*
G01X14580Y1363400D02*
X15464Y1363597D01*
G01X14580Y1363400D02*
X15464Y1363597D01*
G01X15078Y1363400D02*
X15962Y1363597D01*
G01D02*
X15078Y1363400D01*
G01X14580Y1359463D02*
X15464Y1359660D01*
G01X14580Y1359463D02*
X15464Y1359660D01*
G01X15078Y1359463D02*
X15962Y1359660D01*
G01D02*
X15078Y1359463D01*
G01X14580Y1355526D02*
X15464Y1355723D01*
G01X14580Y1355526D02*
X15464Y1355723D01*
G01X15078Y1355526D02*
X15962Y1355723D01*
G01D02*
X15078Y1355526D01*
G01X8523Y1363400D02*
X15078D01*
G01X-984D02*
X0D01*
G01X8523D02*
X0D01*
G01X15078D02*
X-984D01*
G01X-1969Y1362612D02*
X0D01*
G01D02*
X-1969D01*
G01Y1361589D02*
X0D01*
G01X-1969D02*
X0D01*
G01X12601Y1360801D02*
X15078D01*
G01X-984D02*
X15078D01*
G01X8523D02*
X12601D01*
G01X0D02*
X8523D01*
G01X0D02*
X-984D01*
G01X15464Y1360604D02*
X15962D01*
G01D02*
X15464D01*
G01Y1359660D02*
X15962D01*
G01D02*
X15464D01*
G01X8523Y1359463D02*
X15078D01*
G01X-984D02*
X0D01*
G01X8523D02*
X0D01*
G01X15078D02*
X-984D01*
G01X-1969Y1358675D02*
X0D01*
G01D02*
X-1969D01*
G01X9370Y1357908D02*
X12519D01*
G01X-1969Y1357652D02*
X0D01*
G01X-1969D02*
X0D01*
G01X12519Y1357514D02*
X9906D01*
G01X10375Y1357120D02*
X9839D01*
G01X12601Y1356864D02*
X15078D01*
G01X-984D02*
X15078D01*
G01X8523D02*
X12601D01*
G01X0D02*
X8523D01*
G01X0D02*
X-984D01*
G01X15464Y1356667D02*
X15962D01*
G01D02*
X15464D01*
G01X11447Y1356595D02*
X11782D01*
G01X10107D02*
X10375D01*
G01X11514Y1356202D02*
X11716D01*
G01X10308D02*
X10174D01*
G01X15464Y1355723D02*
X15962D01*
G01D02*
X15464D01*
G01X8523Y1355526D02*
X15078D01*
G01X-984D02*
X0D01*
G01X8523D02*
X0D01*
G01X15078D02*
X-984D01*
G01X-1969Y1354738D02*
X0D01*
G01D02*
X-1969D01*
G01X9772Y1354561D02*
X10710D01*
G01X12117D02*
X11112D01*
G01X12519Y1354167D02*
X9370D01*
G01X24803Y1350782D02*
X0D01*
G01X15078Y1360801D02*
X15962Y1360604D01*
G01D02*
X15078Y1360801D01*
G01X14580D02*
X15464Y1360604D01*
G01X14580Y1360801D02*
X15464Y1360604D01*
G01X15078Y1356864D02*
X15962Y1356667D01*
G01D02*
X15078Y1356864D01*
G01X14580D02*
X15464Y1356667D01*
G01X14580Y1356864D02*
X15464Y1356667D01*
G01X11782Y1356595D02*
X11983Y1356530D01*
G01X11716Y1356202D02*
X11916Y1356136D01*
G01X10375Y1356595D02*
X10576Y1356530D01*
G01X10509Y1356136D02*
X10308Y1356202D01*
G01X9906Y1357514D02*
X10375Y1357120D01*
G01X9839D02*
X9370Y1357514D01*
G01X11983Y1356530D02*
X12251Y1356333D01*
G01X10576Y1356530D02*
X10844Y1356333D01*
G01X11916Y1356136D02*
X12051Y1356005D01*
G01X10643D02*
X10509Y1356136D01*
G01X12251Y1356333D02*
X12453Y1356070D01*
G01X10844Y1356333D02*
X10911Y1356202D01*
G01X-2196Y1363006D02*
X-1969Y1362612D01*
G01X-2196Y1363006D02*
X-1969Y1362612D01*
G01X-2196Y1359069D02*
X-1969Y1358675D01*
G01X-2196Y1359069D02*
X-1969Y1358675D01*
G01X-2196Y1355132D02*
X-1969Y1354738D01*
G01X-2196Y1355132D02*
X-1969Y1354738D01*
G01X12051Y1356005D02*
X12117Y1355808D01*
G01X10710D02*
X10643Y1356005D01*
G01X12453Y1356070D02*
X12519Y1355742D01*
G01X11313Y1356136D02*
X11514Y1356202D01*
G01X11246Y1356530D02*
X11447Y1356595D01*
G01X10174Y1356202D02*
X9973Y1356136D01*
G01X9906Y1356530D02*
X10107Y1356595D01*
G01X15962Y1359660D02*
Y1360604D01*
G01Y1355723D02*
Y1356667D01*
G01D02*
Y1355723D01*
G01Y1360604D02*
Y1359660D01*
G01X15464D02*
Y1360604D01*
G01Y1355723D02*
Y1356667D01*
G01D02*
Y1355723D01*
G01Y1360604D02*
Y1359660D01*
G01X13424Y1363400D02*
Y1364738D01*
G01Y1359463D02*
Y1360801D01*
G01Y1355526D02*
Y1356864D01*
G01D02*
Y1355526D01*
G01Y1360801D02*
Y1359463D01*
G01Y1364738D02*
Y1363400D01*
G01X12601D02*
Y1364738D01*
G01Y1359463D02*
Y1360801D01*
G01Y1355526D02*
Y1356864D01*
G01D02*
Y1355526D01*
G01Y1360801D02*
Y1359463D01*
G01Y1364738D02*
Y1363400D01*
G01X12519Y1357908D02*
Y1357514D01*
G01Y1355742D02*
Y1354167D01*
G01X12117Y1355808D02*
Y1354561D01*
G01X11112D02*
Y1355808D01*
G01X10710Y1354561D02*
Y1355808D01*
G01X9772D02*
Y1354561D01*
G01X9370Y1357514D02*
Y1357908D01*
G01Y1354167D02*
Y1355742D01*
G01X8523Y1356864D02*
Y1355526D01*
G01Y1356864D02*
Y1355526D01*
G01Y1360801D02*
Y1359463D01*
G01Y1360801D02*
Y1359463D01*
G01Y1364738D02*
Y1363400D01*
G01Y1364738D02*
Y1363400D01*
G01X0Y1344482D02*
Y1694876D01*
G01Y1360801D02*
Y1361589D01*
G01Y1358675D02*
Y1359463D01*
G01Y1362612D02*
Y1363400D01*
G01Y1356864D02*
Y1357652D01*
G01Y1354738D02*
Y1355526D01*
G01D02*
Y1354738D01*
G01Y1357652D02*
Y1356864D01*
G01Y1359463D02*
Y1358675D01*
G01Y1363400D02*
Y1362612D01*
G01Y1361589D02*
Y1360801D01*
G01X-984Y1363400D02*
Y1364738D01*
G01Y1359463D02*
Y1360801D01*
G01Y1355526D02*
Y1356864D01*
G01D02*
Y1355526D01*
G01Y1360801D02*
Y1359463D01*
G01Y1364738D02*
Y1363400D01*
G01X-2251Y1357612D02*
Y1354778D01*
G01Y1361549D02*
Y1358715D01*
G01Y1365486D02*
Y1362652D01*
G01X-2520Y1357297D02*
Y1355093D01*
G01Y1361234D02*
Y1359030D01*
G01Y1365171D02*
Y1362967D01*
G01X10978Y1356333D02*
X11246Y1356530D01*
G01X9638Y1356333D02*
X9906Y1356530D01*
G01X11112Y1355808D02*
X11179Y1356005D01*
G01X9839D02*
X9772Y1355808D01*
G01X9370Y1355742D02*
X9437Y1356070D01*
G01X11179Y1356005D02*
X11313Y1356136D01*
G01X9973D02*
X9839Y1356005D01*
G01X9437Y1356070D02*
X9638Y1356333D01*
G01X-1969Y1357652D02*
X-2196Y1357258D01*
G01X-1969Y1357652D02*
X-2196Y1357258D01*
G01X-1969Y1361589D02*
X-2196Y1361195D01*
G01X-1969Y1361589D02*
X-2196Y1361195D01*
G01X10911Y1356202D02*
X10978Y1356333D01*
G01X14580Y1383085D02*
X15464Y1383282D01*
G01X14580Y1383085D02*
X15464Y1383282D01*
G01X15078Y1383085D02*
X15962Y1383282D01*
G01D02*
X15078Y1383085D01*
G01X14580Y1379148D02*
X15464Y1379345D01*
G01X14580Y1379148D02*
X15464Y1379345D01*
G01X15078Y1379148D02*
X15962Y1379345D01*
G01D02*
X15078Y1379148D01*
G01X14580Y1375211D02*
X15464Y1375408D01*
G01X14580Y1375211D02*
X15464Y1375408D01*
G01X15078Y1375211D02*
X15962Y1375408D01*
G01D02*
X15078Y1375211D01*
G01X14580Y1371274D02*
X15464Y1371471D01*
G01X14580Y1371274D02*
X15464Y1371471D01*
G01X15078Y1371274D02*
X15962Y1371471D01*
G01D02*
X15078Y1371274D01*
G01X14580Y1367337D02*
X15464Y1367534D01*
G01X14580Y1367337D02*
X15464Y1367534D01*
G01X15078Y1367337D02*
X15962Y1367534D01*
G01D02*
X15078Y1367337D01*
G01X12601Y1384423D02*
X15078D01*
G01X-984D02*
X15078D01*
G01X8523D02*
X12601D01*
G01X0D02*
X8523D01*
G01X0D02*
X-984D01*
G01X15464Y1384227D02*
X15962D01*
G01D02*
X15464D01*
G01Y1383282D02*
X15962D01*
G01D02*
X15464D01*
G01X8523Y1383085D02*
X15078D01*
G01X-984D02*
X0D01*
G01X8523D02*
X0D01*
G01X15078D02*
X-984D01*
G01X-1969Y1382297D02*
X0D01*
G01D02*
X-1969D01*
G01Y1381274D02*
X0D01*
G01X-1969D02*
X0D01*
G01X12601Y1380486D02*
X15078D01*
G01X-984D02*
X15078D01*
G01X8523D02*
X12601D01*
G01X0D02*
X8523D01*
G01X0D02*
X-984D01*
G01X15464Y1380290D02*
X15962D01*
G01D02*
X15464D01*
G01Y1379345D02*
X15962D01*
G01D02*
X15464D01*
G01X8523Y1379148D02*
X15078D01*
G01X-984D02*
X0D01*
G01X8523D02*
X0D01*
G01X15078D02*
X-984D01*
G01X-1969Y1378360D02*
X0D01*
G01D02*
X-1969D01*
G01Y1377337D02*
X0D01*
G01X-1969D02*
X0D01*
G01X12601Y1376549D02*
X15078D01*
G01X-984D02*
X15078D01*
G01X8523D02*
X12601D01*
G01X0D02*
X8523D01*
G01X0D02*
X-984D01*
G01X15464Y1376353D02*
X15962D01*
G01D02*
X15464D01*
G01Y1375408D02*
X15962D01*
G01D02*
X15464D01*
G01X8523Y1375211D02*
X15078D01*
G01X-984D02*
X0D01*
G01X8523D02*
X0D01*
G01X15078D02*
X-984D01*
G01X-1969Y1374423D02*
X0D01*
G01D02*
X-1969D01*
G01Y1373400D02*
X0D01*
G01X-1969D02*
X0D01*
G01X12601Y1372612D02*
X15078D01*
G01X-984D02*
X15078D01*
G01X8523D02*
X12601D01*
G01X0D02*
X8523D01*
G01X0D02*
X-984D01*
G01X15464Y1372416D02*
X15962D01*
G01D02*
X15464D01*
G01Y1371471D02*
X15962D01*
G01D02*
X15464D01*
G01X8523Y1371274D02*
X15078D01*
G01X-984D02*
X0D01*
G01X8523D02*
X0D01*
G01X15078D02*
X-984D01*
G01X-1969Y1370486D02*
X0D01*
G01D02*
X-1969D01*
G01Y1369463D02*
X0D01*
G01X-1969D02*
X0D01*
G01X12601Y1368675D02*
X15078D01*
G01X-984D02*
X15078D01*
G01X8523D02*
X12601D01*
G01X0D02*
X8523D01*
G01X0D02*
X-984D01*
G01X15464Y1368478D02*
X15962D01*
G01D02*
X15464D01*
G01Y1367534D02*
X15962D01*
G01D02*
X15464D01*
G01X8523Y1367337D02*
X15078D01*
G01X-984D02*
X0D01*
G01X8523D02*
X0D01*
G01X15078D02*
X-984D01*
G01X-1969Y1366549D02*
X0D01*
G01D02*
X-1969D01*
G01Y1365526D02*
X0D01*
G01X-1969D02*
X0D01*
G01X12601Y1364738D02*
X15078D01*
G01X-984D02*
X15078D01*
G01X8523D02*
X12601D01*
G01X0D02*
X8523D01*
G01X0D02*
X-984D01*
G01X15464Y1364541D02*
X15962D01*
G01D02*
X15464D01*
G01Y1363597D02*
X15962D01*
G01D02*
X15464D01*
G01X15078Y1384423D02*
X15962Y1384227D01*
G01D02*
X15078Y1384423D01*
G01X14580D02*
X15464Y1384227D01*
G01X14580Y1384423D02*
X15464Y1384227D01*
G01X15078Y1380486D02*
X15962Y1380290D01*
G01D02*
X15078Y1380486D01*
G01X14580D02*
X15464Y1380290D01*
G01X14580Y1380486D02*
X15464Y1380290D01*
G01X15078Y1376549D02*
X15962Y1376353D01*
G01D02*
X15078Y1376549D01*
G01X14580D02*
X15464Y1376353D01*
G01X14580Y1376549D02*
X15464Y1376353D01*
G01X15078Y1372612D02*
X15962Y1372416D01*
G01D02*
X15078Y1372612D01*
G01X14580D02*
X15464Y1372416D01*
G01X14580Y1372612D02*
X15464Y1372416D01*
G01X15078Y1368675D02*
X15962Y1368478D01*
G01D02*
X15078Y1368675D01*
G01X14580D02*
X15464Y1368478D01*
G01X14580Y1368675D02*
X15464Y1368478D01*
G01X15078Y1364738D02*
X15962Y1364541D01*
G01D02*
X15078Y1364738D01*
G01X14580D02*
X15464Y1364541D01*
G01X14580Y1364738D02*
X15464Y1364541D01*
G01X-2196Y1382691D02*
X-1969Y1382297D01*
G01X-2196Y1382691D02*
X-1969Y1382297D01*
G01X-2196Y1378754D02*
X-1969Y1378360D01*
G01X-2196Y1378754D02*
X-1969Y1378360D01*
G01X-2196Y1374817D02*
X-1969Y1374423D01*
G01X-2196Y1374817D02*
X-1969Y1374423D01*
G01X-2196Y1370880D02*
X-1969Y1370486D01*
G01X-2196Y1370880D02*
X-1969Y1370486D01*
G01X-2196Y1366943D02*
X-1969Y1366549D01*
G01X-2196Y1366943D02*
X-1969Y1366549D01*
G01X15962Y1383282D02*
Y1384227D01*
G01Y1379345D02*
Y1380290D01*
G01Y1375408D02*
Y1376353D01*
G01Y1367534D02*
Y1368478D01*
G01Y1371471D02*
Y1372416D01*
G01Y1363597D02*
Y1364541D01*
G01D02*
Y1363597D01*
G01Y1368478D02*
Y1367534D01*
G01Y1372416D02*
Y1371471D01*
G01Y1376353D02*
Y1375408D01*
G01Y1380290D02*
Y1379345D01*
G01Y1384227D02*
Y1383282D01*
G01X15464D02*
Y1384227D01*
G01Y1379345D02*
Y1380290D01*
G01Y1375408D02*
Y1376353D01*
G01Y1371471D02*
Y1372416D01*
G01Y1367534D02*
Y1368478D01*
G01Y1363597D02*
Y1364541D01*
G01D02*
Y1363597D01*
G01Y1368478D02*
Y1367534D01*
G01Y1372416D02*
Y1371471D01*
G01Y1376353D02*
Y1375408D01*
G01Y1380290D02*
Y1379345D01*
G01Y1384227D02*
Y1383282D01*
G01X13424Y1383085D02*
Y1384423D01*
G01Y1379148D02*
Y1380486D01*
G01Y1375211D02*
Y1376549D01*
G01Y1367337D02*
Y1368675D01*
G01Y1371274D02*
Y1372612D01*
G01D02*
Y1371274D01*
G01Y1368675D02*
Y1367337D01*
G01Y1376549D02*
Y1375211D01*
G01Y1380486D02*
Y1379148D01*
G01Y1384423D02*
Y1383085D01*
G01X12601D02*
Y1384423D01*
G01Y1379148D02*
Y1380486D01*
G01Y1375211D02*
Y1376549D01*
G01Y1367337D02*
Y1368675D01*
G01Y1371274D02*
Y1372612D01*
G01D02*
Y1371274D01*
G01Y1368675D02*
Y1367337D01*
G01Y1376549D02*
Y1375211D01*
G01Y1380486D02*
Y1379148D01*
G01Y1384423D02*
Y1383085D01*
G01X8523Y1368675D02*
Y1367337D01*
G01Y1372612D02*
Y1371274D01*
G01Y1368675D02*
Y1367337D01*
G01Y1372612D02*
Y1371274D01*
G01Y1376549D02*
Y1375211D01*
G01Y1376549D02*
Y1375211D01*
G01Y1380486D02*
Y1379148D01*
G01Y1380486D02*
Y1379148D01*
G01Y1384423D02*
Y1383085D01*
G01Y1384423D02*
Y1383085D01*
G01X0Y1384423D02*
Y1385211D01*
G01Y1382297D02*
Y1383085D01*
G01Y1380486D02*
Y1381274D01*
G01Y1378360D02*
Y1379148D01*
G01Y1372612D02*
Y1373400D01*
G01Y1376549D02*
Y1377337D01*
G01Y1374423D02*
Y1375211D01*
G01Y1368675D02*
Y1369463D01*
G01Y1370486D02*
Y1371274D01*
G01Y1364738D02*
Y1365526D01*
G01Y1366549D02*
Y1367337D01*
G01D02*
Y1366549D01*
G01Y1365526D02*
Y1364738D01*
G01Y1371274D02*
Y1370486D01*
G01Y1369463D02*
Y1368675D01*
G01Y1375211D02*
Y1374423D01*
G01Y1373400D02*
Y1372612D01*
G01Y1377337D02*
Y1376549D01*
G01Y1379148D02*
Y1378360D01*
G01Y1381274D02*
Y1380486D01*
G01Y1383085D02*
Y1382297D01*
G01Y1385211D02*
Y1384423D01*
G01X-984Y1383085D02*
Y1384423D01*
G01Y1379148D02*
Y1380486D01*
G01Y1375211D02*
Y1376549D01*
G01Y1371274D02*
Y1372612D01*
G01Y1367337D02*
Y1368675D01*
G01Y1372612D02*
Y1371274D01*
G01Y1368675D02*
Y1367337D01*
G01Y1376549D02*
Y1375211D01*
G01Y1380486D02*
Y1379148D01*
G01Y1384423D02*
Y1383085D01*
G01X-2251Y1369423D02*
Y1366589D01*
G01Y1377297D02*
Y1374463D01*
G01Y1373360D02*
Y1370526D01*
G01Y1381234D02*
Y1378400D01*
G01Y1385171D02*
Y1382337D01*
G01X-2520Y1369108D02*
Y1366904D01*
G01Y1376982D02*
Y1374778D01*
G01Y1373045D02*
Y1370841D01*
G01Y1380919D02*
Y1378715D01*
G01Y1384856D02*
Y1382652D01*
G01X-1969Y1365526D02*
X-2196Y1365132D01*
G01X-1969Y1365526D02*
X-2196Y1365132D01*
G01X-1969Y1369463D02*
X-2196Y1369069D01*
G01X-1969Y1369463D02*
X-2196Y1369069D01*
G01X-1969Y1373400D02*
X-2196Y1373006D01*
G01X-1969Y1373400D02*
X-2196Y1373006D01*
G01X-1969Y1377337D02*
X-2196Y1376943D01*
G01X-1969Y1377337D02*
X-2196Y1376943D01*
G01X-1969Y1381274D02*
X-2196Y1380880D01*
G01X-1969Y1381274D02*
X-2196Y1380880D01*
G01X14580Y1394896D02*
X15464Y1395093D01*
G01X14580Y1394896D02*
X15464Y1395093D01*
G01X15078Y1394896D02*
X15962Y1395093D01*
G01D02*
X15078Y1394896D01*
G01X14580Y1390959D02*
X15464Y1391156D01*
G01X14580Y1390959D02*
X15464Y1391156D01*
G01X15078Y1390959D02*
X15962Y1391156D01*
G01D02*
X15078Y1390959D01*
G01X14580Y1387022D02*
X15464Y1387219D01*
G01X14580Y1387022D02*
X15464Y1387219D01*
G01X15078Y1387022D02*
X15962Y1387219D01*
G01D02*
X15078Y1387022D01*
G01X3937Y1405315D02*
X19882D01*
G01X3937D02*
X19882D01*
G01X0Y1404955D02*
X15551D01*
G01X3937Y1397947D02*
X0D01*
G01X15551D02*
X3937D01*
G01Y1397835D02*
X19882D01*
G01X3937D02*
X19882D01*
G01X-1969Y1397022D02*
X0D01*
G01X-1969D02*
X0D01*
G01X12601Y1396234D02*
X15078D01*
G01X-984D02*
X15078D01*
G01X8523D02*
X12601D01*
G01X0D02*
X8523D01*
G01X0D02*
X-984D01*
G01X15464Y1396038D02*
X15962D01*
G01D02*
X15464D01*
G01Y1395093D02*
X15962D01*
G01D02*
X15464D01*
G01X8523Y1394896D02*
X15078D01*
G01X-984D02*
X0D01*
G01X8523D02*
X0D01*
G01X15078D02*
X-984D01*
G01X-1969Y1394108D02*
X0D01*
G01D02*
X-1969D01*
G01Y1393085D02*
X0D01*
G01X-1969D02*
X0D01*
G01X12601Y1392297D02*
X15078D01*
G01X-984D02*
X15078D01*
G01X8523D02*
X12601D01*
G01X0D02*
X8523D01*
G01X0D02*
X-984D01*
G01X15464Y1392101D02*
X15962D01*
G01D02*
X15464D01*
G01Y1391156D02*
X15962D01*
G01D02*
X15464D01*
G01X8523Y1390959D02*
X15078D01*
G01X-984D02*
X0D01*
G01X8523D02*
X0D01*
G01X15078D02*
X-984D01*
G01X-1969Y1390171D02*
X0D01*
G01D02*
X-1969D01*
G01Y1389148D02*
X0D01*
G01X-1969D02*
X0D01*
G01X12601Y1388360D02*
X15078D01*
G01X-984D02*
X15078D01*
G01X8523D02*
X12601D01*
G01X0D02*
X8523D01*
G01X0D02*
X-984D01*
G01X15464Y1388164D02*
X15962D01*
G01D02*
X15464D01*
G01Y1387219D02*
X15962D01*
G01D02*
X15464D01*
G01X8523Y1387022D02*
X15078D01*
G01X-984D02*
X0D01*
G01X8523D02*
X0D01*
G01X15078D02*
X-984D01*
G01X-1969Y1386234D02*
X0D01*
G01D02*
X-1969D01*
G01Y1385211D02*
X0D01*
G01X-1969D02*
X0D01*
G01X15078Y1396234D02*
X15962Y1396038D01*
G01D02*
X15078Y1396234D01*
G01X14580D02*
X15464Y1396038D01*
G01X14580Y1396234D02*
X15464Y1396038D01*
G01X15078Y1392297D02*
X15962Y1392101D01*
G01D02*
X15078Y1392297D01*
G01X14580D02*
X15464Y1392101D01*
G01X14580Y1392297D02*
X15464Y1392101D01*
G01X15078Y1388360D02*
X15962Y1388164D01*
G01D02*
X15078Y1388360D01*
G01X14580D02*
X15464Y1388164D01*
G01X14580Y1388360D02*
X15464Y1388164D01*
G01X15551Y1404955D02*
X18701Y1403821D01*
G01X2545Y1406707D02*
X3937Y1405315D01*
G01X2545Y1406707D02*
X3937Y1405315D01*
G01X-2196Y1394502D02*
X-1969Y1394108D01*
G01X-2196Y1394502D02*
X-1969Y1394108D01*
G01X-2196Y1390565D02*
X-1969Y1390171D01*
G01X-2196Y1390565D02*
X-1969Y1390171D01*
G01X-2196Y1386628D02*
X-1969Y1386234D01*
G01X-2196Y1386628D02*
X-1969Y1386234D01*
G01X15962Y1391156D02*
Y1392101D01*
G01Y1395093D02*
Y1396038D01*
G01Y1387219D02*
Y1388164D01*
G01D02*
Y1387219D01*
G01Y1392101D02*
Y1391156D01*
G01Y1396038D02*
Y1395093D01*
G01X15551Y1404955D02*
Y1397947D01*
G01X15464Y1395093D02*
Y1396038D01*
G01Y1391156D02*
Y1392101D01*
G01Y1387219D02*
Y1388164D01*
G01D02*
Y1387219D01*
G01Y1392101D02*
Y1391156D01*
G01Y1396038D02*
Y1395093D01*
G01X13424Y1390959D02*
Y1392297D01*
G01Y1394896D02*
Y1396234D01*
G01Y1387022D02*
Y1388360D01*
G01D02*
Y1387022D01*
G01Y1396234D02*
Y1394896D01*
G01Y1392297D02*
Y1390959D01*
G01X12601D02*
Y1392297D01*
G01Y1394896D02*
Y1396234D01*
G01Y1387022D02*
Y1388360D01*
G01D02*
Y1387022D01*
G01Y1396234D02*
Y1394896D01*
G01Y1392297D02*
Y1390959D01*
G01X8523Y1388360D02*
Y1387022D01*
G01Y1388360D02*
Y1387022D01*
G01Y1392297D02*
Y1390959D01*
G01Y1396234D02*
Y1394896D01*
G01Y1392297D02*
Y1390959D01*
G01Y1396234D02*
Y1394896D01*
G01X0Y1396234D02*
Y1397022D01*
G01Y1392297D02*
Y1393085D01*
G01Y1394108D02*
Y1394896D01*
G01Y1388360D02*
Y1389148D01*
G01Y1386234D02*
Y1387022D01*
G01Y1390171D02*
Y1390959D01*
G01Y1387022D02*
Y1386234D01*
G01Y1390959D02*
Y1390171D01*
G01Y1389148D02*
Y1388360D01*
G01Y1394896D02*
Y1394108D01*
G01Y1393085D02*
Y1392297D01*
G01Y1397022D02*
Y1396234D01*
G01X-984Y1394896D02*
Y1396234D01*
G01Y1390959D02*
Y1392297D01*
G01Y1387022D02*
Y1388360D01*
G01D02*
Y1387022D01*
G01Y1396234D02*
Y1394896D01*
G01Y1392297D02*
Y1390959D01*
G01X-2251Y1389108D02*
Y1386274D01*
G01Y1393045D02*
Y1390211D01*
G01Y1396982D02*
Y1394148D01*
G01X-2520Y1388793D02*
Y1386589D01*
G01Y1392730D02*
Y1390526D01*
G01Y1396667D02*
Y1394463D01*
G01X18701Y1399081D02*
X15551Y1397947D01*
G01X1168Y1395066D02*
X0Y1393898D01*
G01X1168Y1395066D02*
X0Y1393898D01*
G01X3937Y1397835D02*
X2336Y1396234D01*
G01X3937Y1397835D02*
X2336Y1396234D01*
G01D02*
X1168Y1395066D01*
G01X2336Y1396234D02*
X1168Y1395066D01*
G01X-1969Y1385211D02*
X-2196Y1384817D01*
G01X-1969Y1385211D02*
X-2196Y1384817D01*
G01X-1969Y1389148D02*
X-2196Y1388754D01*
G01X-1969Y1389148D02*
X-2196Y1388754D01*
G01X-1969Y1393085D02*
X-2196Y1392691D01*
G01X-1969Y1393085D02*
X-2196Y1392691D01*
G01X-1969Y1397022D02*
X-2196Y1396628D01*
G01X-1969Y1397022D02*
X-2196Y1396628D01*
G01X14580Y1426392D02*
X15464Y1426589D01*
G01X14580Y1426392D02*
X15464Y1426589D01*
G01X15078Y1426392D02*
X15962Y1426589D01*
G01D02*
X15078Y1426392D01*
G01X14580Y1422455D02*
X15464Y1422652D01*
G01X14580Y1422455D02*
X15464Y1422652D01*
G01X15078Y1422455D02*
X15962Y1422652D01*
G01D02*
X15078Y1422455D01*
G01X14580Y1418518D02*
X15464Y1418715D01*
G01X14580Y1418518D02*
X15464Y1418715D01*
G01X15078Y1418518D02*
X15962Y1418715D01*
G01D02*
X15078Y1418518D01*
G01X14580Y1414581D02*
X15464Y1414778D01*
G01X14580Y1414581D02*
X15464Y1414778D01*
G01X15078Y1414581D02*
X15962Y1414778D01*
G01D02*
X15078Y1414581D01*
G01X14580Y1410644D02*
X15464Y1410841D01*
G01X14580Y1410644D02*
X15464Y1410841D01*
G01X15078Y1410644D02*
X15962Y1410841D01*
G01D02*
X15078Y1410644D01*
G01X14580Y1406707D02*
X15464Y1406904D01*
G01X14580Y1406707D02*
X15464Y1406904D01*
G01X15078Y1406707D02*
X15962Y1406904D01*
G01D02*
X15078Y1406707D01*
G01X15464Y1426589D02*
X15962D01*
G01D02*
X15464D01*
G01X8523Y1426392D02*
X15078D01*
G01X-984D02*
X0D01*
G01X8523D02*
X0D01*
G01X15078D02*
X-984D01*
G01X-1969Y1425604D02*
X0D01*
G01D02*
X-1969D01*
G01Y1424581D02*
X0D01*
G01X-1969D02*
X0D01*
G01X12601Y1423793D02*
X15078D01*
G01X-984D02*
X15078D01*
G01X8523D02*
X12601D01*
G01X0D02*
X8523D01*
G01X0D02*
X-984D01*
G01X15464Y1423597D02*
X15962D01*
G01D02*
X15464D01*
G01Y1422652D02*
X15962D01*
G01D02*
X15464D01*
G01X8523Y1422455D02*
X15078D01*
G01X-984D02*
X0D01*
G01X8523D02*
X0D01*
G01X15078D02*
X-984D01*
G01X-1969Y1421667D02*
X0D01*
G01D02*
X-1969D01*
G01Y1420644D02*
X0D01*
G01X-1969D02*
X0D01*
G01X12601Y1419856D02*
X15078D01*
G01X-984D02*
X15078D01*
G01X8523D02*
X12601D01*
G01X0D02*
X8523D01*
G01X0D02*
X-984D01*
G01X15464Y1419660D02*
X15962D01*
G01D02*
X15464D01*
G01Y1418715D02*
X15962D01*
G01D02*
X15464D01*
G01X8523Y1418518D02*
X15078D01*
G01X-984D02*
X0D01*
G01X8523D02*
X0D01*
G01X15078D02*
X-984D01*
G01X-1969Y1417730D02*
X0D01*
G01D02*
X-1969D01*
G01Y1416707D02*
X0D01*
G01X-1969D02*
X0D01*
G01X12601Y1415919D02*
X15078D01*
G01X-984D02*
X15078D01*
G01X8523D02*
X12601D01*
G01X0D02*
X8523D01*
G01X0D02*
X-984D01*
G01X15464Y1415723D02*
X15962D01*
G01D02*
X15464D01*
G01Y1414778D02*
X15962D01*
G01D02*
X15464D01*
G01X8523Y1414581D02*
X15078D01*
G01X-984D02*
X0D01*
G01X8523D02*
X0D01*
G01X15078D02*
X-984D01*
G01X-1969Y1413793D02*
X0D01*
G01D02*
X-1969D01*
G01Y1412770D02*
X0D01*
G01X-1969D02*
X0D01*
G01X12601Y1411982D02*
X15078D01*
G01X-984D02*
X15078D01*
G01X8523D02*
X12601D01*
G01X0D02*
X8523D01*
G01X0D02*
X-984D01*
G01X15464Y1411786D02*
X15962D01*
G01D02*
X15464D01*
G01Y1410841D02*
X15962D01*
G01D02*
X15464D01*
G01X8523Y1410644D02*
X15078D01*
G01X-984D02*
X0D01*
G01X8523D02*
X0D01*
G01X15078D02*
X-984D01*
G01X-1969Y1409856D02*
X0D01*
G01D02*
X-1969D01*
G01Y1408833D02*
X0D01*
G01X-1969D02*
X0D01*
G01X12601Y1408045D02*
X15078D01*
G01X-984D02*
X15078D01*
G01X8523D02*
X12601D01*
G01X0D02*
X8523D01*
G01X0D02*
X-984D01*
G01X15464Y1407849D02*
X15962D01*
G01D02*
X15464D01*
G01Y1406904D02*
X15962D01*
G01D02*
X15464D01*
G01X8523Y1406707D02*
X15078D01*
G01X-984D02*
X0D01*
G01X8523D02*
X0D01*
G01X15078D02*
X-984D01*
G01X-1969Y1405919D02*
X0D01*
G01D02*
X-1969D01*
G01X15078Y1423793D02*
X15962Y1423597D01*
G01D02*
X15078Y1423793D01*
G01X14580D02*
X15464Y1423597D01*
G01X14580Y1423793D02*
X15464Y1423597D01*
G01X15078Y1419856D02*
X15962Y1419660D01*
G01D02*
X15078Y1419856D01*
G01X14580D02*
X15464Y1419660D01*
G01X14580Y1419856D02*
X15464Y1419660D01*
G01X15078Y1415919D02*
X15962Y1415723D01*
G01D02*
X15078Y1415919D01*
G01X14580D02*
X15464Y1415723D01*
G01X14580Y1415919D02*
X15464Y1415723D01*
G01X15078Y1411982D02*
X15962Y1411786D01*
G01D02*
X15078Y1411982D01*
G01X14580D02*
X15464Y1411786D01*
G01X14580Y1411982D02*
X15464Y1411786D01*
G01X15078Y1408045D02*
X15962Y1407849D01*
G01D02*
X15078Y1408045D01*
G01X14580D02*
X15464Y1407849D01*
G01X14580Y1408045D02*
X15464Y1407849D01*
G01X1206Y1408045D02*
X2545Y1406707D01*
G01X1206Y1408045D02*
X2545Y1406707D01*
G01X0Y1409252D02*
X1206Y1408045D01*
G01X0Y1409252D02*
X1206Y1408045D01*
G01X-2196Y1425998D02*
X-1969Y1425604D01*
G01X-2196Y1425998D02*
X-1969Y1425604D01*
G01X-2196Y1422061D02*
X-1969Y1421667D01*
G01X-2196Y1422061D02*
X-1969Y1421667D01*
G01X-2196Y1418124D02*
X-1969Y1417730D01*
G01X-2196Y1418124D02*
X-1969Y1417730D01*
G01X-2196Y1414187D02*
X-1969Y1413793D01*
G01X-2196Y1414187D02*
X-1969Y1413793D01*
G01X-2196Y1410250D02*
X-1969Y1409856D01*
G01X-2196Y1410250D02*
X-1969Y1409856D01*
G01X-2196Y1406313D02*
X-1969Y1405919D01*
G01X-2196Y1406313D02*
X-1969Y1405919D01*
G01X15962Y1426589D02*
Y1427534D01*
G01Y1422652D02*
Y1423597D01*
G01Y1414778D02*
Y1415723D01*
G01Y1418715D02*
Y1419660D01*
G01Y1410841D02*
Y1411786D01*
G01Y1406904D02*
Y1407849D01*
G01D02*
Y1406904D01*
G01Y1411786D02*
Y1410841D01*
G01Y1415723D02*
Y1414778D01*
G01Y1419660D02*
Y1418715D01*
G01Y1423597D02*
Y1422652D01*
G01Y1427534D02*
Y1426589D01*
G01X15464D02*
Y1427534D01*
G01Y1422652D02*
Y1423597D01*
G01Y1418715D02*
Y1419660D01*
G01Y1414778D02*
Y1415723D01*
G01Y1410841D02*
Y1411786D01*
G01Y1406904D02*
Y1407849D01*
G01D02*
Y1406904D01*
G01Y1411786D02*
Y1410841D01*
G01Y1415723D02*
Y1414778D01*
G01Y1419660D02*
Y1418715D01*
G01Y1423597D02*
Y1422652D01*
G01Y1427534D02*
Y1426589D01*
G01X13424Y1426392D02*
Y1427730D01*
G01Y1418518D02*
Y1419856D01*
G01Y1422455D02*
Y1423793D01*
G01Y1414581D02*
Y1415919D01*
G01Y1410644D02*
Y1411982D01*
G01Y1406707D02*
Y1408045D01*
G01D02*
Y1406707D01*
G01Y1411982D02*
Y1410644D01*
G01Y1415919D02*
Y1414581D01*
G01Y1423793D02*
Y1422455D01*
G01Y1419856D02*
Y1418518D01*
G01Y1427730D02*
Y1426392D01*
G01X12601D02*
Y1427730D01*
G01Y1418518D02*
Y1419856D01*
G01Y1422455D02*
Y1423793D01*
G01Y1414581D02*
Y1415919D01*
G01Y1410644D02*
Y1411982D01*
G01Y1406707D02*
Y1408045D01*
G01D02*
Y1406707D01*
G01Y1411982D02*
Y1410644D01*
G01Y1415919D02*
Y1414581D01*
G01Y1423793D02*
Y1422455D01*
G01Y1419856D02*
Y1418518D01*
G01Y1427730D02*
Y1426392D01*
G01X8523Y1408045D02*
Y1406707D01*
G01Y1408045D02*
Y1406707D01*
G01Y1411982D02*
Y1410644D01*
G01Y1411982D02*
Y1410644D01*
G01Y1415919D02*
Y1414581D01*
G01Y1415919D02*
Y1414581D01*
G01Y1419856D02*
Y1418518D01*
G01Y1423793D02*
Y1422455D01*
G01Y1419856D02*
Y1418518D01*
G01Y1423793D02*
Y1422455D01*
G01Y1427730D02*
Y1426392D01*
G01Y1427730D02*
Y1426392D01*
G01X0Y1409252D02*
Y1714167D01*
G01Y1409252D02*
Y1714167D01*
G01Y1423793D02*
Y1424581D01*
G01Y1425604D02*
Y1426392D01*
G01Y1419856D02*
Y1420644D01*
G01Y1421667D02*
Y1422455D01*
G01Y1415919D02*
Y1416707D01*
G01Y1417730D02*
Y1418518D01*
G01Y1411982D02*
Y1412770D01*
G01Y1409856D02*
Y1410644D01*
G01Y1413793D02*
Y1414581D01*
G01Y1408045D02*
Y1408833D01*
G01Y1405919D02*
Y1406707D01*
G01D02*
Y1405919D01*
G01Y1408833D02*
Y1408045D01*
G01Y1410644D02*
Y1409856D01*
G01Y1414581D02*
Y1413793D01*
G01Y1412770D02*
Y1411982D01*
G01Y1418518D02*
Y1417730D01*
G01Y1416707D02*
Y1415919D01*
G01Y1422455D02*
Y1421667D01*
G01Y1420644D02*
Y1419856D01*
G01Y1426392D02*
Y1425604D01*
G01Y1424581D02*
Y1423793D01*
G01X-984Y1426392D02*
Y1427730D01*
G01Y1422455D02*
Y1423793D01*
G01Y1418518D02*
Y1419856D01*
G01Y1414581D02*
Y1415919D01*
G01Y1410644D02*
Y1411982D01*
G01Y1406707D02*
Y1408045D01*
G01D02*
Y1406707D01*
G01Y1411982D02*
Y1410644D01*
G01Y1415919D02*
Y1414581D01*
G01Y1423793D02*
Y1422455D01*
G01Y1419856D02*
Y1418518D01*
G01Y1427730D02*
Y1426392D01*
G01X-2251Y1408793D02*
Y1405959D01*
G01Y1412730D02*
Y1409896D01*
G01Y1416667D02*
Y1413833D01*
G01Y1420604D02*
Y1417770D01*
G01Y1424541D02*
Y1421707D01*
G01Y1428478D02*
Y1425644D01*
G01X-2520Y1408478D02*
Y1406274D01*
G01Y1412416D02*
Y1410211D01*
G01Y1416353D02*
Y1414148D01*
G01Y1424227D02*
Y1422022D01*
G01Y1420290D02*
Y1418085D01*
G01Y1428164D02*
Y1425959D01*
G01X-1969Y1408833D02*
X-2196Y1408439D01*
G01X-1969Y1408833D02*
X-2196Y1408439D01*
G01X-1969Y1412770D02*
X-2196Y1412376D01*
G01X-1969Y1412770D02*
X-2196Y1412376D01*
G01X-1969Y1416707D02*
X-2196Y1416313D01*
G01X-1969Y1416707D02*
X-2196Y1416313D01*
G01X-1969Y1420644D02*
X-2196Y1420250D01*
G01X-1969Y1420644D02*
X-2196Y1420250D01*
G01X-1969Y1424581D02*
X-2196Y1424187D01*
G01X-1969Y1424581D02*
X-2196Y1424187D01*
G01X14580Y1446077D02*
X15464Y1446274D01*
G01X14580Y1446077D02*
X15464Y1446274D01*
G01X15078Y1446077D02*
X15962Y1446274D01*
G01D02*
X15078Y1446077D01*
G01X14580Y1442140D02*
X15464Y1442337D01*
G01X14580Y1442140D02*
X15464Y1442337D01*
G01X15078Y1442140D02*
X15962Y1442337D01*
G01D02*
X15078Y1442140D01*
G01X14580Y1438203D02*
X15464Y1438400D01*
G01X14580Y1438203D02*
X15464Y1438400D01*
G01X15078Y1438203D02*
X15962Y1438400D01*
G01D02*
X15078Y1438203D01*
G01X14580Y1434266D02*
X15464Y1434463D01*
G01X14580Y1434266D02*
X15464Y1434463D01*
G01X15078Y1434266D02*
X15962Y1434463D01*
G01D02*
X15078Y1434266D01*
G01X14580Y1430329D02*
X15464Y1430526D01*
G01X14580Y1430329D02*
X15464Y1430526D01*
G01X15078Y1430329D02*
X15962Y1430526D01*
G01D02*
X15078Y1430329D01*
G01X12601Y1447416D02*
X15078D01*
G01X-984D02*
X15078D01*
G01X8523D02*
X12601D01*
G01X0D02*
X8523D01*
G01X0D02*
X-984D01*
G01X15464Y1447219D02*
X15962D01*
G01D02*
X15464D01*
G01Y1446274D02*
X15962D01*
G01D02*
X15464D01*
G01X8523Y1446077D02*
X15078D01*
G01X-984D02*
X0D01*
G01X8523D02*
X0D01*
G01X15078D02*
X-984D01*
G01X-1969Y1445290D02*
X0D01*
G01D02*
X-1969D01*
G01Y1444266D02*
X0D01*
G01X-1969D02*
X0D01*
G01X12601Y1443478D02*
X15078D01*
G01X-984D02*
X15078D01*
G01X8523D02*
X12601D01*
G01X0D02*
X8523D01*
G01X0D02*
X-984D01*
G01X15464Y1443282D02*
X15962D01*
G01D02*
X15464D01*
G01Y1442337D02*
X15962D01*
G01D02*
X15464D01*
G01X8523Y1442140D02*
X15078D01*
G01X-984D02*
X0D01*
G01X8523D02*
X0D01*
G01X15078D02*
X-984D01*
G01X-1969Y1441353D02*
X0D01*
G01D02*
X-1969D01*
G01Y1440329D02*
X0D01*
G01X-1969D02*
X0D01*
G01X12601Y1439541D02*
X15078D01*
G01X-984D02*
X15078D01*
G01X8523D02*
X12601D01*
G01X0D02*
X8523D01*
G01X0D02*
X-984D01*
G01X15464Y1439345D02*
X15962D01*
G01D02*
X15464D01*
G01Y1438400D02*
X15962D01*
G01D02*
X15464D01*
G01X8523Y1438203D02*
X15078D01*
G01X-984D02*
X0D01*
G01X8523D02*
X0D01*
G01X15078D02*
X-984D01*
G01X-1969Y1437416D02*
X0D01*
G01D02*
X-1969D01*
G01Y1436392D02*
X0D01*
G01X-1969D02*
X0D01*
G01X12601Y1435604D02*
X15078D01*
G01X-984D02*
X15078D01*
G01X8523D02*
X12601D01*
G01X0D02*
X8523D01*
G01X0D02*
X-984D01*
G01X15464Y1435408D02*
X15962D01*
G01D02*
X15464D01*
G01Y1434463D02*
X15962D01*
G01D02*
X15464D01*
G01X8523Y1434266D02*
X15078D01*
G01X-984D02*
X0D01*
G01X8523D02*
X0D01*
G01X15078D02*
X-984D01*
G01X-1969Y1433478D02*
X0D01*
G01D02*
X-1969D01*
G01Y1432455D02*
X0D01*
G01X-1969D02*
X0D01*
G01X12601Y1431667D02*
X15078D01*
G01X-984D02*
X15078D01*
G01X8523D02*
X12601D01*
G01X0D02*
X8523D01*
G01X0D02*
X-984D01*
G01X15464Y1431471D02*
X15962D01*
G01D02*
X15464D01*
G01Y1430526D02*
X15962D01*
G01D02*
X15464D01*
G01X8523Y1430329D02*
X15078D01*
G01X-984D02*
X0D01*
G01X8523D02*
X0D01*
G01X15078D02*
X-984D01*
G01X-1969Y1429541D02*
X0D01*
G01D02*
X-1969D01*
G01Y1428518D02*
X0D01*
G01X-1969D02*
X0D01*
G01X12601Y1427730D02*
X15078D01*
G01X-984D02*
X15078D01*
G01X8523D02*
X12601D01*
G01X0D02*
X8523D01*
G01X0D02*
X-984D01*
G01X15464Y1427534D02*
X15962D01*
G01D02*
X15464D01*
G01X15078Y1447416D02*
X15962Y1447219D01*
G01D02*
X15078Y1447416D01*
G01X14580D02*
X15464Y1447219D01*
G01X14580Y1447416D02*
X15464Y1447219D01*
G01X15078Y1443478D02*
X15962Y1443282D01*
G01D02*
X15078Y1443478D01*
G01X14580D02*
X15464Y1443282D01*
G01X14580Y1443478D02*
X15464Y1443282D01*
G01X15078Y1439541D02*
X15962Y1439345D01*
G01D02*
X15078Y1439541D01*
G01X14580D02*
X15464Y1439345D01*
G01X14580Y1439541D02*
X15464Y1439345D01*
G01X15078Y1435604D02*
X15962Y1435408D01*
G01D02*
X15078Y1435604D01*
G01X14580D02*
X15464Y1435408D01*
G01X14580Y1435604D02*
X15464Y1435408D01*
G01X15078Y1431667D02*
X15962Y1431471D01*
G01D02*
X15078Y1431667D01*
G01X14580D02*
X15464Y1431471D01*
G01X14580Y1431667D02*
X15464Y1431471D01*
G01X15078Y1427730D02*
X15962Y1427534D01*
G01D02*
X15078Y1427730D01*
G01X14580D02*
X15464Y1427534D01*
G01X14580Y1427730D02*
X15464Y1427534D01*
G01X-2196Y1445683D02*
X-1969Y1445290D01*
G01X-2196Y1445683D02*
X-1969Y1445290D01*
G01X-2196Y1441746D02*
X-1969Y1441353D01*
G01X-2196Y1441746D02*
X-1969Y1441353D01*
G01X-2196Y1437809D02*
X-1969Y1437416D01*
G01X-2196Y1437809D02*
X-1969Y1437416D01*
G01X-2196Y1433872D02*
X-1969Y1433478D01*
G01X-2196Y1433872D02*
X-1969Y1433478D01*
G01X-2196Y1429935D02*
X-1969Y1429541D01*
G01X-2196Y1429935D02*
X-1969Y1429541D01*
G01X15962Y1446274D02*
Y1447219D01*
G01Y1442337D02*
Y1443282D01*
G01Y1438400D02*
Y1439345D01*
G01Y1434463D02*
Y1435408D01*
G01Y1430526D02*
Y1431471D01*
G01D02*
Y1430526D01*
G01Y1435408D02*
Y1434463D01*
G01Y1439345D02*
Y1438400D01*
G01Y1443282D02*
Y1442337D01*
G01Y1447219D02*
Y1446274D01*
G01X15464D02*
Y1447219D01*
G01Y1442337D02*
Y1443282D01*
G01Y1438400D02*
Y1439345D01*
G01Y1434463D02*
Y1435408D01*
G01Y1430526D02*
Y1431471D01*
G01D02*
Y1430526D01*
G01Y1435408D02*
Y1434463D01*
G01Y1439345D02*
Y1438400D01*
G01Y1447219D02*
Y1446274D01*
G01Y1443282D02*
Y1442337D01*
G01X13424Y1442140D02*
Y1443478D01*
G01Y1446077D02*
Y1447416D01*
G01Y1438203D02*
Y1439541D01*
G01Y1434266D02*
Y1435604D01*
G01Y1430329D02*
Y1431667D01*
G01D02*
Y1430329D01*
G01Y1435604D02*
Y1434266D01*
G01Y1439541D02*
Y1438203D01*
G01Y1447416D02*
Y1446077D01*
G01Y1443478D02*
Y1442140D01*
G01X12601Y1446077D02*
Y1447416D01*
G01Y1442140D02*
Y1443478D01*
G01Y1438203D02*
Y1439541D01*
G01Y1434266D02*
Y1435604D01*
G01Y1430329D02*
Y1431667D01*
G01D02*
Y1430329D01*
G01Y1435604D02*
Y1434266D01*
G01Y1439541D02*
Y1438203D01*
G01Y1447416D02*
Y1446077D01*
G01Y1443478D02*
Y1442140D01*
G01X8523Y1431667D02*
Y1430329D01*
G01Y1431667D02*
Y1430329D01*
G01Y1435604D02*
Y1434266D01*
G01Y1435604D02*
Y1434266D01*
G01Y1439541D02*
Y1438203D01*
G01Y1439541D02*
Y1438203D01*
G01Y1447416D02*
Y1446077D01*
G01Y1443478D02*
Y1442140D01*
G01Y1443478D02*
Y1442140D01*
G01Y1447416D02*
Y1446077D01*
G01X0Y1447416D02*
Y1448203D01*
G01Y1443478D02*
Y1444266D01*
G01Y1445290D02*
Y1446077D01*
G01Y1439541D02*
Y1440329D01*
G01Y1441353D02*
Y1442140D01*
G01Y1435604D02*
Y1436392D01*
G01Y1433478D02*
Y1434266D01*
G01Y1437416D02*
Y1438203D01*
G01Y1431667D02*
Y1432455D01*
G01Y1429541D02*
Y1430329D01*
G01Y1427730D02*
Y1428518D01*
G01D02*
Y1427730D01*
G01Y1430329D02*
Y1429541D01*
G01Y1432455D02*
Y1431667D01*
G01Y1434266D02*
Y1433478D01*
G01Y1438203D02*
Y1437416D01*
G01Y1436392D02*
Y1435604D01*
G01Y1442140D02*
Y1441353D01*
G01Y1440329D02*
Y1439541D01*
G01Y1446077D02*
Y1445290D01*
G01Y1444266D02*
Y1443478D01*
G01Y1448203D02*
Y1447416D01*
G01X-984Y1446077D02*
Y1447416D01*
G01Y1442140D02*
Y1443478D01*
G01Y1438203D02*
Y1439541D01*
G01Y1434266D02*
Y1435604D01*
G01Y1430329D02*
Y1431667D01*
G01D02*
Y1430329D01*
G01Y1435604D02*
Y1434266D01*
G01Y1439541D02*
Y1438203D01*
G01Y1447416D02*
Y1446077D01*
G01Y1443478D02*
Y1442140D01*
G01X-2251Y1432416D02*
Y1429581D01*
G01Y1436353D02*
Y1433518D01*
G01Y1440290D02*
Y1437455D01*
G01Y1444227D02*
Y1441392D01*
G01Y1448164D02*
Y1445329D01*
G01X-2520Y1432101D02*
Y1429896D01*
G01Y1436038D02*
Y1433833D01*
G01Y1439975D02*
Y1437770D01*
G01Y1443912D02*
Y1441707D01*
G01Y1447849D02*
Y1445644D01*
G01X-1969Y1428518D02*
X-2196Y1428124D01*
G01X-1969Y1428518D02*
X-2196Y1428124D01*
G01X-1969Y1432455D02*
X-2196Y1432061D01*
G01X-1969Y1432455D02*
X-2196Y1432061D01*
G01X-1969Y1436392D02*
X-2196Y1435998D01*
G01X-1969Y1436392D02*
X-2196Y1435998D01*
G01X-1969Y1440329D02*
X-2196Y1439935D01*
G01X-1969Y1440329D02*
X-2196Y1439935D01*
G01X-1969Y1444266D02*
X-2196Y1443872D01*
G01X-1969Y1444266D02*
X-2196Y1443872D01*
G01X-1969Y1448203D02*
X-2196Y1447809D01*
G01X-1969Y1448203D02*
X-2196Y1447809D01*
G01X14580Y1465762D02*
X15464Y1465959D01*
G01X14580Y1465762D02*
X15464Y1465959D01*
G01X15078Y1465762D02*
X15962Y1465959D01*
G01D02*
X15078Y1465762D01*
G01X14580Y1461825D02*
X15464Y1462022D01*
G01X14580Y1461825D02*
X15464Y1462022D01*
G01X15078Y1461825D02*
X15962Y1462022D01*
G01D02*
X15078Y1461825D01*
G01X14580Y1457888D02*
X15464Y1458085D01*
G01X14580Y1457888D02*
X15464Y1458085D01*
G01X15078Y1457888D02*
X15962Y1458085D01*
G01D02*
X15078Y1457888D01*
G01X14580Y1453951D02*
X15464Y1454148D01*
G01X14580Y1453951D02*
X15464Y1454148D01*
G01X15078Y1453951D02*
X15962Y1454148D01*
G01D02*
X15078Y1453951D01*
G01X14580Y1450014D02*
X15464Y1450211D01*
G01X14580Y1450014D02*
X15464Y1450211D01*
G01X15078Y1450014D02*
X15962Y1450211D01*
G01D02*
X15078Y1450014D01*
G01X-1969Y1468912D02*
X0D01*
G01D02*
X-1969D01*
G01Y1467888D02*
X0D01*
G01X-1969D02*
X0D01*
G01X12601Y1467101D02*
X15078D01*
G01X-984D02*
X15078D01*
G01X8523D02*
X12601D01*
G01X0D02*
X8523D01*
G01X0D02*
X-984D01*
G01X15464Y1466904D02*
X15962D01*
G01D02*
X15464D01*
G01Y1465959D02*
X15962D01*
G01D02*
X15464D01*
G01X8523Y1465762D02*
X15078D01*
G01X-984D02*
X0D01*
G01X8523D02*
X0D01*
G01X15078D02*
X-984D01*
G01X-1969Y1464975D02*
X0D01*
G01D02*
X-1969D01*
G01Y1463951D02*
X0D01*
G01X-1969D02*
X0D01*
G01X12601Y1463164D02*
X15078D01*
G01X-984D02*
X15078D01*
G01X8523D02*
X12601D01*
G01X0D02*
X8523D01*
G01X0D02*
X-984D01*
G01X15464Y1462967D02*
X15962D01*
G01D02*
X15464D01*
G01Y1462022D02*
X15962D01*
G01D02*
X15464D01*
G01X8523Y1461825D02*
X15078D01*
G01X-984D02*
X0D01*
G01X8523D02*
X0D01*
G01X15078D02*
X-984D01*
G01X-1969Y1461038D02*
X0D01*
G01D02*
X-1969D01*
G01Y1460014D02*
X0D01*
G01X-1969D02*
X0D01*
G01X12601Y1459227D02*
X15078D01*
G01X-984D02*
X15078D01*
G01X8523D02*
X12601D01*
G01X0D02*
X8523D01*
G01X0D02*
X-984D01*
G01X15464Y1459030D02*
X15962D01*
G01D02*
X15464D01*
G01Y1458085D02*
X15962D01*
G01D02*
X15464D01*
G01X8523Y1457888D02*
X15078D01*
G01X-984D02*
X0D01*
G01X8523D02*
X0D01*
G01X15078D02*
X-984D01*
G01X-1969Y1457101D02*
X0D01*
G01D02*
X-1969D01*
G01Y1456077D02*
X0D01*
G01X-1969D02*
X0D01*
G01X12601Y1455290D02*
X15078D01*
G01X-984D02*
X15078D01*
G01X8523D02*
X12601D01*
G01X0D02*
X8523D01*
G01X0D02*
X-984D01*
G01X15464Y1455093D02*
X15962D01*
G01D02*
X15464D01*
G01Y1454148D02*
X15962D01*
G01D02*
X15464D01*
G01X8523Y1453951D02*
X15078D01*
G01X-984D02*
X0D01*
G01X8523D02*
X0D01*
G01X15078D02*
X-984D01*
G01X-1969Y1453164D02*
X0D01*
G01D02*
X-1969D01*
G01Y1452140D02*
X0D01*
G01X-1969D02*
X0D01*
G01X12601Y1451353D02*
X15078D01*
G01X-984D02*
X15078D01*
G01X8523D02*
X12601D01*
G01X0D02*
X8523D01*
G01X0D02*
X-984D01*
G01X15464Y1451156D02*
X15962D01*
G01D02*
X15464D01*
G01Y1450211D02*
X15962D01*
G01D02*
X15464D01*
G01X8523Y1450014D02*
X15078D01*
G01X-984D02*
X0D01*
G01X8523D02*
X0D01*
G01X15078D02*
X-984D01*
G01X-1969Y1449227D02*
X0D01*
G01D02*
X-1969D01*
G01Y1448203D02*
X0D01*
G01X-1969D02*
X0D01*
G01X15078Y1467101D02*
X15962Y1466904D01*
G01D02*
X15078Y1467101D01*
G01X14580D02*
X15464Y1466904D01*
G01X14580Y1467101D02*
X15464Y1466904D01*
G01X15078Y1463164D02*
X15962Y1462967D01*
G01D02*
X15078Y1463164D01*
G01X14580D02*
X15464Y1462967D01*
G01X14580Y1463164D02*
X15464Y1462967D01*
G01X15078Y1459227D02*
X15962Y1459030D01*
G01D02*
X15078Y1459227D01*
G01X14580D02*
X15464Y1459030D01*
G01X14580Y1459227D02*
X15464Y1459030D01*
G01X15078Y1455290D02*
X15962Y1455093D01*
G01D02*
X15078Y1455290D01*
G01X14580D02*
X15464Y1455093D01*
G01X14580Y1455290D02*
X15464Y1455093D01*
G01X15078Y1451353D02*
X15962Y1451156D01*
G01D02*
X15078Y1451353D01*
G01X14580D02*
X15464Y1451156D01*
G01X14580Y1451353D02*
X15464Y1451156D01*
G01X-2196Y1469305D02*
X-1969Y1468912D01*
G01X-2196Y1469305D02*
X-1969Y1468912D01*
G01X-2196Y1465368D02*
X-1969Y1464975D01*
G01X-2196Y1465368D02*
X-1969Y1464975D01*
G01X-2196Y1461431D02*
X-1969Y1461038D01*
G01X-2196Y1461431D02*
X-1969Y1461038D01*
G01X-2196Y1457494D02*
X-1969Y1457101D01*
G01X-2196Y1457494D02*
X-1969Y1457101D01*
G01X-2196Y1453557D02*
X-1969Y1453164D01*
G01X-2196Y1453557D02*
X-1969Y1453164D01*
G01X-2196Y1449620D02*
X-1969Y1449227D01*
G01X-2196Y1449620D02*
X-1969Y1449227D01*
G01X15962Y1465959D02*
Y1466904D01*
G01Y1462022D02*
Y1462967D01*
G01Y1458085D02*
Y1459030D01*
G01Y1454148D02*
Y1455093D01*
G01Y1450211D02*
Y1451156D01*
G01D02*
Y1450211D01*
G01Y1455093D02*
Y1454148D01*
G01Y1459030D02*
Y1458085D01*
G01Y1462967D02*
Y1462022D01*
G01Y1466904D02*
Y1465959D01*
G01X15464D02*
Y1466904D01*
G01Y1462022D02*
Y1462967D01*
G01Y1458085D02*
Y1459030D01*
G01Y1454148D02*
Y1455093D01*
G01Y1450211D02*
Y1451156D01*
G01D02*
Y1450211D01*
G01Y1455093D02*
Y1454148D01*
G01Y1459030D02*
Y1458085D01*
G01Y1462967D02*
Y1462022D01*
G01Y1466904D02*
Y1465959D01*
G01X13424Y1465762D02*
Y1467101D01*
G01Y1461825D02*
Y1463164D01*
G01Y1457888D02*
Y1459227D01*
G01Y1453951D02*
Y1455290D01*
G01Y1450014D02*
Y1451353D01*
G01D02*
Y1450014D01*
G01Y1455290D02*
Y1453951D01*
G01Y1459227D02*
Y1457888D01*
G01Y1463164D02*
Y1461825D01*
G01Y1467101D02*
Y1465762D01*
G01X12601D02*
Y1467101D01*
G01Y1461825D02*
Y1463164D01*
G01Y1457888D02*
Y1459227D01*
G01Y1453951D02*
Y1455290D01*
G01Y1450014D02*
Y1451353D01*
G01D02*
Y1450014D01*
G01Y1455290D02*
Y1453951D01*
G01Y1459227D02*
Y1457888D01*
G01Y1463164D02*
Y1461825D01*
G01Y1467101D02*
Y1465762D01*
G01X8523Y1451353D02*
Y1450014D01*
G01Y1451353D02*
Y1450014D01*
G01Y1455290D02*
Y1453951D01*
G01Y1455290D02*
Y1453951D01*
G01Y1459227D02*
Y1457888D01*
G01Y1459227D02*
Y1457888D01*
G01Y1463164D02*
Y1461825D01*
G01Y1463164D02*
Y1461825D01*
G01Y1467101D02*
Y1465762D01*
G01Y1467101D02*
Y1465762D01*
G01X0Y1467101D02*
Y1467888D01*
G01Y1468912D02*
Y1469699D01*
G01Y1463164D02*
Y1463951D01*
G01Y1464975D02*
Y1465762D01*
G01Y1459227D02*
Y1460014D01*
G01Y1457101D02*
Y1457888D01*
G01Y1461038D02*
Y1461825D01*
G01Y1455290D02*
Y1456077D01*
G01Y1453164D02*
Y1453951D01*
G01Y1451353D02*
Y1452140D01*
G01Y1449227D02*
Y1450014D01*
G01D02*
Y1449227D01*
G01Y1452140D02*
Y1451353D01*
G01Y1453951D02*
Y1453164D01*
G01Y1456077D02*
Y1455290D01*
G01Y1457888D02*
Y1457101D01*
G01Y1461825D02*
Y1461038D01*
G01Y1460014D02*
Y1459227D01*
G01Y1465762D02*
Y1464975D01*
G01Y1463951D02*
Y1463164D01*
G01Y1469699D02*
Y1468912D01*
G01Y1467888D02*
Y1467101D01*
G01X-984Y1465762D02*
Y1467101D01*
G01Y1461825D02*
Y1463164D01*
G01Y1457888D02*
Y1459227D01*
G01Y1453951D02*
Y1455290D01*
G01Y1450014D02*
Y1451353D01*
G01D02*
Y1450014D01*
G01Y1455290D02*
Y1453951D01*
G01Y1459227D02*
Y1457888D01*
G01Y1463164D02*
Y1461825D01*
G01Y1467101D02*
Y1465762D01*
G01X-2251Y1452101D02*
Y1449266D01*
G01Y1456038D02*
Y1453203D01*
G01Y1459975D02*
Y1457140D01*
G01Y1463912D02*
Y1461077D01*
G01Y1467849D02*
Y1465014D01*
G01Y1471786D02*
Y1468951D01*
G01X-2520Y1451786D02*
Y1449581D01*
G01Y1455723D02*
Y1453518D01*
G01Y1459660D02*
Y1457455D01*
G01Y1463597D02*
Y1461392D01*
G01Y1467534D02*
Y1465329D01*
G01X-1969Y1452140D02*
X-2196Y1451746D01*
G01X-1969Y1452140D02*
X-2196Y1451746D01*
G01X-1969Y1456077D02*
X-2196Y1455683D01*
G01X-1969Y1456077D02*
X-2196Y1455683D01*
G01X-1969Y1460014D02*
X-2196Y1459620D01*
G01X-1969Y1460014D02*
X-2196Y1459620D01*
G01X-1969Y1463951D02*
X-2196Y1463557D01*
G01X-1969Y1463951D02*
X-2196Y1463557D01*
G01X-1969Y1467888D02*
X-2196Y1467494D01*
G01X-1969Y1467888D02*
X-2196Y1467494D01*
G01X14580Y1489384D02*
X15464Y1489581D01*
G01X14580Y1489384D02*
X15464Y1489581D01*
G01X15078Y1489384D02*
X15962Y1489581D01*
G01D02*
X15078Y1489384D01*
G01X14580Y1485447D02*
X15464Y1485644D01*
G01X14580Y1485447D02*
X15464Y1485644D01*
G01X15078Y1485447D02*
X15962Y1485644D01*
G01D02*
X15078Y1485447D01*
G01X14580Y1481510D02*
X15464Y1481707D01*
G01X14580Y1481510D02*
X15464Y1481707D01*
G01X15078Y1481510D02*
X15962Y1481707D01*
G01D02*
X15078Y1481510D01*
G01X14580Y1477573D02*
X15464Y1477770D01*
G01X14580Y1477573D02*
X15464Y1477770D01*
G01X15078Y1477573D02*
X15962Y1477770D01*
G01D02*
X15078Y1477573D01*
G01X14580Y1473636D02*
X15464Y1473833D01*
G01X14580Y1473636D02*
X15464Y1473833D01*
G01X15078Y1473636D02*
X15962Y1473833D01*
G01D02*
X15078Y1473636D01*
G01X14580Y1469699D02*
X15464Y1469896D01*
G01X14580Y1469699D02*
X15464Y1469896D01*
G01X15078Y1469699D02*
X15962Y1469896D01*
G01D02*
X15078Y1469699D01*
G01X15464Y1489581D02*
X15962D01*
G01D02*
X15464D01*
G01X8523Y1489384D02*
X15078D01*
G01X-984D02*
X0D01*
G01X8523D02*
X0D01*
G01X15078D02*
X-984D01*
G01X-1969Y1488597D02*
X0D01*
G01D02*
X-1969D01*
G01Y1487573D02*
X0D01*
G01X-1969D02*
X0D01*
G01X12601Y1486786D02*
X15078D01*
G01X-984D02*
X15078D01*
G01X8523D02*
X12601D01*
G01X0D02*
X8523D01*
G01X0D02*
X-984D01*
G01X15464Y1486589D02*
X15962D01*
G01D02*
X15464D01*
G01Y1485644D02*
X15962D01*
G01D02*
X15464D01*
G01X8523Y1485447D02*
X15078D01*
G01X-984D02*
X0D01*
G01X8523D02*
X0D01*
G01X15078D02*
X-984D01*
G01X-1969Y1484660D02*
X0D01*
G01D02*
X-1969D01*
G01Y1483636D02*
X0D01*
G01X-1969D02*
X0D01*
G01X12601Y1482849D02*
X15078D01*
G01X-984D02*
X15078D01*
G01X8523D02*
X12601D01*
G01X0D02*
X8523D01*
G01X0D02*
X-984D01*
G01X15464Y1482652D02*
X15962D01*
G01D02*
X15464D01*
G01Y1481707D02*
X15962D01*
G01D02*
X15464D01*
G01X8523Y1481510D02*
X15078D01*
G01X-984D02*
X0D01*
G01X8523D02*
X0D01*
G01X15078D02*
X-984D01*
G01X-1969Y1480723D02*
X0D01*
G01D02*
X-1969D01*
G01Y1479699D02*
X0D01*
G01X-1969D02*
X0D01*
G01X12601Y1478912D02*
X15078D01*
G01X-984D02*
X15078D01*
G01X8523D02*
X12601D01*
G01X0D02*
X8523D01*
G01X0D02*
X-984D01*
G01X15464Y1478715D02*
X15962D01*
G01D02*
X15464D01*
G01Y1477770D02*
X15962D01*
G01D02*
X15464D01*
G01X8523Y1477573D02*
X15078D01*
G01X-984D02*
X0D01*
G01X8523D02*
X0D01*
G01X15078D02*
X-984D01*
G01X-1969Y1476786D02*
X0D01*
G01D02*
X-1969D01*
G01Y1475762D02*
X0D01*
G01X-1969D02*
X0D01*
G01X12601Y1474975D02*
X15078D01*
G01X-984D02*
X15078D01*
G01X8523D02*
X12601D01*
G01X0D02*
X8523D01*
G01X0D02*
X-984D01*
G01X15464Y1474778D02*
X15962D01*
G01D02*
X15464D01*
G01Y1473833D02*
X15962D01*
G01D02*
X15464D01*
G01X8523Y1473636D02*
X15078D01*
G01X-984D02*
X0D01*
G01X8523D02*
X0D01*
G01X15078D02*
X-984D01*
G01X-1969Y1472849D02*
X0D01*
G01D02*
X-1969D01*
G01Y1471825D02*
X0D01*
G01X-1969D02*
X0D01*
G01X12601Y1471038D02*
X15078D01*
G01X-984D02*
X15078D01*
G01X8523D02*
X12601D01*
G01X0D02*
X8523D01*
G01X0D02*
X-984D01*
G01X15464Y1470841D02*
X15962D01*
G01D02*
X15464D01*
G01Y1469896D02*
X15962D01*
G01D02*
X15464D01*
G01X8523Y1469699D02*
X15078D01*
G01X-984D02*
X0D01*
G01X8523D02*
X0D01*
G01X15078D02*
X-984D01*
G01X15078Y1486786D02*
X15962Y1486589D01*
G01D02*
X15078Y1486786D01*
G01X14580D02*
X15464Y1486589D01*
G01X14580Y1486786D02*
X15464Y1486589D01*
G01X15078Y1482849D02*
X15962Y1482652D01*
G01D02*
X15078Y1482849D01*
G01X14580D02*
X15464Y1482652D01*
G01X14580Y1482849D02*
X15464Y1482652D01*
G01X15078Y1478912D02*
X15962Y1478715D01*
G01D02*
X15078Y1478912D01*
G01X14580D02*
X15464Y1478715D01*
G01X14580Y1478912D02*
X15464Y1478715D01*
G01X15078Y1474975D02*
X15962Y1474778D01*
G01D02*
X15078Y1474975D01*
G01X14580D02*
X15464Y1474778D01*
G01X14580Y1474975D02*
X15464Y1474778D01*
G01X15078Y1471038D02*
X15962Y1470841D01*
G01D02*
X15078Y1471038D01*
G01X14580D02*
X15464Y1470841D01*
G01X14580Y1471038D02*
X15464Y1470841D01*
G01X-2196Y1488990D02*
X-1969Y1488597D01*
G01X-2196Y1488990D02*
X-1969Y1488597D01*
G01X-2196Y1485053D02*
X-1969Y1484660D01*
G01X-2196Y1485053D02*
X-1969Y1484660D01*
G01X-2196Y1481116D02*
X-1969Y1480723D01*
G01X-2196Y1481116D02*
X-1969Y1480723D01*
G01X-2196Y1477179D02*
X-1969Y1476786D01*
G01X-2196Y1477179D02*
X-1969Y1476786D01*
G01X-2196Y1473242D02*
X-1969Y1472849D01*
G01X-2196Y1473242D02*
X-1969Y1472849D01*
G01X15962Y1489581D02*
Y1490526D01*
G01Y1485644D02*
Y1486589D01*
G01Y1481707D02*
Y1482652D01*
G01Y1477770D02*
Y1478715D01*
G01Y1473833D02*
Y1474778D01*
G01Y1469896D02*
Y1470841D01*
G01D02*
Y1469896D01*
G01Y1474778D02*
Y1473833D01*
G01Y1478715D02*
Y1477770D01*
G01Y1482652D02*
Y1481707D01*
G01Y1486589D02*
Y1485644D01*
G01Y1490526D02*
Y1489581D01*
G01X15464D02*
Y1490526D01*
G01Y1485644D02*
Y1486589D01*
G01Y1481707D02*
Y1482652D01*
G01Y1477770D02*
Y1478715D01*
G01Y1473833D02*
Y1474778D01*
G01Y1469896D02*
Y1470841D01*
G01D02*
Y1469896D01*
G01Y1474778D02*
Y1473833D01*
G01Y1478715D02*
Y1477770D01*
G01Y1482652D02*
Y1481707D01*
G01Y1486589D02*
Y1485644D01*
G01Y1490526D02*
Y1489581D01*
G01X13424Y1489384D02*
Y1490723D01*
G01Y1485447D02*
Y1486786D01*
G01Y1481510D02*
Y1482849D01*
G01Y1477573D02*
Y1478912D01*
G01Y1473636D02*
Y1474975D01*
G01Y1469699D02*
Y1471038D01*
G01D02*
Y1469699D01*
G01Y1474975D02*
Y1473636D01*
G01Y1478912D02*
Y1477573D01*
G01Y1482849D02*
Y1481510D01*
G01Y1486786D02*
Y1485447D01*
G01Y1490723D02*
Y1489384D01*
G01X12601D02*
Y1490723D01*
G01Y1485447D02*
Y1486786D01*
G01Y1481510D02*
Y1482849D01*
G01Y1477573D02*
Y1478912D01*
G01Y1473636D02*
Y1474975D01*
G01Y1469699D02*
Y1471038D01*
G01D02*
Y1469699D01*
G01Y1474975D02*
Y1473636D01*
G01Y1478912D02*
Y1477573D01*
G01Y1482849D02*
Y1481510D01*
G01Y1486786D02*
Y1485447D01*
G01Y1490723D02*
Y1489384D01*
G01X8523Y1471038D02*
Y1469699D01*
G01Y1471038D02*
Y1469699D01*
G01Y1474975D02*
Y1473636D01*
G01Y1474975D02*
Y1473636D01*
G01Y1478912D02*
Y1477573D01*
G01Y1478912D02*
Y1477573D01*
G01Y1482849D02*
Y1481510D01*
G01Y1482849D02*
Y1481510D01*
G01Y1486786D02*
Y1485447D01*
G01Y1486786D02*
Y1485447D01*
G01Y1490723D02*
Y1489384D01*
G01Y1490723D02*
Y1489384D01*
G01X0Y1486786D02*
Y1487573D01*
G01Y1484660D02*
Y1485447D01*
G01Y1488597D02*
Y1489384D01*
G01Y1482849D02*
Y1483636D01*
G01Y1480723D02*
Y1481510D01*
G01Y1478912D02*
Y1479699D01*
G01Y1476786D02*
Y1477573D01*
G01Y1471038D02*
Y1471825D01*
G01Y1474975D02*
Y1475762D01*
G01Y1472849D02*
Y1473636D01*
G01D02*
Y1472849D01*
G01Y1471825D02*
Y1471038D01*
G01Y1475762D02*
Y1474975D01*
G01Y1477573D02*
Y1476786D01*
G01Y1479699D02*
Y1478912D01*
G01Y1481510D02*
Y1480723D01*
G01Y1483636D02*
Y1482849D01*
G01Y1485447D02*
Y1484660D01*
G01Y1489384D02*
Y1488597D01*
G01Y1487573D02*
Y1486786D01*
G01X-984Y1489384D02*
Y1490723D01*
G01Y1485447D02*
Y1486786D01*
G01Y1481510D02*
Y1482849D01*
G01Y1477573D02*
Y1478912D01*
G01Y1473636D02*
Y1474975D01*
G01Y1469699D02*
Y1471038D01*
G01D02*
Y1469699D01*
G01Y1474975D02*
Y1473636D01*
G01Y1478912D02*
Y1477573D01*
G01Y1482849D02*
Y1481510D01*
G01Y1486786D02*
Y1485447D01*
G01Y1490723D02*
Y1489384D01*
G01X-2251Y1475723D02*
Y1472888D01*
G01Y1479660D02*
Y1476825D01*
G01Y1483597D02*
Y1480762D01*
G01Y1487534D02*
Y1484699D01*
G01Y1491471D02*
Y1488636D01*
G01X-2520Y1475408D02*
Y1473203D01*
G01Y1471471D02*
Y1469266D01*
G01Y1479345D02*
Y1477140D01*
G01Y1483282D02*
Y1481077D01*
G01Y1487219D02*
Y1485014D01*
G01Y1491156D02*
Y1488951D01*
G01X-1969Y1471825D02*
X-2196Y1471431D01*
G01X-1969Y1471825D02*
X-2196Y1471431D01*
G01X-1969Y1475762D02*
X-2196Y1475368D01*
G01X-1969Y1475762D02*
X-2196Y1475368D01*
G01X-1969Y1479699D02*
X-2196Y1479305D01*
G01X-1969Y1479699D02*
X-2196Y1479305D01*
G01X-1969Y1483636D02*
X-2196Y1483242D01*
G01X-1969Y1483636D02*
X-2196Y1483242D01*
G01X-1969Y1487573D02*
X-2196Y1487179D01*
G01X-1969Y1487573D02*
X-2196Y1487179D01*
G01X14580Y1509069D02*
X15464Y1509266D01*
G01X14580Y1509069D02*
X15464Y1509266D01*
G01X15078Y1509069D02*
X15962Y1509266D01*
G01D02*
X15078Y1509069D01*
G01X14580Y1505132D02*
X15464Y1505329D01*
G01X14580Y1505132D02*
X15464Y1505329D01*
G01X15078Y1505132D02*
X15962Y1505329D01*
G01D02*
X15078Y1505132D01*
G01X14580Y1501195D02*
X15464Y1501392D01*
G01X14580Y1501195D02*
X15464Y1501392D01*
G01X15078Y1501195D02*
X15962Y1501392D01*
G01D02*
X15078Y1501195D01*
G01X14580Y1497258D02*
X15464Y1497455D01*
G01X14580Y1497258D02*
X15464Y1497455D01*
G01X15078Y1497258D02*
X15962Y1497455D01*
G01D02*
X15078Y1497258D01*
G01X14580Y1493321D02*
X15464Y1493518D01*
G01X14580Y1493321D02*
X15464Y1493518D01*
G01X15078Y1493321D02*
X15962Y1493518D01*
G01D02*
X15078Y1493321D01*
G01X-1969Y1511195D02*
X0D01*
G01X-1969D02*
X0D01*
G01X12601Y1510408D02*
X15078D01*
G01X-984D02*
X15078D01*
G01X8523D02*
X12601D01*
G01X0D02*
X8523D01*
G01X0D02*
X-984D01*
G01X15464Y1510211D02*
X15962D01*
G01D02*
X15464D01*
G01Y1509266D02*
X15962D01*
G01D02*
X15464D01*
G01X8523Y1509069D02*
X15078D01*
G01X-984D02*
X0D01*
G01X8523D02*
X0D01*
G01X15078D02*
X-984D01*
G01X-1969Y1508282D02*
X0D01*
G01D02*
X-1969D01*
G01Y1507258D02*
X0D01*
G01X-1969D02*
X0D01*
G01X12601Y1506471D02*
X15078D01*
G01X-984D02*
X15078D01*
G01X8523D02*
X12601D01*
G01X0D02*
X8523D01*
G01X0D02*
X-984D01*
G01X15464Y1506274D02*
X15962D01*
G01D02*
X15464D01*
G01Y1505329D02*
X15962D01*
G01D02*
X15464D01*
G01X8523Y1505132D02*
X15078D01*
G01X-984D02*
X0D01*
G01X8523D02*
X0D01*
G01X15078D02*
X-984D01*
G01X-1969Y1504345D02*
X0D01*
G01D02*
X-1969D01*
G01Y1503321D02*
X0D01*
G01X-1969D02*
X0D01*
G01X12601Y1502534D02*
X15078D01*
G01X-984D02*
X15078D01*
G01X8523D02*
X12601D01*
G01X0D02*
X8523D01*
G01X0D02*
X-984D01*
G01X15464Y1502337D02*
X15962D01*
G01D02*
X15464D01*
G01Y1501392D02*
X15962D01*
G01D02*
X15464D01*
G01X8523Y1501195D02*
X15078D01*
G01X-984D02*
X0D01*
G01X8523D02*
X0D01*
G01X15078D02*
X-984D01*
G01X-1969Y1500408D02*
X0D01*
G01D02*
X-1969D01*
G01Y1499384D02*
X0D01*
G01X-1969D02*
X0D01*
G01X12601Y1498597D02*
X15078D01*
G01X-984D02*
X15078D01*
G01X8523D02*
X12601D01*
G01X0D02*
X8523D01*
G01X0D02*
X-984D01*
G01X15464Y1498400D02*
X15962D01*
G01D02*
X15464D01*
G01Y1497455D02*
X15962D01*
G01D02*
X15464D01*
G01X8523Y1497258D02*
X15078D01*
G01X-984D02*
X0D01*
G01X8523D02*
X0D01*
G01X15078D02*
X-984D01*
G01X-1969Y1496471D02*
X0D01*
G01D02*
X-1969D01*
G01Y1495447D02*
X0D01*
G01X-1969D02*
X0D01*
G01X12601Y1494660D02*
X15078D01*
G01X-984D02*
X15078D01*
G01X8523D02*
X12601D01*
G01X0D02*
X8523D01*
G01X0D02*
X-984D01*
G01X15464Y1494463D02*
X15962D01*
G01D02*
X15464D01*
G01Y1493518D02*
X15962D01*
G01D02*
X15464D01*
G01X8523Y1493321D02*
X15078D01*
G01X-984D02*
X0D01*
G01X8523D02*
X0D01*
G01X15078D02*
X-984D01*
G01X-1969Y1492534D02*
X0D01*
G01D02*
X-1969D01*
G01Y1491510D02*
X0D01*
G01X-1969D02*
X0D01*
G01X12601Y1490723D02*
X15078D01*
G01X-984D02*
X15078D01*
G01X8523D02*
X12601D01*
G01X0D02*
X8523D01*
G01X0D02*
X-984D01*
G01X15464Y1490526D02*
X15962D01*
G01D02*
X15464D01*
G01X15078Y1510408D02*
X15962Y1510211D01*
G01D02*
X15078Y1510408D01*
G01X14580D02*
X15464Y1510211D01*
G01X14580Y1510408D02*
X15464Y1510211D01*
G01X15078Y1506471D02*
X15962Y1506274D01*
G01D02*
X15078Y1506471D01*
G01X14580D02*
X15464Y1506274D01*
G01X14580Y1506471D02*
X15464Y1506274D01*
G01X15078Y1502534D02*
X15962Y1502337D01*
G01D02*
X15078Y1502534D01*
G01X14580D02*
X15464Y1502337D01*
G01X14580Y1502534D02*
X15464Y1502337D01*
G01X15078Y1498597D02*
X15962Y1498400D01*
G01D02*
X15078Y1498597D01*
G01X14580D02*
X15464Y1498400D01*
G01X14580Y1498597D02*
X15464Y1498400D01*
G01X15078Y1494660D02*
X15962Y1494463D01*
G01D02*
X15078Y1494660D01*
G01X14580D02*
X15464Y1494463D01*
G01X14580Y1494660D02*
X15464Y1494463D01*
G01X15078Y1490723D02*
X15962Y1490526D01*
G01D02*
X15078Y1490723D01*
G01X14580D02*
X15464Y1490526D01*
G01X14580Y1490723D02*
X15464Y1490526D01*
G01X-2196Y1508675D02*
X-1969Y1508282D01*
G01X-2196Y1508675D02*
X-1969Y1508282D01*
G01X-2196Y1504738D02*
X-1969Y1504345D01*
G01X-2196Y1504738D02*
X-1969Y1504345D01*
G01X-2196Y1500801D02*
X-1969Y1500408D01*
G01X-2196Y1500801D02*
X-1969Y1500408D01*
G01X-2196Y1496864D02*
X-1969Y1496471D01*
G01X-2196Y1496864D02*
X-1969Y1496471D01*
G01X-2196Y1492927D02*
X-1969Y1492534D01*
G01X-2196Y1492927D02*
X-1969Y1492534D01*
G01X15962Y1509266D02*
Y1510211D01*
G01Y1505329D02*
Y1506274D01*
G01Y1501392D02*
Y1502337D01*
G01Y1497455D02*
Y1498400D01*
G01Y1493518D02*
Y1494463D01*
G01D02*
Y1493518D01*
G01Y1498400D02*
Y1497455D01*
G01Y1502337D02*
Y1501392D01*
G01Y1506274D02*
Y1505329D01*
G01Y1510211D02*
Y1509266D01*
G01X15464D02*
Y1510211D01*
G01Y1505329D02*
Y1506274D01*
G01Y1501392D02*
Y1502337D01*
G01Y1497455D02*
Y1498400D01*
G01Y1493518D02*
Y1494463D01*
G01D02*
Y1493518D01*
G01Y1498400D02*
Y1497455D01*
G01Y1502337D02*
Y1501392D01*
G01Y1506274D02*
Y1505329D01*
G01Y1510211D02*
Y1509266D01*
G01X13424Y1509069D02*
Y1510408D01*
G01Y1505132D02*
Y1506471D01*
G01Y1501195D02*
Y1502534D01*
G01Y1493321D02*
Y1494660D01*
G01Y1497258D02*
Y1498597D01*
G01D02*
Y1497258D01*
G01Y1494660D02*
Y1493321D01*
G01Y1502534D02*
Y1501195D01*
G01Y1506471D02*
Y1505132D01*
G01Y1510408D02*
Y1509069D01*
G01X12601D02*
Y1510408D01*
G01Y1505132D02*
Y1506471D01*
G01Y1501195D02*
Y1502534D01*
G01Y1493321D02*
Y1494660D01*
G01Y1497258D02*
Y1498597D01*
G01D02*
Y1497258D01*
G01Y1494660D02*
Y1493321D01*
G01Y1502534D02*
Y1501195D01*
G01Y1506471D02*
Y1505132D01*
G01Y1510408D02*
Y1509069D01*
G01X8523Y1494660D02*
Y1493321D01*
G01Y1498597D02*
Y1497258D01*
G01Y1494660D02*
Y1493321D01*
G01Y1498597D02*
Y1497258D01*
G01Y1502534D02*
Y1501195D01*
G01Y1502534D02*
Y1501195D01*
G01Y1506471D02*
Y1505132D01*
G01Y1506471D02*
Y1505132D01*
G01Y1510408D02*
Y1509069D01*
G01Y1510408D02*
Y1509069D01*
G01X0Y1510408D02*
Y1511195D01*
G01Y1508282D02*
Y1509069D01*
G01Y1506471D02*
Y1507258D01*
G01Y1504345D02*
Y1505132D01*
G01Y1498597D02*
Y1499384D01*
G01Y1502534D02*
Y1503321D01*
G01Y1500408D02*
Y1501195D01*
G01Y1494660D02*
Y1495447D01*
G01Y1496471D02*
Y1497258D01*
G01Y1490723D02*
Y1491510D01*
G01Y1492534D02*
Y1493321D01*
G01D02*
Y1492534D01*
G01Y1491510D02*
Y1490723D01*
G01Y1497258D02*
Y1496471D01*
G01Y1495447D02*
Y1494660D01*
G01Y1501195D02*
Y1500408D01*
G01Y1499384D02*
Y1498597D01*
G01Y1503321D02*
Y1502534D01*
G01Y1505132D02*
Y1504345D01*
G01Y1507258D02*
Y1506471D01*
G01Y1509069D02*
Y1508282D01*
G01Y1511195D02*
Y1510408D01*
G01X-984Y1509069D02*
Y1510408D01*
G01Y1505132D02*
Y1506471D01*
G01Y1501195D02*
Y1502534D01*
G01Y1497258D02*
Y1498597D01*
G01Y1493321D02*
Y1494660D01*
G01Y1498597D02*
Y1497258D01*
G01Y1494660D02*
Y1493321D01*
G01Y1502534D02*
Y1501195D01*
G01Y1506471D02*
Y1505132D01*
G01Y1510408D02*
Y1509069D01*
G01X-2251Y1495408D02*
Y1492573D01*
G01Y1499345D02*
Y1496510D01*
G01Y1503282D02*
Y1500447D01*
G01Y1507219D02*
Y1504384D01*
G01Y1511156D02*
Y1508321D01*
G01X-2520Y1499030D02*
Y1496825D01*
G01Y1495093D02*
Y1492888D01*
G01Y1502967D02*
Y1500762D01*
G01Y1506904D02*
Y1504699D01*
G01Y1510841D02*
Y1508636D01*
G01X-1969Y1491510D02*
X-2196Y1491116D01*
G01X-1969Y1491510D02*
X-2196Y1491116D01*
G01X-1969Y1495447D02*
X-2196Y1495053D01*
G01X-1969Y1495447D02*
X-2196Y1495053D01*
G01X-1969Y1499384D02*
X-2196Y1498990D01*
G01X-1969Y1499384D02*
X-2196Y1498990D01*
G01X-1969Y1503321D02*
X-2196Y1502927D01*
G01X-1969Y1503321D02*
X-2196Y1502927D01*
G01X-1969Y1507258D02*
X-2196Y1506864D01*
G01X-1969Y1507258D02*
X-2196Y1506864D01*
G01X-1969Y1511195D02*
X-2196Y1510801D01*
G01X-1969Y1511195D02*
X-2196Y1510801D01*
G01X14580Y1528754D02*
X15464Y1528951D01*
G01X14580Y1528754D02*
X15464Y1528951D01*
G01X15078Y1528754D02*
X15962Y1528951D01*
G01D02*
X15078Y1528754D01*
G01X14580Y1524817D02*
X15464Y1525014D01*
G01X14580Y1524817D02*
X15464Y1525014D01*
G01X15078Y1524817D02*
X15962Y1525014D01*
G01D02*
X15078Y1524817D01*
G01X14580Y1520880D02*
X15464Y1521077D01*
G01X14580Y1520880D02*
X15464Y1521077D01*
G01X15078Y1520880D02*
X15962Y1521077D01*
G01D02*
X15078Y1520880D01*
G01X14580Y1516943D02*
X15464Y1517140D01*
G01X14580Y1516943D02*
X15464Y1517140D01*
G01X15078Y1516943D02*
X15962Y1517140D01*
G01D02*
X15078Y1516943D01*
G01X14580Y1513006D02*
X15464Y1513203D01*
G01X14580Y1513006D02*
X15464Y1513203D01*
G01X15078Y1513006D02*
X15962Y1513203D01*
G01D02*
X15078Y1513006D01*
G01X-1969Y1531904D02*
X0D01*
G01D02*
X-1969D01*
G01Y1530880D02*
X0D01*
G01X-1969D02*
X0D01*
G01X12601Y1530093D02*
X15078D01*
G01X-984D02*
X15078D01*
G01X8523D02*
X12601D01*
G01X0D02*
X8523D01*
G01X0D02*
X-984D01*
G01X15464Y1529896D02*
X15962D01*
G01D02*
X15464D01*
G01Y1528951D02*
X15962D01*
G01D02*
X15464D01*
G01X8523Y1528754D02*
X15078D01*
G01X-984D02*
X0D01*
G01X8523D02*
X0D01*
G01X15078D02*
X-984D01*
G01X-1969Y1527967D02*
X0D01*
G01D02*
X-1969D01*
G01Y1526943D02*
X0D01*
G01X-1969D02*
X0D01*
G01X12601Y1526156D02*
X15078D01*
G01X-984D02*
X15078D01*
G01X8523D02*
X12601D01*
G01X0D02*
X8523D01*
G01X0D02*
X-984D01*
G01X15464Y1525959D02*
X15962D01*
G01D02*
X15464D01*
G01Y1525014D02*
X15962D01*
G01D02*
X15464D01*
G01X8523Y1524817D02*
X15078D01*
G01X-984D02*
X0D01*
G01X8523D02*
X0D01*
G01X15078D02*
X-984D01*
G01X-1969Y1524030D02*
X0D01*
G01D02*
X-1969D01*
G01Y1523006D02*
X0D01*
G01X-1969D02*
X0D01*
G01X12601Y1522219D02*
X15078D01*
G01X-984D02*
X15078D01*
G01X8523D02*
X12601D01*
G01X0D02*
X8523D01*
G01X0D02*
X-984D01*
G01X15464Y1522022D02*
X15962D01*
G01D02*
X15464D01*
G01Y1521077D02*
X15962D01*
G01D02*
X15464D01*
G01X8523Y1520880D02*
X15078D01*
G01X-984D02*
X0D01*
G01X8523D02*
X0D01*
G01X15078D02*
X-984D01*
G01X-1969Y1520093D02*
X0D01*
G01D02*
X-1969D01*
G01Y1519069D02*
X0D01*
G01X-1969D02*
X0D01*
G01X12601Y1518282D02*
X15078D01*
G01X-984D02*
X15078D01*
G01X8523D02*
X12601D01*
G01X0D02*
X8523D01*
G01X0D02*
X-984D01*
G01X15464Y1518085D02*
X15962D01*
G01D02*
X15464D01*
G01Y1517140D02*
X15962D01*
G01D02*
X15464D01*
G01X8523Y1516943D02*
X15078D01*
G01X-984D02*
X0D01*
G01X8523D02*
X0D01*
G01X15078D02*
X-984D01*
G01X-1969Y1516156D02*
X0D01*
G01D02*
X-1969D01*
G01Y1515132D02*
X0D01*
G01X-1969D02*
X0D01*
G01X12601Y1514345D02*
X15078D01*
G01X-984D02*
X15078D01*
G01X8523D02*
X12601D01*
G01X0D02*
X8523D01*
G01X0D02*
X-984D01*
G01X15464Y1514148D02*
X15962D01*
G01D02*
X15464D01*
G01Y1513203D02*
X15962D01*
G01D02*
X15464D01*
G01X8523Y1513006D02*
X15078D01*
G01X-984D02*
X0D01*
G01X8523D02*
X0D01*
G01X15078D02*
X-984D01*
G01X-1969Y1512219D02*
X0D01*
G01D02*
X-1969D01*
G01X15078Y1530093D02*
X15962Y1529896D01*
G01D02*
X15078Y1530093D01*
G01X14580D02*
X15464Y1529896D01*
G01X14580Y1530093D02*
X15464Y1529896D01*
G01X15078Y1526156D02*
X15962Y1525959D01*
G01D02*
X15078Y1526156D01*
G01X14580D02*
X15464Y1525959D01*
G01X14580Y1526156D02*
X15464Y1525959D01*
G01X15078Y1522219D02*
X15962Y1522022D01*
G01D02*
X15078Y1522219D01*
G01X14580D02*
X15464Y1522022D01*
G01X14580Y1522219D02*
X15464Y1522022D01*
G01X15078Y1518282D02*
X15962Y1518085D01*
G01D02*
X15078Y1518282D01*
G01X14580D02*
X15464Y1518085D01*
G01X14580Y1518282D02*
X15464Y1518085D01*
G01X15078Y1514345D02*
X15962Y1514148D01*
G01D02*
X15078Y1514345D01*
G01X14580D02*
X15464Y1514148D01*
G01X14580Y1514345D02*
X15464Y1514148D01*
G01X-2196Y1532297D02*
X-1969Y1531904D01*
G01X-2196Y1532297D02*
X-1969Y1531904D01*
G01X-2196Y1528360D02*
X-1969Y1527967D01*
G01X-2196Y1528360D02*
X-1969Y1527967D01*
G01X-2196Y1524423D02*
X-1969Y1524030D01*
G01X-2196Y1524423D02*
X-1969Y1524030D01*
G01X-2196Y1520486D02*
X-1969Y1520093D01*
G01X-2196Y1520486D02*
X-1969Y1520093D01*
G01X-2196Y1516549D02*
X-1969Y1516156D01*
G01X-2196Y1516549D02*
X-1969Y1516156D01*
G01X-2196Y1512612D02*
X-1969Y1512219D01*
G01X-2196Y1512612D02*
X-1969Y1512219D01*
G01X15962Y1528951D02*
Y1529896D01*
G01Y1525014D02*
Y1525959D01*
G01Y1517140D02*
Y1518085D01*
G01Y1521077D02*
Y1522022D01*
G01Y1513203D02*
Y1514148D01*
G01D02*
Y1513203D01*
G01Y1518085D02*
Y1517140D01*
G01Y1522022D02*
Y1521077D01*
G01Y1525959D02*
Y1525014D01*
G01Y1529896D02*
Y1528951D01*
G01X15464D02*
Y1529896D01*
G01Y1525014D02*
Y1525959D01*
G01Y1521077D02*
Y1522022D01*
G01Y1517140D02*
Y1518085D01*
G01Y1513203D02*
Y1514148D01*
G01D02*
Y1513203D01*
G01Y1518085D02*
Y1517140D01*
G01Y1522022D02*
Y1521077D01*
G01Y1525959D02*
Y1525014D01*
G01Y1529896D02*
Y1528951D01*
G01X13424Y1528754D02*
Y1530093D01*
G01Y1524817D02*
Y1526156D01*
G01Y1516943D02*
Y1518282D01*
G01Y1520880D02*
Y1522219D01*
G01Y1513006D02*
Y1514345D01*
G01D02*
Y1513006D01*
G01Y1522219D02*
Y1520880D01*
G01Y1518282D02*
Y1516943D01*
G01Y1526156D02*
Y1524817D01*
G01Y1530093D02*
Y1528754D01*
G01X12601D02*
Y1530093D01*
G01Y1524817D02*
Y1526156D01*
G01Y1516943D02*
Y1518282D01*
G01Y1520880D02*
Y1522219D01*
G01Y1513006D02*
Y1514345D01*
G01D02*
Y1513006D01*
G01Y1522219D02*
Y1520880D01*
G01Y1518282D02*
Y1516943D01*
G01Y1526156D02*
Y1524817D01*
G01Y1530093D02*
Y1528754D01*
G01X8523Y1514345D02*
Y1513006D01*
G01Y1514345D02*
Y1513006D01*
G01Y1518282D02*
Y1516943D01*
G01Y1522219D02*
Y1520880D01*
G01Y1518282D02*
Y1516943D01*
G01Y1522219D02*
Y1520880D01*
G01Y1526156D02*
Y1524817D01*
G01Y1526156D02*
Y1524817D01*
G01Y1530093D02*
Y1528754D01*
G01Y1530093D02*
Y1528754D01*
G01X0Y1531904D02*
Y1532691D01*
G01Y1530093D02*
Y1530880D01*
G01Y1527967D02*
Y1528754D01*
G01Y1522219D02*
Y1523006D01*
G01Y1526156D02*
Y1526943D01*
G01Y1524030D02*
Y1524817D01*
G01Y1518282D02*
Y1519069D01*
G01Y1520093D02*
Y1520880D01*
G01Y1514345D02*
Y1515132D01*
G01Y1516156D02*
Y1516943D01*
G01Y1512219D02*
Y1513006D01*
G01D02*
Y1512219D01*
G01Y1516943D02*
Y1516156D01*
G01Y1515132D02*
Y1514345D01*
G01Y1520880D02*
Y1520093D01*
G01Y1519069D02*
Y1518282D01*
G01Y1524817D02*
Y1524030D01*
G01Y1523006D02*
Y1522219D01*
G01Y1526943D02*
Y1526156D01*
G01Y1528754D02*
Y1527967D01*
G01Y1530880D02*
Y1530093D01*
G01Y1532691D02*
Y1531904D01*
G01X-984Y1528754D02*
Y1530093D01*
G01Y1524817D02*
Y1526156D01*
G01Y1520880D02*
Y1522219D01*
G01Y1516943D02*
Y1518282D01*
G01Y1513006D02*
Y1514345D01*
G01D02*
Y1513006D01*
G01Y1522219D02*
Y1520880D01*
G01Y1518282D02*
Y1516943D01*
G01Y1526156D02*
Y1524817D01*
G01Y1530093D02*
Y1528754D01*
G01X-2251Y1515093D02*
Y1512258D01*
G01Y1519030D02*
Y1516195D01*
G01Y1522967D02*
Y1520132D01*
G01Y1526904D02*
Y1524069D01*
G01Y1530841D02*
Y1528006D01*
G01Y1534778D02*
Y1531943D01*
G01X-2520Y1514778D02*
Y1512573D01*
G01Y1522652D02*
Y1520447D01*
G01Y1518715D02*
Y1516510D01*
G01Y1526589D02*
Y1524384D01*
G01Y1530526D02*
Y1528321D01*
G01Y1534463D02*
Y1532258D01*
G01X-1969Y1515132D02*
X-2196Y1514738D01*
G01X-1969Y1515132D02*
X-2196Y1514738D01*
G01X-1969Y1519069D02*
X-2196Y1518675D01*
G01X-1969Y1519069D02*
X-2196Y1518675D01*
G01X-1969Y1523006D02*
X-2196Y1522612D01*
G01X-1969Y1523006D02*
X-2196Y1522612D01*
G01X-1969Y1526943D02*
X-2196Y1526549D01*
G01X-1969Y1526943D02*
X-2196Y1526549D01*
G01X-1969Y1530880D02*
X-2196Y1530486D01*
G01X-1969Y1530880D02*
X-2196Y1530486D01*
G01X14580Y1552376D02*
X15464Y1552573D01*
G01X14580Y1552376D02*
X15464Y1552573D01*
G01X15078Y1552376D02*
X15962Y1552573D01*
G01D02*
X15078Y1552376D01*
G01X14580Y1548439D02*
X15464Y1548636D01*
G01X14580Y1548439D02*
X15464Y1548636D01*
G01X15078Y1548439D02*
X15962Y1548636D01*
G01D02*
X15078Y1548439D01*
G01X14580Y1544502D02*
X15464Y1544699D01*
G01X14580Y1544502D02*
X15464Y1544699D01*
G01X15078Y1544502D02*
X15962Y1544699D01*
G01D02*
X15078Y1544502D01*
G01X14580Y1540565D02*
X15464Y1540762D01*
G01X14580Y1540565D02*
X15464Y1540762D01*
G01X15078Y1540565D02*
X15962Y1540762D01*
G01D02*
X15078Y1540565D01*
G01X14580Y1536628D02*
X15464Y1536825D01*
G01X14580Y1536628D02*
X15464Y1536825D01*
G01X15078Y1536628D02*
X15962Y1536825D01*
G01D02*
X15078Y1536628D01*
G01X14580Y1532691D02*
X15464Y1532888D01*
G01X14580Y1532691D02*
X15464Y1532888D01*
G01X15078Y1532691D02*
X15962Y1532888D01*
G01D02*
X15078Y1532691D01*
G01X12601Y1553715D02*
X15078D01*
G01X-984D02*
X15078D01*
G01X8523D02*
X12601D01*
G01X0D02*
X8523D01*
G01X0D02*
X-984D01*
G01X15464Y1553518D02*
X15962D01*
G01D02*
X15464D01*
G01Y1552573D02*
X15962D01*
G01D02*
X15464D01*
G01X8523Y1552376D02*
X15078D01*
G01X-984D02*
X0D01*
G01X8523D02*
X0D01*
G01X15078D02*
X-984D01*
G01X-1969Y1551589D02*
X0D01*
G01D02*
X-1969D01*
G01Y1550565D02*
X0D01*
G01X-1969D02*
X0D01*
G01X12601Y1549778D02*
X15078D01*
G01X-984D02*
X15078D01*
G01X8523D02*
X12601D01*
G01X0D02*
X8523D01*
G01X0D02*
X-984D01*
G01X15464Y1549581D02*
X15962D01*
G01D02*
X15464D01*
G01Y1548636D02*
X15962D01*
G01D02*
X15464D01*
G01X8523Y1548439D02*
X15078D01*
G01X-984D02*
X0D01*
G01X8523D02*
X0D01*
G01X15078D02*
X-984D01*
G01X-1969Y1547652D02*
X0D01*
G01D02*
X-1969D01*
G01Y1546628D02*
X0D01*
G01X-1969D02*
X0D01*
G01X12601Y1545841D02*
X15078D01*
G01X-984D02*
X15078D01*
G01X8523D02*
X12601D01*
G01X0D02*
X8523D01*
G01X0D02*
X-984D01*
G01X15464Y1545644D02*
X15962D01*
G01D02*
X15464D01*
G01Y1544699D02*
X15962D01*
G01D02*
X15464D01*
G01X8523Y1544502D02*
X15078D01*
G01X-984D02*
X0D01*
G01X8523D02*
X0D01*
G01X15078D02*
X-984D01*
G01X-1969Y1543715D02*
X0D01*
G01D02*
X-1969D01*
G01Y1542691D02*
X0D01*
G01X-1969D02*
X0D01*
G01X12601Y1541904D02*
X15078D01*
G01X-984D02*
X15078D01*
G01X8523D02*
X12601D01*
G01X0D02*
X8523D01*
G01X0D02*
X-984D01*
G01X15464Y1541707D02*
X15962D01*
G01D02*
X15464D01*
G01Y1540762D02*
X15962D01*
G01D02*
X15464D01*
G01X8523Y1540565D02*
X15078D01*
G01X-984D02*
X0D01*
G01X8523D02*
X0D01*
G01X15078D02*
X-984D01*
G01X-1969Y1539778D02*
X0D01*
G01D02*
X-1969D01*
G01Y1538754D02*
X0D01*
G01X-1969D02*
X0D01*
G01X12601Y1537967D02*
X15078D01*
G01X-984D02*
X15078D01*
G01X8523D02*
X12601D01*
G01X0D02*
X8523D01*
G01X0D02*
X-984D01*
G01X15464Y1537770D02*
X15962D01*
G01D02*
X15464D01*
G01Y1536825D02*
X15962D01*
G01D02*
X15464D01*
G01X8523Y1536628D02*
X15078D01*
G01X-984D02*
X0D01*
G01X8523D02*
X0D01*
G01X15078D02*
X-984D01*
G01X-1969Y1535841D02*
X0D01*
G01D02*
X-1969D01*
G01Y1534817D02*
X0D01*
G01X-1969D02*
X0D01*
G01X12601Y1534030D02*
X15078D01*
G01X-984D02*
X15078D01*
G01X8523D02*
X12601D01*
G01X0D02*
X8523D01*
G01X0D02*
X-984D01*
G01X15464Y1533833D02*
X15962D01*
G01D02*
X15464D01*
G01Y1532888D02*
X15962D01*
G01D02*
X15464D01*
G01X8523Y1532691D02*
X15078D01*
G01X-984D02*
X0D01*
G01X8523D02*
X0D01*
G01X15078D02*
X-984D01*
G01X15078Y1553715D02*
X15962Y1553518D01*
G01D02*
X15078Y1553715D01*
G01X14580D02*
X15464Y1553518D01*
G01X14580Y1553715D02*
X15464Y1553518D01*
G01X15078Y1549778D02*
X15962Y1549581D01*
G01D02*
X15078Y1549778D01*
G01X14580D02*
X15464Y1549581D01*
G01X14580Y1549778D02*
X15464Y1549581D01*
G01X15078Y1545841D02*
X15962Y1545644D01*
G01D02*
X15078Y1545841D01*
G01X14580D02*
X15464Y1545644D01*
G01X14580Y1545841D02*
X15464Y1545644D01*
G01X15078Y1541904D02*
X15962Y1541707D01*
G01D02*
X15078Y1541904D01*
G01X14580D02*
X15464Y1541707D01*
G01X14580Y1541904D02*
X15464Y1541707D01*
G01X15078Y1537967D02*
X15962Y1537770D01*
G01D02*
X15078Y1537967D01*
G01X14580D02*
X15464Y1537770D01*
G01X14580Y1537967D02*
X15464Y1537770D01*
G01X15078Y1534030D02*
X15962Y1533833D01*
G01D02*
X15078Y1534030D01*
G01X14580D02*
X15464Y1533833D01*
G01X14580Y1534030D02*
X15464Y1533833D01*
G01X-2196Y1551982D02*
X-1969Y1551589D01*
G01X-2196Y1551982D02*
X-1969Y1551589D01*
G01X-2196Y1548045D02*
X-1969Y1547652D01*
G01X-2196Y1548045D02*
X-1969Y1547652D01*
G01X-2196Y1544108D02*
X-1969Y1543715D01*
G01X-2196Y1544108D02*
X-1969Y1543715D01*
G01X-2196Y1540171D02*
X-1969Y1539778D01*
G01X-2196Y1540171D02*
X-1969Y1539778D01*
G01X-2196Y1536234D02*
X-1969Y1535841D01*
G01X-2196Y1536234D02*
X-1969Y1535841D01*
G01X15962Y1552573D02*
Y1553518D01*
G01Y1548636D02*
Y1549581D01*
G01Y1544699D02*
Y1545644D01*
G01Y1540762D02*
Y1541707D01*
G01Y1536825D02*
Y1537770D01*
G01Y1532888D02*
Y1533833D01*
G01D02*
Y1532888D01*
G01Y1537770D02*
Y1536825D01*
G01Y1541707D02*
Y1540762D01*
G01Y1545644D02*
Y1544699D01*
G01Y1549581D02*
Y1548636D01*
G01Y1553518D02*
Y1552573D01*
G01X15464D02*
Y1553518D01*
G01Y1548636D02*
Y1549581D01*
G01Y1544699D02*
Y1545644D01*
G01Y1540762D02*
Y1541707D01*
G01Y1536825D02*
Y1537770D01*
G01Y1532888D02*
Y1533833D01*
G01D02*
Y1532888D01*
G01Y1537770D02*
Y1536825D01*
G01Y1545644D02*
Y1544699D01*
G01Y1541707D02*
Y1540762D01*
G01Y1549581D02*
Y1548636D01*
G01Y1553518D02*
Y1552573D01*
G01X13424Y1552376D02*
Y1553715D01*
G01Y1548439D02*
Y1549778D01*
G01Y1540565D02*
Y1541904D01*
G01Y1544502D02*
Y1545841D01*
G01Y1536628D02*
Y1537967D01*
G01Y1532691D02*
Y1534030D01*
G01D02*
Y1532691D01*
G01Y1537967D02*
Y1536628D01*
G01Y1545841D02*
Y1544502D01*
G01Y1541904D02*
Y1540565D01*
G01Y1549778D02*
Y1548439D01*
G01Y1553715D02*
Y1552376D01*
G01X12601D02*
Y1553715D01*
G01Y1548439D02*
Y1549778D01*
G01Y1544502D02*
Y1545841D01*
G01Y1540565D02*
Y1541904D01*
G01Y1536628D02*
Y1537967D01*
G01Y1532691D02*
Y1534030D01*
G01D02*
Y1532691D01*
G01Y1537967D02*
Y1536628D01*
G01Y1545841D02*
Y1544502D01*
G01Y1541904D02*
Y1540565D01*
G01Y1549778D02*
Y1548439D01*
G01Y1553715D02*
Y1552376D01*
G01X8523Y1534030D02*
Y1532691D01*
G01Y1534030D02*
Y1532691D01*
G01Y1537967D02*
Y1536628D01*
G01Y1537967D02*
Y1536628D01*
G01Y1545841D02*
Y1544502D01*
G01Y1541904D02*
Y1540565D01*
G01Y1541904D02*
Y1540565D01*
G01Y1545841D02*
Y1544502D01*
G01Y1549778D02*
Y1548439D01*
G01Y1549778D02*
Y1548439D01*
G01Y1553715D02*
Y1552376D01*
G01Y1553715D02*
Y1552376D01*
G01X0Y1553715D02*
Y1554502D01*
G01Y1551589D02*
Y1552376D01*
G01Y1549778D02*
Y1550565D01*
G01Y1545841D02*
Y1546628D01*
G01Y1547652D02*
Y1548439D01*
G01Y1541904D02*
Y1542691D01*
G01Y1543715D02*
Y1544502D01*
G01Y1537967D02*
Y1538754D01*
G01Y1539778D02*
Y1540565D01*
G01Y1534030D02*
Y1534817D01*
G01Y1535841D02*
Y1536628D01*
G01D02*
Y1535841D01*
G01Y1534817D02*
Y1534030D01*
G01Y1540565D02*
Y1539778D01*
G01Y1538754D02*
Y1537967D01*
G01Y1544502D02*
Y1543715D01*
G01Y1542691D02*
Y1541904D01*
G01Y1548439D02*
Y1547652D01*
G01Y1546628D02*
Y1545841D01*
G01Y1550565D02*
Y1549778D01*
G01Y1552376D02*
Y1551589D01*
G01Y1554502D02*
Y1553715D01*
G01X-984Y1552376D02*
Y1553715D01*
G01Y1548439D02*
Y1549778D01*
G01Y1544502D02*
Y1545841D01*
G01Y1540565D02*
Y1541904D01*
G01Y1536628D02*
Y1537967D01*
G01Y1532691D02*
Y1534030D01*
G01D02*
Y1532691D01*
G01Y1537967D02*
Y1536628D01*
G01Y1545841D02*
Y1544502D01*
G01Y1541904D02*
Y1540565D01*
G01Y1549778D02*
Y1548439D01*
G01Y1553715D02*
Y1552376D01*
G01X-2251Y1538715D02*
Y1535880D01*
G01Y1542652D02*
Y1539817D01*
G01Y1546589D02*
Y1543754D01*
G01Y1550526D02*
Y1547691D01*
G01Y1554463D02*
Y1551628D01*
G01X-2520Y1538400D02*
Y1536195D01*
G01Y1542337D02*
Y1540132D01*
G01Y1550211D02*
Y1548006D01*
G01Y1546274D02*
Y1544069D01*
G01Y1554148D02*
Y1551943D01*
G01X-1969Y1534817D02*
X-2196Y1534423D01*
G01X-1969Y1534817D02*
X-2196Y1534423D01*
G01X-1969Y1538754D02*
X-2196Y1538360D01*
G01X-1969Y1538754D02*
X-2196Y1538360D01*
G01X-1969Y1542691D02*
X-2196Y1542297D01*
G01X-1969Y1542691D02*
X-2196Y1542297D01*
G01X-1969Y1546628D02*
X-2196Y1546234D01*
G01X-1969Y1546628D02*
X-2196Y1546234D01*
G01X-1969Y1550565D02*
X-2196Y1550171D01*
G01X-1969Y1550565D02*
X-2196Y1550171D01*
G01X14580Y1572061D02*
X15464Y1572258D01*
G01X14580Y1572061D02*
X15464Y1572258D01*
G01X15078Y1572061D02*
X15962Y1572258D01*
G01D02*
X15078Y1572061D01*
G01X14580Y1568124D02*
X15464Y1568321D01*
G01X14580Y1568124D02*
X15464Y1568321D01*
G01X15078Y1568124D02*
X15962Y1568321D01*
G01D02*
X15078Y1568124D01*
G01X14580Y1564187D02*
X15464Y1564384D01*
G01X14580Y1564187D02*
X15464Y1564384D01*
G01X15078Y1564187D02*
X15962Y1564384D01*
G01D02*
X15078Y1564187D01*
G01X14580Y1560250D02*
X15464Y1560447D01*
G01X14580Y1560250D02*
X15464Y1560447D01*
G01X15078Y1560250D02*
X15962Y1560447D01*
G01D02*
X15078Y1560250D01*
G01X14580Y1556313D02*
X15464Y1556510D01*
G01X14580Y1556313D02*
X15464Y1556510D01*
G01X15078Y1556313D02*
X15962Y1556510D01*
G01D02*
X15078Y1556313D01*
G01X-1969Y1574187D02*
X0D01*
G01X-1969D02*
X0D01*
G01X12601Y1573400D02*
X15078D01*
G01X-984D02*
X15078D01*
G01X8523D02*
X12601D01*
G01X0D02*
X8523D01*
G01X0D02*
X-984D01*
G01X15464Y1573203D02*
X15962D01*
G01D02*
X15464D01*
G01Y1572258D02*
X15962D01*
G01D02*
X15464D01*
G01X8523Y1572061D02*
X15078D01*
G01X-984D02*
X0D01*
G01X8523D02*
X0D01*
G01X15078D02*
X-984D01*
G01X-1969Y1571274D02*
X0D01*
G01D02*
X-1969D01*
G01Y1570250D02*
X0D01*
G01X-1969D02*
X0D01*
G01X12601Y1569463D02*
X15078D01*
G01X-984D02*
X15078D01*
G01X8523D02*
X12601D01*
G01X0D02*
X8523D01*
G01X0D02*
X-984D01*
G01X15464Y1569266D02*
X15962D01*
G01D02*
X15464D01*
G01Y1568321D02*
X15962D01*
G01D02*
X15464D01*
G01X8523Y1568124D02*
X15078D01*
G01X-984D02*
X0D01*
G01X8523D02*
X0D01*
G01X15078D02*
X-984D01*
G01X-1969Y1567337D02*
X0D01*
G01D02*
X-1969D01*
G01Y1566313D02*
X0D01*
G01X-1969D02*
X0D01*
G01X12601Y1565526D02*
X15078D01*
G01X-984D02*
X15078D01*
G01X8523D02*
X12601D01*
G01X0D02*
X8523D01*
G01X0D02*
X-984D01*
G01X15464Y1565329D02*
X15962D01*
G01D02*
X15464D01*
G01Y1564384D02*
X15962D01*
G01D02*
X15464D01*
G01X8523Y1564187D02*
X15078D01*
G01X-984D02*
X0D01*
G01X8523D02*
X0D01*
G01X15078D02*
X-984D01*
G01X-1969Y1563400D02*
X0D01*
G01D02*
X-1969D01*
G01Y1562376D02*
X0D01*
G01X-1969D02*
X0D01*
G01X12601Y1561589D02*
X15078D01*
G01X-984D02*
X15078D01*
G01X8523D02*
X12601D01*
G01X0D02*
X8523D01*
G01X0D02*
X-984D01*
G01X15464Y1561392D02*
X15962D01*
G01D02*
X15464D01*
G01Y1560447D02*
X15962D01*
G01D02*
X15464D01*
G01X8523Y1560250D02*
X15078D01*
G01X-984D02*
X0D01*
G01X8523D02*
X0D01*
G01X15078D02*
X-984D01*
G01X-1969Y1559463D02*
X0D01*
G01D02*
X-1969D01*
G01Y1558439D02*
X0D01*
G01X-1969D02*
X0D01*
G01X12601Y1557652D02*
X15078D01*
G01X-984D02*
X15078D01*
G01X8523D02*
X12601D01*
G01X0D02*
X8523D01*
G01X0D02*
X-984D01*
G01X15464Y1557455D02*
X15962D01*
G01D02*
X15464D01*
G01Y1556510D02*
X15962D01*
G01D02*
X15464D01*
G01X8523Y1556313D02*
X15078D01*
G01X-984D02*
X0D01*
G01X8523D02*
X0D01*
G01X15078D02*
X-984D01*
G01X-1969Y1555526D02*
X0D01*
G01D02*
X-1969D01*
G01Y1554502D02*
X0D01*
G01X-1969D02*
X0D01*
G01X15078Y1573400D02*
X15962Y1573203D01*
G01D02*
X15078Y1573400D01*
G01X14580D02*
X15464Y1573203D01*
G01X14580Y1573400D02*
X15464Y1573203D01*
G01X15078Y1569463D02*
X15962Y1569266D01*
G01D02*
X15078Y1569463D01*
G01X14580D02*
X15464Y1569266D01*
G01X14580Y1569463D02*
X15464Y1569266D01*
G01X15078Y1565526D02*
X15962Y1565329D01*
G01D02*
X15078Y1565526D01*
G01X14580D02*
X15464Y1565329D01*
G01X14580Y1565526D02*
X15464Y1565329D01*
G01X15078Y1561589D02*
X15962Y1561392D01*
G01D02*
X15078Y1561589D01*
G01X14580D02*
X15464Y1561392D01*
G01X14580Y1561589D02*
X15464Y1561392D01*
G01X15078Y1557652D02*
X15962Y1557455D01*
G01D02*
X15078Y1557652D01*
G01X14580D02*
X15464Y1557455D01*
G01X14580Y1557652D02*
X15464Y1557455D01*
G01X-2196Y1571667D02*
X-1969Y1571274D01*
G01X-2196Y1571667D02*
X-1969Y1571274D01*
G01X-2196Y1567730D02*
X-1969Y1567337D01*
G01X-2196Y1567730D02*
X-1969Y1567337D01*
G01X-2196Y1563793D02*
X-1969Y1563400D01*
G01X-2196Y1563793D02*
X-1969Y1563400D01*
G01X-2196Y1559856D02*
X-1969Y1559463D01*
G01X-2196Y1559856D02*
X-1969Y1559463D01*
G01X-2196Y1555919D02*
X-1969Y1555526D01*
G01X-2196Y1555919D02*
X-1969Y1555526D01*
G01X15962Y1572258D02*
Y1573203D01*
G01Y1564384D02*
Y1565329D01*
G01Y1568321D02*
Y1569266D01*
G01Y1560447D02*
Y1561392D01*
G01Y1556510D02*
Y1557455D01*
G01D02*
Y1556510D01*
G01Y1561392D02*
Y1560447D01*
G01Y1565329D02*
Y1564384D01*
G01Y1569266D02*
Y1568321D01*
G01Y1573203D02*
Y1572258D01*
G01X15464D02*
Y1573203D01*
G01Y1568321D02*
Y1569266D01*
G01Y1564384D02*
Y1565329D01*
G01Y1560447D02*
Y1561392D01*
G01Y1556510D02*
Y1557455D01*
G01D02*
Y1556510D01*
G01Y1561392D02*
Y1560447D01*
G01Y1565329D02*
Y1564384D01*
G01Y1569266D02*
Y1568321D01*
G01Y1573203D02*
Y1572258D01*
G01X13424Y1572061D02*
Y1573400D01*
G01Y1564187D02*
Y1565526D01*
G01Y1568124D02*
Y1569463D01*
G01Y1560250D02*
Y1561589D01*
G01Y1556313D02*
Y1557652D01*
G01D02*
Y1556313D01*
G01Y1561589D02*
Y1560250D01*
G01Y1569463D02*
Y1568124D01*
G01Y1565526D02*
Y1564187D01*
G01Y1573400D02*
Y1572061D01*
G01X12601D02*
Y1573400D01*
G01Y1564187D02*
Y1565526D01*
G01Y1568124D02*
Y1569463D01*
G01Y1560250D02*
Y1561589D01*
G01Y1556313D02*
Y1557652D01*
G01D02*
Y1556313D01*
G01Y1561589D02*
Y1560250D01*
G01Y1569463D02*
Y1568124D01*
G01Y1565526D02*
Y1564187D01*
G01Y1573400D02*
Y1572061D01*
G01X8523Y1557652D02*
Y1556313D01*
G01Y1557652D02*
Y1556313D01*
G01Y1561589D02*
Y1560250D01*
G01Y1561589D02*
Y1560250D01*
G01Y1565526D02*
Y1564187D01*
G01Y1569463D02*
Y1568124D01*
G01Y1565526D02*
Y1564187D01*
G01Y1569463D02*
Y1568124D01*
G01Y1573400D02*
Y1572061D01*
G01Y1573400D02*
Y1572061D01*
G01X0Y1573400D02*
Y1574187D01*
G01Y1569463D02*
Y1570250D01*
G01Y1571274D02*
Y1572061D01*
G01Y1565526D02*
Y1566313D01*
G01Y1567337D02*
Y1568124D01*
G01Y1561589D02*
Y1562376D01*
G01Y1559463D02*
Y1560250D01*
G01Y1563400D02*
Y1564187D01*
G01Y1557652D02*
Y1558439D01*
G01Y1555526D02*
Y1556313D01*
G01D02*
Y1555526D01*
G01Y1558439D02*
Y1557652D01*
G01Y1560250D02*
Y1559463D01*
G01Y1564187D02*
Y1563400D01*
G01Y1562376D02*
Y1561589D01*
G01Y1568124D02*
Y1567337D01*
G01Y1566313D02*
Y1565526D01*
G01Y1572061D02*
Y1571274D01*
G01Y1570250D02*
Y1569463D01*
G01Y1574187D02*
Y1573400D01*
G01X-984Y1572061D02*
Y1573400D01*
G01Y1568124D02*
Y1569463D01*
G01Y1564187D02*
Y1565526D01*
G01Y1560250D02*
Y1561589D01*
G01Y1556313D02*
Y1557652D01*
G01D02*
Y1556313D01*
G01Y1561589D02*
Y1560250D01*
G01Y1569463D02*
Y1568124D01*
G01Y1565526D02*
Y1564187D01*
G01Y1573400D02*
Y1572061D01*
G01X-2251Y1558400D02*
Y1555565D01*
G01Y1562337D02*
Y1559502D01*
G01Y1566274D02*
Y1563439D01*
G01Y1570211D02*
Y1567376D01*
G01Y1574148D02*
Y1571313D01*
G01X-2520Y1558085D02*
Y1555880D01*
G01Y1562022D02*
Y1559817D01*
G01Y1565959D02*
Y1563754D01*
G01Y1573833D02*
Y1571628D01*
G01Y1569896D02*
Y1567691D01*
G01X-1969Y1554502D02*
X-2196Y1554108D01*
G01X-1969Y1554502D02*
X-2196Y1554108D01*
G01X-1969Y1558439D02*
X-2196Y1558045D01*
G01X-1969Y1558439D02*
X-2196Y1558045D01*
G01X-1969Y1562376D02*
X-2196Y1561982D01*
G01X-1969Y1562376D02*
X-2196Y1561982D01*
G01X-1969Y1566313D02*
X-2196Y1565919D01*
G01X-1969Y1566313D02*
X-2196Y1565919D01*
G01X-1969Y1570250D02*
X-2196Y1569856D01*
G01X-1969Y1570250D02*
X-2196Y1569856D01*
G01X-1969Y1574187D02*
X-2196Y1573793D01*
G01X-1969Y1574187D02*
X-2196Y1573793D01*
G01X14580Y1595683D02*
X15464Y1595880D01*
G01X14580Y1595683D02*
X15464Y1595880D01*
G01X15078Y1595683D02*
X15962Y1595880D01*
G01D02*
X15078Y1595683D01*
G01X14580Y1591746D02*
X15464Y1591943D01*
G01X14580Y1591746D02*
X15464Y1591943D01*
G01X15078Y1591746D02*
X15962Y1591943D01*
G01D02*
X15078Y1591746D01*
G01X14580Y1587809D02*
X15464Y1588006D01*
G01X14580Y1587809D02*
X15464Y1588006D01*
G01X15078Y1587809D02*
X15962Y1588006D01*
G01D02*
X15078Y1587809D01*
G01X14580Y1583872D02*
X15464Y1584069D01*
G01X14580Y1583872D02*
X15464Y1584069D01*
G01X15078Y1583872D02*
X15962Y1584069D01*
G01D02*
X15078Y1583872D01*
G01X14580Y1579935D02*
X15464Y1580132D01*
G01X14580Y1579935D02*
X15464Y1580132D01*
G01X15078Y1579935D02*
X15962Y1580132D01*
G01D02*
X15078Y1579935D01*
G01X14580Y1575998D02*
X15464Y1576195D01*
G01X14580Y1575998D02*
X15464Y1576195D01*
G01X15078Y1575998D02*
X15962Y1576195D01*
G01D02*
X15078Y1575998D01*
G01X15464Y1595880D02*
X15962D01*
G01D02*
X15464D01*
G01X8523Y1595683D02*
X15078D01*
G01X-984D02*
X0D01*
G01X8523D02*
X0D01*
G01X15078D02*
X-984D01*
G01X-1969Y1594896D02*
X0D01*
G01D02*
X-1969D01*
G01Y1593872D02*
X0D01*
G01X-1969D02*
X0D01*
G01X12601Y1593085D02*
X15078D01*
G01X-984D02*
X15078D01*
G01X8523D02*
X12601D01*
G01X0D02*
X8523D01*
G01X0D02*
X-984D01*
G01X15464Y1592888D02*
X15962D01*
G01D02*
X15464D01*
G01Y1591943D02*
X15962D01*
G01D02*
X15464D01*
G01X8523Y1591746D02*
X15078D01*
G01X-984D02*
X0D01*
G01X8523D02*
X0D01*
G01X15078D02*
X-984D01*
G01X-1969Y1590959D02*
X0D01*
G01D02*
X-1969D01*
G01Y1589935D02*
X0D01*
G01X-1969D02*
X0D01*
G01X12601Y1589148D02*
X15078D01*
G01X-984D02*
X15078D01*
G01X8523D02*
X12601D01*
G01X0D02*
X8523D01*
G01X0D02*
X-984D01*
G01X15464Y1588951D02*
X15962D01*
G01D02*
X15464D01*
G01Y1588006D02*
X15962D01*
G01D02*
X15464D01*
G01X8523Y1587809D02*
X15078D01*
G01X-984D02*
X0D01*
G01X8523D02*
X0D01*
G01X15078D02*
X-984D01*
G01X-1969Y1587022D02*
X0D01*
G01D02*
X-1969D01*
G01Y1585998D02*
X0D01*
G01X-1969D02*
X0D01*
G01X12601Y1585211D02*
X15078D01*
G01X-984D02*
X15078D01*
G01X8523D02*
X12601D01*
G01X0D02*
X8523D01*
G01X0D02*
X-984D01*
G01X15464Y1585014D02*
X15962D01*
G01D02*
X15464D01*
G01Y1584069D02*
X15962D01*
G01D02*
X15464D01*
G01X8523Y1583872D02*
X15078D01*
G01X-984D02*
X0D01*
G01X8523D02*
X0D01*
G01X15078D02*
X-984D01*
G01X-1969Y1583085D02*
X0D01*
G01D02*
X-1969D01*
G01Y1582061D02*
X0D01*
G01X-1969D02*
X0D01*
G01X12601Y1581274D02*
X15078D01*
G01X-984D02*
X15078D01*
G01X8523D02*
X12601D01*
G01X0D02*
X8523D01*
G01X0D02*
X-984D01*
G01X15464Y1581077D02*
X15962D01*
G01D02*
X15464D01*
G01Y1580132D02*
X15962D01*
G01D02*
X15464D01*
G01X8523Y1579935D02*
X15078D01*
G01X-984D02*
X0D01*
G01X8523D02*
X0D01*
G01X15078D02*
X-984D01*
G01X-1969Y1579148D02*
X0D01*
G01D02*
X-1969D01*
G01Y1578124D02*
X0D01*
G01X-1969D02*
X0D01*
G01X12601Y1577337D02*
X15078D01*
G01X-984D02*
X15078D01*
G01X8523D02*
X12601D01*
G01X0D02*
X8523D01*
G01X0D02*
X-984D01*
G01X15464Y1577140D02*
X15962D01*
G01D02*
X15464D01*
G01Y1576195D02*
X15962D01*
G01D02*
X15464D01*
G01X8523Y1575998D02*
X15078D01*
G01X-984D02*
X0D01*
G01X8523D02*
X0D01*
G01X15078D02*
X-984D01*
G01X-1969Y1575211D02*
X0D01*
G01D02*
X-1969D01*
G01X15078Y1593085D02*
X15962Y1592888D01*
G01D02*
X15078Y1593085D01*
G01X14580D02*
X15464Y1592888D01*
G01X14580Y1593085D02*
X15464Y1592888D01*
G01X15078Y1589148D02*
X15962Y1588951D01*
G01D02*
X15078Y1589148D01*
G01X14580D02*
X15464Y1588951D01*
G01X14580Y1589148D02*
X15464Y1588951D01*
G01X15078Y1585211D02*
X15962Y1585014D01*
G01D02*
X15078Y1585211D01*
G01X14580D02*
X15464Y1585014D01*
G01X14580Y1585211D02*
X15464Y1585014D01*
G01X15078Y1581274D02*
X15962Y1581077D01*
G01D02*
X15078Y1581274D01*
G01X14580D02*
X15464Y1581077D01*
G01X14580Y1581274D02*
X15464Y1581077D01*
G01X15078Y1577337D02*
X15962Y1577140D01*
G01D02*
X15078Y1577337D01*
G01X14580D02*
X15464Y1577140D01*
G01X14580Y1577337D02*
X15464Y1577140D01*
G01X-2196Y1595290D02*
X-1969Y1594896D01*
G01X-2196Y1595290D02*
X-1969Y1594896D01*
G01X-2196Y1591353D02*
X-1969Y1590959D01*
G01X-2196Y1591353D02*
X-1969Y1590959D01*
G01X-2196Y1587416D02*
X-1969Y1587022D01*
G01X-2196Y1587416D02*
X-1969Y1587022D01*
G01X-2196Y1583478D02*
X-1969Y1583085D01*
G01X-2196Y1583478D02*
X-1969Y1583085D01*
G01X-2196Y1579541D02*
X-1969Y1579148D01*
G01X-2196Y1579541D02*
X-1969Y1579148D01*
G01X-2196Y1575604D02*
X-1969Y1575211D01*
G01X-2196Y1575604D02*
X-1969Y1575211D01*
G01X15962Y1595880D02*
Y1596825D01*
G01Y1591943D02*
Y1592888D01*
G01Y1588006D02*
Y1588951D01*
G01Y1584069D02*
Y1585014D01*
G01Y1580132D02*
Y1581077D01*
G01Y1576195D02*
Y1577140D01*
G01D02*
Y1576195D01*
G01Y1581077D02*
Y1580132D01*
G01Y1585014D02*
Y1584069D01*
G01Y1588951D02*
Y1588006D01*
G01Y1592888D02*
Y1591943D01*
G01Y1596825D02*
Y1595880D01*
G01X15464D02*
Y1596825D01*
G01Y1591943D02*
Y1592888D01*
G01Y1588006D02*
Y1588951D01*
G01Y1584069D02*
Y1585014D01*
G01Y1580132D02*
Y1581077D01*
G01Y1576195D02*
Y1577140D01*
G01D02*
Y1576195D01*
G01Y1581077D02*
Y1580132D01*
G01Y1585014D02*
Y1584069D01*
G01Y1592888D02*
Y1591943D01*
G01Y1588951D02*
Y1588006D01*
G01Y1596825D02*
Y1595880D01*
G01X13424Y1595683D02*
Y1597022D01*
G01Y1591746D02*
Y1593085D01*
G01Y1587809D02*
Y1589148D01*
G01Y1583872D02*
Y1585211D01*
G01Y1579935D02*
Y1581274D01*
G01Y1575998D02*
Y1577337D01*
G01D02*
Y1575998D01*
G01Y1581274D02*
Y1579935D01*
G01Y1585211D02*
Y1583872D01*
G01Y1589148D02*
Y1587809D01*
G01Y1597022D02*
Y1595683D01*
G01Y1593085D02*
Y1591746D01*
G01X12601Y1595683D02*
Y1597022D01*
G01Y1591746D02*
Y1593085D01*
G01Y1587809D02*
Y1589148D01*
G01Y1583872D02*
Y1585211D01*
G01Y1579935D02*
Y1581274D01*
G01Y1575998D02*
Y1577337D01*
G01D02*
Y1575998D01*
G01Y1581274D02*
Y1579935D01*
G01Y1585211D02*
Y1583872D01*
G01Y1589148D02*
Y1587809D01*
G01Y1597022D02*
Y1595683D01*
G01Y1593085D02*
Y1591746D01*
G01X8523Y1577337D02*
Y1575998D01*
G01Y1577337D02*
Y1575998D01*
G01Y1581274D02*
Y1579935D01*
G01Y1581274D02*
Y1579935D01*
G01Y1585211D02*
Y1583872D01*
G01Y1585211D02*
Y1583872D01*
G01Y1589148D02*
Y1587809D01*
G01Y1589148D02*
Y1587809D01*
G01Y1597022D02*
Y1595683D01*
G01Y1593085D02*
Y1591746D01*
G01Y1597022D02*
Y1595683D01*
G01Y1593085D02*
Y1591746D01*
G01X0Y1593085D02*
Y1593872D01*
G01Y1594896D02*
Y1595683D01*
G01Y1589148D02*
Y1589935D01*
G01Y1590959D02*
Y1591746D01*
G01Y1585211D02*
Y1585998D01*
G01Y1583085D02*
Y1583872D01*
G01Y1587022D02*
Y1587809D01*
G01Y1581274D02*
Y1582061D01*
G01Y1579148D02*
Y1579935D01*
G01Y1577337D02*
Y1578124D01*
G01Y1575211D02*
Y1575998D01*
G01D02*
Y1575211D01*
G01Y1578124D02*
Y1577337D01*
G01Y1579935D02*
Y1579148D01*
G01Y1582061D02*
Y1581274D01*
G01Y1587809D02*
Y1587022D01*
G01Y1583872D02*
Y1583085D01*
G01Y1585998D02*
Y1585211D01*
G01Y1591746D02*
Y1590959D01*
G01Y1589935D02*
Y1589148D01*
G01Y1595683D02*
Y1594896D01*
G01Y1593872D02*
Y1593085D01*
G01X-984Y1595683D02*
Y1597022D01*
G01Y1591746D02*
Y1593085D01*
G01Y1587809D02*
Y1589148D01*
G01Y1583872D02*
Y1585211D01*
G01Y1579935D02*
Y1581274D01*
G01Y1575998D02*
Y1577337D01*
G01D02*
Y1575998D01*
G01Y1581274D02*
Y1579935D01*
G01Y1585211D02*
Y1583872D01*
G01Y1589148D02*
Y1587809D01*
G01Y1597022D02*
Y1595683D01*
G01Y1593085D02*
Y1591746D01*
G01X-2251Y1578085D02*
Y1575250D01*
G01Y1582022D02*
Y1579187D01*
G01Y1585959D02*
Y1583124D01*
G01Y1589896D02*
Y1587061D01*
G01Y1593833D02*
Y1590998D01*
G01Y1597770D02*
Y1594935D01*
G01X-2520Y1577770D02*
Y1575565D01*
G01Y1581707D02*
Y1579502D01*
G01Y1585644D02*
Y1583439D01*
G01Y1589581D02*
Y1587376D01*
G01Y1597455D02*
Y1595250D01*
G01Y1593518D02*
Y1591313D01*
G01X-1969Y1578124D02*
X-2196Y1577730D01*
G01X-1969Y1578124D02*
X-2196Y1577730D01*
G01X-1969Y1582061D02*
X-2196Y1581667D01*
G01X-1969Y1582061D02*
X-2196Y1581667D01*
G01X-1969Y1585998D02*
X-2196Y1585604D01*
G01X-1969Y1585998D02*
X-2196Y1585604D01*
G01X-1969Y1589935D02*
X-2196Y1589541D01*
G01X-1969Y1589935D02*
X-2196Y1589541D01*
G01X-1969Y1593872D02*
X-2196Y1593478D01*
G01X-1969Y1593872D02*
X-2196Y1593478D01*
G01X14580Y1615368D02*
X15464Y1615565D01*
G01X14580Y1615368D02*
X15464Y1615565D01*
G01X15078Y1615368D02*
X15962Y1615565D01*
G01D02*
X15078Y1615368D01*
G01X14580Y1611431D02*
X15464Y1611628D01*
G01X14580Y1611431D02*
X15464Y1611628D01*
G01X15078Y1611431D02*
X15962Y1611628D01*
G01D02*
X15078Y1611431D01*
G01X14580Y1607494D02*
X15464Y1607691D01*
G01X14580Y1607494D02*
X15464Y1607691D01*
G01X15078Y1607494D02*
X15962Y1607691D01*
G01D02*
X15078Y1607494D01*
G01X14580Y1603557D02*
X15464Y1603754D01*
G01X14580Y1603557D02*
X15464Y1603754D01*
G01X15078Y1603557D02*
X15962Y1603754D01*
G01D02*
X15078Y1603557D01*
G01X14580Y1599620D02*
X15464Y1599817D01*
G01X14580Y1599620D02*
X15464Y1599817D01*
G01X15078Y1599620D02*
X15962Y1599817D01*
G01D02*
X15078Y1599620D01*
G01X12601Y1616707D02*
X15078D01*
G01X-984D02*
X15078D01*
G01X8523D02*
X12601D01*
G01X0D02*
X8523D01*
G01X0D02*
X-984D01*
G01X15464Y1616510D02*
X15962D01*
G01D02*
X15464D01*
G01Y1615565D02*
X15962D01*
G01D02*
X15464D01*
G01X8523Y1615368D02*
X15078D01*
G01X-984D02*
X0D01*
G01X8523D02*
X0D01*
G01X15078D02*
X-984D01*
G01X-1969Y1614581D02*
X0D01*
G01D02*
X-1969D01*
G01Y1613557D02*
X0D01*
G01X-1969D02*
X0D01*
G01X12601Y1612770D02*
X15078D01*
G01X-984D02*
X15078D01*
G01X8523D02*
X12601D01*
G01X0D02*
X8523D01*
G01X0D02*
X-984D01*
G01X15464Y1612573D02*
X15962D01*
G01D02*
X15464D01*
G01Y1611628D02*
X15962D01*
G01D02*
X15464D01*
G01X8523Y1611431D02*
X15078D01*
G01X-984D02*
X0D01*
G01X8523D02*
X0D01*
G01X15078D02*
X-984D01*
G01X-1969Y1610644D02*
X0D01*
G01D02*
X-1969D01*
G01Y1609620D02*
X0D01*
G01X-1969D02*
X0D01*
G01X12601Y1608833D02*
X15078D01*
G01X-984D02*
X15078D01*
G01X8523D02*
X12601D01*
G01X0D02*
X8523D01*
G01X0D02*
X-984D01*
G01X15464Y1608636D02*
X15962D01*
G01D02*
X15464D01*
G01Y1607691D02*
X15962D01*
G01D02*
X15464D01*
G01X8523Y1607494D02*
X15078D01*
G01X-984D02*
X0D01*
G01X8523D02*
X0D01*
G01X15078D02*
X-984D01*
G01X-1969Y1606707D02*
X0D01*
G01D02*
X-1969D01*
G01Y1605683D02*
X0D01*
G01X-1969D02*
X0D01*
G01X12601Y1604896D02*
X15078D01*
G01X-984D02*
X15078D01*
G01X8523D02*
X12601D01*
G01X0D02*
X8523D01*
G01X0D02*
X-984D01*
G01X15464Y1604699D02*
X15962D01*
G01D02*
X15464D01*
G01Y1603754D02*
X15962D01*
G01D02*
X15464D01*
G01X8523Y1603557D02*
X15078D01*
G01X-984D02*
X0D01*
G01X8523D02*
X0D01*
G01X15078D02*
X-984D01*
G01X-1969Y1602770D02*
X0D01*
G01D02*
X-1969D01*
G01Y1601746D02*
X0D01*
G01X-1969D02*
X0D01*
G01X12601Y1600959D02*
X15078D01*
G01X-984D02*
X15078D01*
G01X8523D02*
X12601D01*
G01X0D02*
X8523D01*
G01X0D02*
X-984D01*
G01X15464Y1600762D02*
X15962D01*
G01D02*
X15464D01*
G01Y1599817D02*
X15962D01*
G01D02*
X15464D01*
G01X8523Y1599620D02*
X15078D01*
G01X-984D02*
X0D01*
G01X8523D02*
X0D01*
G01X15078D02*
X-984D01*
G01X-1969Y1598833D02*
X0D01*
G01D02*
X-1969D01*
G01Y1597809D02*
X0D01*
G01X-1969D02*
X0D01*
G01X12601Y1597022D02*
X15078D01*
G01X-984D02*
X15078D01*
G01X8523D02*
X12601D01*
G01X0D02*
X8523D01*
G01X0D02*
X-984D01*
G01X15464Y1596825D02*
X15962D01*
G01D02*
X15464D01*
G01X15078Y1616707D02*
X15962Y1616510D01*
G01D02*
X15078Y1616707D01*
G01X14580D02*
X15464Y1616510D01*
G01X14580Y1616707D02*
X15464Y1616510D01*
G01X15078Y1612770D02*
X15962Y1612573D01*
G01D02*
X15078Y1612770D01*
G01X14580D02*
X15464Y1612573D01*
G01X14580Y1612770D02*
X15464Y1612573D01*
G01X15078Y1608833D02*
X15962Y1608636D01*
G01D02*
X15078Y1608833D01*
G01X14580D02*
X15464Y1608636D01*
G01X14580Y1608833D02*
X15464Y1608636D01*
G01X15078Y1604896D02*
X15962Y1604699D01*
G01D02*
X15078Y1604896D01*
G01X14580D02*
X15464Y1604699D01*
G01X14580Y1604896D02*
X15464Y1604699D01*
G01X15078Y1600959D02*
X15962Y1600762D01*
G01D02*
X15078Y1600959D01*
G01X14580D02*
X15464Y1600762D01*
G01X14580Y1600959D02*
X15464Y1600762D01*
G01X15078Y1597022D02*
X15962Y1596825D01*
G01D02*
X15078Y1597022D01*
G01X14580D02*
X15464Y1596825D01*
G01X14580Y1597022D02*
X15464Y1596825D01*
G01X-2196Y1614975D02*
X-1969Y1614581D01*
G01X-2196Y1614975D02*
X-1969Y1614581D01*
G01X-2196Y1611038D02*
X-1969Y1610644D01*
G01X-2196Y1611038D02*
X-1969Y1610644D01*
G01X-2196Y1607101D02*
X-1969Y1606707D01*
G01X-2196Y1607101D02*
X-1969Y1606707D01*
G01X-2196Y1603164D02*
X-1969Y1602770D01*
G01X-2196Y1603164D02*
X-1969Y1602770D01*
G01X-2196Y1599227D02*
X-1969Y1598833D01*
G01X-2196Y1599227D02*
X-1969Y1598833D01*
G01X15962Y1615565D02*
Y1616510D01*
G01Y1611628D02*
Y1612573D01*
G01Y1607691D02*
Y1608636D01*
G01Y1603754D02*
Y1604699D01*
G01Y1599817D02*
Y1600762D01*
G01D02*
Y1599817D01*
G01Y1604699D02*
Y1603754D01*
G01Y1608636D02*
Y1607691D01*
G01Y1612573D02*
Y1611628D01*
G01Y1616510D02*
Y1615565D01*
G01X15464D02*
Y1616510D01*
G01Y1611628D02*
Y1612573D01*
G01Y1607691D02*
Y1608636D01*
G01Y1603754D02*
Y1604699D01*
G01Y1599817D02*
Y1600762D01*
G01D02*
Y1599817D01*
G01Y1604699D02*
Y1603754D01*
G01Y1608636D02*
Y1607691D01*
G01Y1612573D02*
Y1611628D01*
G01Y1616510D02*
Y1615565D01*
G01X13424Y1615368D02*
Y1616707D01*
G01Y1611431D02*
Y1612770D01*
G01Y1607494D02*
Y1608833D01*
G01Y1603557D02*
Y1604896D01*
G01Y1599620D02*
Y1600959D01*
G01D02*
Y1599620D01*
G01Y1604896D02*
Y1603557D01*
G01Y1608833D02*
Y1607494D01*
G01Y1612770D02*
Y1611431D01*
G01Y1616707D02*
Y1615368D01*
G01X12601D02*
Y1616707D01*
G01Y1611431D02*
Y1612770D01*
G01Y1607494D02*
Y1608833D01*
G01Y1603557D02*
Y1604896D01*
G01Y1599620D02*
Y1600959D01*
G01D02*
Y1599620D01*
G01Y1604896D02*
Y1603557D01*
G01Y1608833D02*
Y1607494D01*
G01Y1612770D02*
Y1611431D01*
G01Y1616707D02*
Y1615368D01*
G01X8523Y1600959D02*
Y1599620D01*
G01Y1600959D02*
Y1599620D01*
G01Y1604896D02*
Y1603557D01*
G01Y1604896D02*
Y1603557D01*
G01Y1608833D02*
Y1607494D01*
G01Y1608833D02*
Y1607494D01*
G01Y1612770D02*
Y1611431D01*
G01Y1612770D02*
Y1611431D01*
G01Y1616707D02*
Y1615368D01*
G01Y1616707D02*
Y1615368D01*
G01X0Y1616707D02*
Y1617494D01*
G01Y1612770D02*
Y1613557D01*
G01Y1614581D02*
Y1615368D01*
G01Y1608833D02*
Y1609620D01*
G01Y1606707D02*
Y1607494D01*
G01Y1610644D02*
Y1611431D01*
G01Y1604896D02*
Y1605683D01*
G01Y1602770D02*
Y1603557D01*
G01Y1600959D02*
Y1601746D01*
G01Y1597022D02*
Y1597809D01*
G01Y1598833D02*
Y1599620D01*
G01D02*
Y1598833D01*
G01Y1597809D02*
Y1597022D01*
G01Y1601746D02*
Y1600959D01*
G01Y1603557D02*
Y1602770D01*
G01Y1605683D02*
Y1604896D01*
G01Y1611431D02*
Y1610644D01*
G01Y1607494D02*
Y1606707D01*
G01Y1609620D02*
Y1608833D01*
G01Y1615368D02*
Y1614581D01*
G01Y1613557D02*
Y1612770D01*
G01Y1617494D02*
Y1616707D01*
G01X-984Y1615368D02*
Y1616707D01*
G01Y1611431D02*
Y1612770D01*
G01Y1607494D02*
Y1608833D01*
G01Y1603557D02*
Y1604896D01*
G01Y1599620D02*
Y1600959D01*
G01D02*
Y1599620D01*
G01Y1604896D02*
Y1603557D01*
G01Y1608833D02*
Y1607494D01*
G01Y1612770D02*
Y1611431D01*
G01Y1616707D02*
Y1615368D01*
G01X-2251Y1601707D02*
Y1598872D01*
G01Y1605644D02*
Y1602809D01*
G01Y1609581D02*
Y1606746D01*
G01Y1613518D02*
Y1610683D01*
G01Y1617455D02*
Y1614620D01*
G01X-2520Y1601392D02*
Y1599187D01*
G01Y1605329D02*
Y1603124D01*
G01Y1609266D02*
Y1607061D01*
G01Y1613203D02*
Y1610998D01*
G01Y1617140D02*
Y1614935D01*
G01X-1969Y1597809D02*
X-2196Y1597416D01*
G01X-1969Y1597809D02*
X-2196Y1597416D01*
G01X-1969Y1601746D02*
X-2196Y1601353D01*
G01X-1969Y1601746D02*
X-2196Y1601353D01*
G01X-1969Y1605683D02*
X-2196Y1605290D01*
G01X-1969Y1605683D02*
X-2196Y1605290D01*
G01X-1969Y1609620D02*
X-2196Y1609227D01*
G01X-1969Y1609620D02*
X-2196Y1609227D01*
G01X-1969Y1613557D02*
X-2196Y1613164D01*
G01X-1969Y1613557D02*
X-2196Y1613164D01*
G01X-1969Y1617494D02*
X-2196Y1617101D01*
G01X-1969Y1617494D02*
X-2196Y1617101D01*
G01X14580Y1635053D02*
X15464Y1635250D01*
G01X14580Y1635053D02*
X15464Y1635250D01*
G01X15078Y1635053D02*
X15962Y1635250D01*
G01D02*
X15078Y1635053D01*
G01X14580Y1631116D02*
X15464Y1631313D01*
G01X14580Y1631116D02*
X15464Y1631313D01*
G01X15078Y1631116D02*
X15962Y1631313D01*
G01D02*
X15078Y1631116D01*
G01X14580Y1627179D02*
X15464Y1627376D01*
G01X14580Y1627179D02*
X15464Y1627376D01*
G01X15078Y1627179D02*
X15962Y1627376D01*
G01D02*
X15078Y1627179D01*
G01X14580Y1623242D02*
X15464Y1623439D01*
G01X14580Y1623242D02*
X15464Y1623439D01*
G01X15078Y1623242D02*
X15962Y1623439D01*
G01D02*
X15078Y1623242D01*
G01X14580Y1619305D02*
X15464Y1619502D01*
G01X14580Y1619305D02*
X15464Y1619502D01*
G01X15078Y1619305D02*
X15962Y1619502D01*
G01D02*
X15078Y1619305D01*
G01X-1969Y1638203D02*
X0D01*
G01D02*
X-1969D01*
G01Y1637179D02*
X0D01*
G01X-1969D02*
X0D01*
G01X12601Y1636392D02*
X15078D01*
G01X-984D02*
X15078D01*
G01X8523D02*
X12601D01*
G01X0D02*
X8523D01*
G01X0D02*
X-984D01*
G01X15464Y1636195D02*
X15962D01*
G01D02*
X15464D01*
G01Y1635250D02*
X15962D01*
G01D02*
X15464D01*
G01X8523Y1635053D02*
X15078D01*
G01X-984D02*
X0D01*
G01X8523D02*
X0D01*
G01X15078D02*
X-984D01*
G01X-1969Y1634266D02*
X0D01*
G01D02*
X-1969D01*
G01Y1633242D02*
X0D01*
G01X-1969D02*
X0D01*
G01X12601Y1632455D02*
X15078D01*
G01X-984D02*
X15078D01*
G01X8523D02*
X12601D01*
G01X0D02*
X8523D01*
G01X0D02*
X-984D01*
G01X15464Y1632258D02*
X15962D01*
G01D02*
X15464D01*
G01Y1631313D02*
X15962D01*
G01D02*
X15464D01*
G01X8523Y1631116D02*
X15078D01*
G01X-984D02*
X0D01*
G01X8523D02*
X0D01*
G01X15078D02*
X-984D01*
G01X-1969Y1630329D02*
X0D01*
G01D02*
X-1969D01*
G01Y1629305D02*
X0D01*
G01X-1969D02*
X0D01*
G01X12601Y1628518D02*
X15078D01*
G01X-984D02*
X15078D01*
G01X8523D02*
X12601D01*
G01X0D02*
X8523D01*
G01X0D02*
X-984D01*
G01X15464Y1628321D02*
X15962D01*
G01D02*
X15464D01*
G01Y1627376D02*
X15962D01*
G01D02*
X15464D01*
G01X8523Y1627179D02*
X15078D01*
G01X-984D02*
X0D01*
G01X8523D02*
X0D01*
G01X15078D02*
X-984D01*
G01X-1969Y1626392D02*
X0D01*
G01D02*
X-1969D01*
G01Y1625368D02*
X0D01*
G01X-1969D02*
X0D01*
G01X12601Y1624581D02*
X15078D01*
G01X-984D02*
X15078D01*
G01X8523D02*
X12601D01*
G01X0D02*
X8523D01*
G01X0D02*
X-984D01*
G01X15464Y1624384D02*
X15962D01*
G01D02*
X15464D01*
G01Y1623439D02*
X15962D01*
G01D02*
X15464D01*
G01X8523Y1623242D02*
X15078D01*
G01X-984D02*
X0D01*
G01X8523D02*
X0D01*
G01X15078D02*
X-984D01*
G01X-1969Y1622455D02*
X0D01*
G01D02*
X-1969D01*
G01Y1621431D02*
X0D01*
G01X-1969D02*
X0D01*
G01X12601Y1620644D02*
X15078D01*
G01X-984D02*
X15078D01*
G01X8523D02*
X12601D01*
G01X0D02*
X8523D01*
G01X0D02*
X-984D01*
G01X15464Y1620447D02*
X15962D01*
G01D02*
X15464D01*
G01Y1619502D02*
X15962D01*
G01D02*
X15464D01*
G01X8523Y1619305D02*
X15078D01*
G01X-984D02*
X0D01*
G01X8523D02*
X0D01*
G01X15078D02*
X-984D01*
G01X-1969Y1618518D02*
X0D01*
G01D02*
X-1969D01*
G01Y1617494D02*
X0D01*
G01X-1969D02*
X0D01*
G01X15078Y1636392D02*
X15962Y1636195D01*
G01D02*
X15078Y1636392D01*
G01X14580D02*
X15464Y1636195D01*
G01X14580Y1636392D02*
X15464Y1636195D01*
G01X15078Y1632455D02*
X15962Y1632258D01*
G01D02*
X15078Y1632455D01*
G01X14580D02*
X15464Y1632258D01*
G01X14580Y1632455D02*
X15464Y1632258D01*
G01X15078Y1628518D02*
X15962Y1628321D01*
G01D02*
X15078Y1628518D01*
G01X14580D02*
X15464Y1628321D01*
G01X14580Y1628518D02*
X15464Y1628321D01*
G01X15078Y1624581D02*
X15962Y1624384D01*
G01D02*
X15078Y1624581D01*
G01X14580D02*
X15464Y1624384D01*
G01X14580Y1624581D02*
X15464Y1624384D01*
G01X15078Y1620644D02*
X15962Y1620447D01*
G01D02*
X15078Y1620644D01*
G01X14580D02*
X15464Y1620447D01*
G01X14580Y1620644D02*
X15464Y1620447D01*
G01X-2196Y1638597D02*
X-1969Y1638203D01*
G01X-2196Y1638597D02*
X-1969Y1638203D01*
G01X-2196Y1634660D02*
X-1969Y1634266D01*
G01X-2196Y1634660D02*
X-1969Y1634266D01*
G01X-2196Y1630723D02*
X-1969Y1630329D01*
G01X-2196Y1630723D02*
X-1969Y1630329D01*
G01X-2196Y1626786D02*
X-1969Y1626392D01*
G01X-2196Y1626786D02*
X-1969Y1626392D01*
G01X-2196Y1622849D02*
X-1969Y1622455D01*
G01X-2196Y1622849D02*
X-1969Y1622455D01*
G01X-2196Y1618912D02*
X-1969Y1618518D01*
G01X-2196Y1618912D02*
X-1969Y1618518D01*
G01X15962Y1635250D02*
Y1636195D01*
G01Y1631313D02*
Y1632258D01*
G01Y1627376D02*
Y1628321D01*
G01Y1623439D02*
Y1624384D01*
G01Y1619502D02*
Y1620447D01*
G01D02*
Y1619502D01*
G01Y1624384D02*
Y1623439D01*
G01Y1628321D02*
Y1627376D01*
G01Y1632258D02*
Y1631313D01*
G01Y1636195D02*
Y1635250D01*
G01X15464D02*
Y1636195D01*
G01Y1631313D02*
Y1632258D01*
G01Y1627376D02*
Y1628321D01*
G01Y1623439D02*
Y1624384D01*
G01Y1619502D02*
Y1620447D01*
G01D02*
Y1619502D01*
G01Y1624384D02*
Y1623439D01*
G01Y1628321D02*
Y1627376D01*
G01Y1632258D02*
Y1631313D01*
G01Y1636195D02*
Y1635250D01*
G01X13424Y1635053D02*
Y1636392D01*
G01Y1631116D02*
Y1632455D01*
G01Y1627179D02*
Y1628518D01*
G01Y1623242D02*
Y1624581D01*
G01Y1619305D02*
Y1620644D01*
G01D02*
Y1619305D01*
G01Y1624581D02*
Y1623242D01*
G01Y1628518D02*
Y1627179D01*
G01Y1632455D02*
Y1631116D01*
G01Y1636392D02*
Y1635053D01*
G01X12601D02*
Y1636392D01*
G01Y1631116D02*
Y1632455D01*
G01Y1627179D02*
Y1628518D01*
G01Y1623242D02*
Y1624581D01*
G01Y1619305D02*
Y1620644D01*
G01D02*
Y1619305D01*
G01Y1624581D02*
Y1623242D01*
G01Y1628518D02*
Y1627179D01*
G01Y1632455D02*
Y1631116D01*
G01Y1636392D02*
Y1635053D01*
G01X8523Y1620644D02*
Y1619305D01*
G01Y1620644D02*
Y1619305D01*
G01Y1624581D02*
Y1623242D01*
G01Y1624581D02*
Y1623242D01*
G01Y1628518D02*
Y1627179D01*
G01Y1628518D02*
Y1627179D01*
G01Y1632455D02*
Y1631116D01*
G01Y1632455D02*
Y1631116D01*
G01Y1636392D02*
Y1635053D01*
G01Y1636392D02*
Y1635053D01*
G01X0Y1636392D02*
Y1637179D01*
G01Y1638203D02*
Y1638990D01*
G01Y1632455D02*
Y1633242D01*
G01Y1630329D02*
Y1631116D01*
G01Y1634266D02*
Y1635053D01*
G01Y1628518D02*
Y1629305D01*
G01Y1626392D02*
Y1627179D01*
G01Y1624581D02*
Y1625368D01*
G01Y1620644D02*
Y1621431D01*
G01Y1622455D02*
Y1623242D01*
G01Y1618518D02*
Y1619305D01*
G01D02*
Y1618518D01*
G01Y1623242D02*
Y1622455D01*
G01Y1621431D02*
Y1620644D01*
G01Y1625368D02*
Y1624581D01*
G01Y1627179D02*
Y1626392D01*
G01Y1629305D02*
Y1628518D01*
G01Y1635053D02*
Y1634266D01*
G01Y1631116D02*
Y1630329D01*
G01Y1633242D02*
Y1632455D01*
G01Y1638990D02*
Y1638203D01*
G01Y1637179D02*
Y1636392D01*
G01X-984Y1635053D02*
Y1636392D01*
G01Y1631116D02*
Y1632455D01*
G01Y1627179D02*
Y1628518D01*
G01Y1623242D02*
Y1624581D01*
G01Y1619305D02*
Y1620644D01*
G01D02*
Y1619305D01*
G01Y1624581D02*
Y1623242D01*
G01Y1628518D02*
Y1627179D01*
G01Y1632455D02*
Y1631116D01*
G01Y1636392D02*
Y1635053D01*
G01X-2251Y1621392D02*
Y1618557D01*
G01Y1625329D02*
Y1622494D01*
G01Y1629266D02*
Y1626431D01*
G01Y1633203D02*
Y1630368D01*
G01Y1637140D02*
Y1634305D01*
G01Y1641077D02*
Y1638242D01*
G01X-2520Y1625014D02*
Y1622809D01*
G01Y1621077D02*
Y1618872D01*
G01Y1628951D02*
Y1626746D01*
G01Y1632888D02*
Y1630683D01*
G01Y1636825D02*
Y1634620D01*
G01X-1969Y1621431D02*
X-2196Y1621038D01*
G01X-1969Y1621431D02*
X-2196Y1621038D01*
G01X-1969Y1625368D02*
X-2196Y1624975D01*
G01X-1969Y1625368D02*
X-2196Y1624975D01*
G01X-1969Y1629305D02*
X-2196Y1628912D01*
G01X-1969Y1629305D02*
X-2196Y1628912D01*
G01X-1969Y1633242D02*
X-2196Y1632849D01*
G01X-1969Y1633242D02*
X-2196Y1632849D01*
G01X-1969Y1637179D02*
X-2196Y1636786D01*
G01X-1969Y1637179D02*
X-2196Y1636786D01*
G01X14580Y1658675D02*
X15464Y1658872D01*
G01X14580Y1658675D02*
X15464Y1658872D01*
G01X15078Y1658675D02*
X15962Y1658872D01*
G01D02*
X15078Y1658675D01*
G01X14580Y1654738D02*
X15464Y1654935D01*
G01X14580Y1654738D02*
X15464Y1654935D01*
G01X15078Y1654738D02*
X15962Y1654935D01*
G01D02*
X15078Y1654738D01*
G01X14580Y1650801D02*
X15464Y1650998D01*
G01X14580Y1650801D02*
X15464Y1650998D01*
G01X15078Y1650801D02*
X15962Y1650998D01*
G01D02*
X15078Y1650801D01*
G01X14580Y1646864D02*
X15464Y1647061D01*
G01X14580Y1646864D02*
X15464Y1647061D01*
G01X15078Y1646864D02*
X15962Y1647061D01*
G01D02*
X15078Y1646864D01*
G01X14580Y1642927D02*
X15464Y1643124D01*
G01X14580Y1642927D02*
X15464Y1643124D01*
G01X15078Y1642927D02*
X15962Y1643124D01*
G01D02*
X15078Y1642927D01*
G01X14580Y1638990D02*
X15464Y1639187D01*
G01X14580Y1638990D02*
X15464Y1639187D01*
G01X15078Y1638990D02*
X15962Y1639187D01*
G01D02*
X15078Y1638990D01*
G01X15464Y1658872D02*
X15962D01*
G01D02*
X15464D01*
G01X8523Y1658675D02*
X15078D01*
G01X-984D02*
X0D01*
G01X8523D02*
X0D01*
G01X15078D02*
X-984D01*
G01X-1969Y1657888D02*
X0D01*
G01D02*
X-1969D01*
G01Y1656864D02*
X0D01*
G01X-1969D02*
X0D01*
G01X12601Y1656077D02*
X15078D01*
G01X-984D02*
X15078D01*
G01X8523D02*
X12601D01*
G01X0D02*
X8523D01*
G01X0D02*
X-984D01*
G01X15464Y1655880D02*
X15962D01*
G01D02*
X15464D01*
G01Y1654935D02*
X15962D01*
G01D02*
X15464D01*
G01X8523Y1654738D02*
X15078D01*
G01X-984D02*
X0D01*
G01X8523D02*
X0D01*
G01X15078D02*
X-984D01*
G01X-1969Y1653951D02*
X0D01*
G01D02*
X-1969D01*
G01Y1652927D02*
X0D01*
G01X-1969D02*
X0D01*
G01X12601Y1652140D02*
X15078D01*
G01X-984D02*
X15078D01*
G01X8523D02*
X12601D01*
G01X0D02*
X8523D01*
G01X0D02*
X-984D01*
G01X15464Y1651943D02*
X15962D01*
G01D02*
X15464D01*
G01Y1650998D02*
X15962D01*
G01D02*
X15464D01*
G01X8523Y1650801D02*
X15078D01*
G01X-984D02*
X0D01*
G01X8523D02*
X0D01*
G01X15078D02*
X-984D01*
G01X-1969Y1650014D02*
X0D01*
G01D02*
X-1969D01*
G01Y1648990D02*
X0D01*
G01X-1969D02*
X0D01*
G01X12601Y1648203D02*
X15078D01*
G01X-984D02*
X15078D01*
G01X8523D02*
X12601D01*
G01X0D02*
X8523D01*
G01X0D02*
X-984D01*
G01X15464Y1648006D02*
X15962D01*
G01D02*
X15464D01*
G01Y1647061D02*
X15962D01*
G01D02*
X15464D01*
G01X8523Y1646864D02*
X15078D01*
G01X-984D02*
X0D01*
G01X8523D02*
X0D01*
G01X15078D02*
X-984D01*
G01X-1969Y1646077D02*
X0D01*
G01D02*
X-1969D01*
G01Y1645053D02*
X0D01*
G01X-1969D02*
X0D01*
G01X12601Y1644266D02*
X15078D01*
G01X-984D02*
X15078D01*
G01X8523D02*
X12601D01*
G01X0D02*
X8523D01*
G01X0D02*
X-984D01*
G01X15464Y1644069D02*
X15962D01*
G01D02*
X15464D01*
G01Y1643124D02*
X15962D01*
G01D02*
X15464D01*
G01X8523Y1642927D02*
X15078D01*
G01X-984D02*
X0D01*
G01X8523D02*
X0D01*
G01X15078D02*
X-984D01*
G01X-1969Y1642140D02*
X0D01*
G01D02*
X-1969D01*
G01Y1641116D02*
X0D01*
G01X-1969D02*
X0D01*
G01X12601Y1640329D02*
X15078D01*
G01X-984D02*
X15078D01*
G01X8523D02*
X12601D01*
G01X0D02*
X8523D01*
G01X0D02*
X-984D01*
G01X15464Y1640132D02*
X15962D01*
G01D02*
X15464D01*
G01Y1639187D02*
X15962D01*
G01D02*
X15464D01*
G01X8523Y1638990D02*
X15078D01*
G01X-984D02*
X0D01*
G01X8523D02*
X0D01*
G01X15078D02*
X-984D01*
G01X15078Y1656077D02*
X15962Y1655880D01*
G01D02*
X15078Y1656077D01*
G01X14580D02*
X15464Y1655880D01*
G01X14580Y1656077D02*
X15464Y1655880D01*
G01X15078Y1652140D02*
X15962Y1651943D01*
G01D02*
X15078Y1652140D01*
G01X14580D02*
X15464Y1651943D01*
G01X14580Y1652140D02*
X15464Y1651943D01*
G01X15078Y1648203D02*
X15962Y1648006D01*
G01D02*
X15078Y1648203D01*
G01X14580D02*
X15464Y1648006D01*
G01X14580Y1648203D02*
X15464Y1648006D01*
G01X15078Y1644266D02*
X15962Y1644069D01*
G01D02*
X15078Y1644266D01*
G01X14580D02*
X15464Y1644069D01*
G01X14580Y1644266D02*
X15464Y1644069D01*
G01X15078Y1640329D02*
X15962Y1640132D01*
G01D02*
X15078Y1640329D01*
G01X14580D02*
X15464Y1640132D01*
G01X14580Y1640329D02*
X15464Y1640132D01*
G01X-2196Y1658282D02*
X-1969Y1657888D01*
G01X-2196Y1658282D02*
X-1969Y1657888D01*
G01X-2196Y1654345D02*
X-1969Y1653951D01*
G01X-2196Y1654345D02*
X-1969Y1653951D01*
G01X-2196Y1650408D02*
X-1969Y1650014D01*
G01X-2196Y1650408D02*
X-1969Y1650014D01*
G01X-2196Y1646471D02*
X-1969Y1646077D01*
G01X-2196Y1646471D02*
X-1969Y1646077D01*
G01X-2196Y1642534D02*
X-1969Y1642140D01*
G01X-2196Y1642534D02*
X-1969Y1642140D01*
G01X15962Y1658872D02*
Y1659817D01*
G01Y1654935D02*
Y1655880D01*
G01Y1650998D02*
Y1651943D01*
G01Y1647061D02*
Y1648006D01*
G01Y1643124D02*
Y1644069D01*
G01Y1639187D02*
Y1640132D01*
G01D02*
Y1639187D01*
G01Y1644069D02*
Y1643124D01*
G01Y1648006D02*
Y1647061D01*
G01Y1651943D02*
Y1650998D01*
G01Y1655880D02*
Y1654935D01*
G01Y1659817D02*
Y1658872D01*
G01X15464D02*
Y1659817D01*
G01Y1654935D02*
Y1655880D01*
G01Y1650998D02*
Y1651943D01*
G01Y1647061D02*
Y1648006D01*
G01Y1643124D02*
Y1644069D01*
G01Y1639187D02*
Y1640132D01*
G01Y1644069D02*
Y1643124D01*
G01Y1640132D02*
Y1639187D01*
G01Y1648006D02*
Y1647061D01*
G01Y1651943D02*
Y1650998D01*
G01Y1655880D02*
Y1654935D01*
G01Y1659817D02*
Y1658872D01*
G01X13424Y1658675D02*
Y1660014D01*
G01Y1654738D02*
Y1656077D01*
G01Y1650801D02*
Y1652140D01*
G01Y1646864D02*
Y1648203D01*
G01Y1638990D02*
Y1640329D01*
G01Y1642927D02*
Y1644266D01*
G01D02*
Y1642927D01*
G01Y1640329D02*
Y1638990D01*
G01Y1648203D02*
Y1646864D01*
G01Y1652140D02*
Y1650801D01*
G01Y1656077D02*
Y1654738D01*
G01Y1660014D02*
Y1658675D01*
G01X12601D02*
Y1660014D01*
G01Y1654738D02*
Y1656077D01*
G01Y1650801D02*
Y1652140D01*
G01Y1646864D02*
Y1648203D01*
G01Y1642927D02*
Y1644266D01*
G01Y1638990D02*
Y1640329D01*
G01Y1644266D02*
Y1642927D01*
G01Y1640329D02*
Y1638990D01*
G01Y1648203D02*
Y1646864D01*
G01Y1652140D02*
Y1650801D01*
G01Y1656077D02*
Y1654738D01*
G01Y1660014D02*
Y1658675D01*
G01X8523Y1644266D02*
Y1642927D01*
G01Y1640329D02*
Y1638990D01*
G01Y1640329D02*
Y1638990D01*
G01Y1644266D02*
Y1642927D01*
G01Y1648203D02*
Y1646864D01*
G01Y1648203D02*
Y1646864D01*
G01Y1652140D02*
Y1650801D01*
G01Y1652140D02*
Y1650801D01*
G01Y1656077D02*
Y1654738D01*
G01Y1656077D02*
Y1654738D01*
G01Y1660014D02*
Y1658675D01*
G01Y1660014D02*
Y1658675D01*
G01X0Y1657888D02*
Y1658675D01*
G01Y1656077D02*
Y1656864D01*
G01Y1653951D02*
Y1654738D01*
G01Y1652140D02*
Y1652927D01*
G01Y1650014D02*
Y1650801D01*
G01Y1644266D02*
Y1645053D01*
G01Y1648203D02*
Y1648990D01*
G01Y1646077D02*
Y1646864D01*
G01Y1640329D02*
Y1641116D01*
G01Y1642140D02*
Y1642927D01*
G01D02*
Y1642140D01*
G01Y1641116D02*
Y1640329D01*
G01Y1646864D02*
Y1646077D01*
G01Y1645053D02*
Y1644266D01*
G01Y1648990D02*
Y1648203D01*
G01Y1650801D02*
Y1650014D01*
G01Y1652927D02*
Y1652140D01*
G01Y1654738D02*
Y1653951D01*
G01Y1656864D02*
Y1656077D01*
G01Y1658675D02*
Y1657888D01*
G01X-984Y1658675D02*
Y1660014D01*
G01Y1654738D02*
Y1656077D01*
G01Y1650801D02*
Y1652140D01*
G01Y1646864D02*
Y1648203D01*
G01Y1642927D02*
Y1644266D01*
G01Y1638990D02*
Y1640329D01*
G01Y1644266D02*
Y1642927D01*
G01Y1640329D02*
Y1638990D01*
G01Y1648203D02*
Y1646864D01*
G01Y1652140D02*
Y1650801D01*
G01Y1656077D02*
Y1654738D01*
G01Y1660014D02*
Y1658675D01*
G01X-2251Y1645014D02*
Y1642179D01*
G01Y1648951D02*
Y1646116D01*
G01Y1652888D02*
Y1650053D01*
G01Y1656825D02*
Y1653990D01*
G01Y1660762D02*
Y1657927D01*
G01X-2520Y1640762D02*
Y1638557D01*
G01Y1648636D02*
Y1646431D01*
G01Y1644699D02*
Y1642494D01*
G01Y1652573D02*
Y1650368D01*
G01Y1656510D02*
Y1654305D01*
G01Y1660447D02*
Y1658242D01*
G01X-1969Y1641116D02*
X-2196Y1640723D01*
G01X-1969Y1641116D02*
X-2196Y1640723D01*
G01X-1969Y1645053D02*
X-2196Y1644660D01*
G01X-1969Y1645053D02*
X-2196Y1644660D01*
G01X-1969Y1648990D02*
X-2196Y1648597D01*
G01X-1969Y1648990D02*
X-2196Y1648597D01*
G01X-1969Y1652927D02*
X-2196Y1652534D01*
G01X-1969Y1652927D02*
X-2196Y1652534D01*
G01X-1969Y1656864D02*
X-2196Y1656471D01*
G01X-1969Y1656864D02*
X-2196Y1656471D01*
G01X14580Y1678360D02*
X15464Y1678557D01*
G01X14580Y1678360D02*
X15464Y1678557D01*
G01X15078Y1678360D02*
X15962Y1678557D01*
G01D02*
X15078Y1678360D01*
G01X14580Y1674423D02*
X15464Y1674620D01*
G01X14580Y1674423D02*
X15464Y1674620D01*
G01X15078Y1674423D02*
X15962Y1674620D01*
G01D02*
X15078Y1674423D01*
G01X14580Y1670486D02*
X15464Y1670683D01*
G01X14580Y1670486D02*
X15464Y1670683D01*
G01X15078Y1670486D02*
X15962Y1670683D01*
G01D02*
X15078Y1670486D01*
G01X14580Y1666549D02*
X15464Y1666746D01*
G01X14580Y1666549D02*
X15464Y1666746D01*
G01X15078Y1666549D02*
X15962Y1666746D01*
G01D02*
X15078Y1666549D01*
G01X14580Y1662612D02*
X15464Y1662809D01*
G01X14580Y1662612D02*
X15464Y1662809D01*
G01X15078Y1662612D02*
X15962Y1662809D01*
G01D02*
X15078Y1662612D01*
G01X-1969Y1680486D02*
X0D01*
G01X-1969D02*
X0D01*
G01X12601Y1679699D02*
X15078D01*
G01X-984D02*
X15078D01*
G01X8523D02*
X12601D01*
G01X0D02*
X8523D01*
G01X0D02*
X-984D01*
G01X15464Y1679502D02*
X15962D01*
G01D02*
X15464D01*
G01Y1678557D02*
X15962D01*
G01D02*
X15464D01*
G01X8523Y1678360D02*
X15078D01*
G01X-984D02*
X0D01*
G01X8523D02*
X0D01*
G01X15078D02*
X-984D01*
G01X-1969Y1677573D02*
X0D01*
G01D02*
X-1969D01*
G01Y1676549D02*
X0D01*
G01X-1969D02*
X0D01*
G01X12601Y1675762D02*
X15078D01*
G01X-984D02*
X15078D01*
G01X8523D02*
X12601D01*
G01X0D02*
X8523D01*
G01X0D02*
X-984D01*
G01X15464Y1675565D02*
X15962D01*
G01D02*
X15464D01*
G01Y1674620D02*
X15962D01*
G01D02*
X15464D01*
G01X8523Y1674423D02*
X15078D01*
G01X-984D02*
X0D01*
G01X8523D02*
X0D01*
G01X15078D02*
X-984D01*
G01X-1969Y1673636D02*
X0D01*
G01D02*
X-1969D01*
G01Y1672612D02*
X0D01*
G01X-1969D02*
X0D01*
G01X12601Y1671825D02*
X15078D01*
G01X-984D02*
X15078D01*
G01X8523D02*
X12601D01*
G01X0D02*
X8523D01*
G01X0D02*
X-984D01*
G01X15464Y1671628D02*
X15962D01*
G01D02*
X15464D01*
G01Y1670683D02*
X15962D01*
G01D02*
X15464D01*
G01X8523Y1670486D02*
X15078D01*
G01X-984D02*
X0D01*
G01X8523D02*
X0D01*
G01X15078D02*
X-984D01*
G01X-1969Y1669699D02*
X0D01*
G01D02*
X-1969D01*
G01Y1668675D02*
X0D01*
G01X-1969D02*
X0D01*
G01X12601Y1667888D02*
X15078D01*
G01X-984D02*
X15078D01*
G01X8523D02*
X12601D01*
G01X0D02*
X8523D01*
G01X0D02*
X-984D01*
G01X15464Y1667691D02*
X15962D01*
G01D02*
X15464D01*
G01Y1666746D02*
X15962D01*
G01D02*
X15464D01*
G01X8523Y1666549D02*
X15078D01*
G01X-984D02*
X0D01*
G01X8523D02*
X0D01*
G01X15078D02*
X-984D01*
G01X-1969Y1665762D02*
X0D01*
G01D02*
X-1969D01*
G01Y1664738D02*
X0D01*
G01X-1969D02*
X0D01*
G01X12601Y1663951D02*
X15078D01*
G01X-984D02*
X15078D01*
G01X8523D02*
X12601D01*
G01X0D02*
X8523D01*
G01X0D02*
X-984D01*
G01X15464Y1663754D02*
X15962D01*
G01D02*
X15464D01*
G01Y1662809D02*
X15962D01*
G01D02*
X15464D01*
G01X8523Y1662612D02*
X15078D01*
G01X-984D02*
X0D01*
G01X8523D02*
X0D01*
G01X15078D02*
X-984D01*
G01X-1969Y1661825D02*
X0D01*
G01D02*
X-1969D01*
G01Y1660801D02*
X0D01*
G01X-1969D02*
X0D01*
G01X12601Y1660014D02*
X15078D01*
G01X-984D02*
X15078D01*
G01X8523D02*
X12601D01*
G01X0D02*
X8523D01*
G01X0D02*
X-984D01*
G01X15464Y1659817D02*
X15962D01*
G01D02*
X15464D01*
G01X15078Y1679699D02*
X15962Y1679502D01*
G01D02*
X15078Y1679699D01*
G01X14580D02*
X15464Y1679502D01*
G01X14580Y1679699D02*
X15464Y1679502D01*
G01X15078Y1675762D02*
X15962Y1675565D01*
G01D02*
X15078Y1675762D01*
G01X14580D02*
X15464Y1675565D01*
G01X14580Y1675762D02*
X15464Y1675565D01*
G01X15078Y1671825D02*
X15962Y1671628D01*
G01D02*
X15078Y1671825D01*
G01X14580D02*
X15464Y1671628D01*
G01X14580Y1671825D02*
X15464Y1671628D01*
G01X15078Y1667888D02*
X15962Y1667691D01*
G01D02*
X15078Y1667888D01*
G01X14580D02*
X15464Y1667691D01*
G01X14580Y1667888D02*
X15464Y1667691D01*
G01X15078Y1663951D02*
X15962Y1663754D01*
G01D02*
X15078Y1663951D01*
G01X14580D02*
X15464Y1663754D01*
G01X14580Y1663951D02*
X15464Y1663754D01*
G01X15078Y1660014D02*
X15962Y1659817D01*
G01D02*
X15078Y1660014D01*
G01X14580D02*
X15464Y1659817D01*
G01X14580Y1660014D02*
X15464Y1659817D01*
G01X-2196Y1677967D02*
X-1969Y1677573D01*
G01X-2196Y1677967D02*
X-1969Y1677573D01*
G01X-2196Y1674030D02*
X-1969Y1673636D01*
G01X-2196Y1674030D02*
X-1969Y1673636D01*
G01X-2196Y1670093D02*
X-1969Y1669699D01*
G01X-2196Y1670093D02*
X-1969Y1669699D01*
G01X-2196Y1666156D02*
X-1969Y1665762D01*
G01X-2196Y1666156D02*
X-1969Y1665762D01*
G01X-2196Y1662219D02*
X-1969Y1661825D01*
G01X-2196Y1662219D02*
X-1969Y1661825D01*
G01X15962Y1678557D02*
Y1679502D01*
G01Y1674620D02*
Y1675565D01*
G01Y1670683D02*
Y1671628D01*
G01Y1662809D02*
Y1663754D01*
G01Y1666746D02*
Y1667691D01*
G01Y1663754D02*
Y1662809D01*
G01Y1667691D02*
Y1666746D01*
G01Y1671628D02*
Y1670683D01*
G01Y1675565D02*
Y1674620D01*
G01Y1679502D02*
Y1678557D01*
G01X15464D02*
Y1679502D01*
G01Y1674620D02*
Y1675565D01*
G01Y1670683D02*
Y1671628D01*
G01Y1666746D02*
Y1667691D01*
G01Y1662809D02*
Y1663754D01*
G01D02*
Y1662809D01*
G01Y1667691D02*
Y1666746D01*
G01Y1671628D02*
Y1670683D01*
G01Y1675565D02*
Y1674620D01*
G01Y1679502D02*
Y1678557D01*
G01X13424Y1678360D02*
Y1679699D01*
G01Y1674423D02*
Y1675762D01*
G01Y1670486D02*
Y1671825D01*
G01Y1666549D02*
Y1667888D01*
G01Y1662612D02*
Y1663951D01*
G01D02*
Y1662612D01*
G01Y1671825D02*
Y1670486D01*
G01Y1667888D02*
Y1666549D01*
G01Y1675762D02*
Y1674423D01*
G01Y1679699D02*
Y1678360D01*
G01X12601D02*
Y1679699D01*
G01Y1674423D02*
Y1675762D01*
G01Y1666549D02*
Y1667888D01*
G01Y1670486D02*
Y1671825D01*
G01Y1662612D02*
Y1663951D01*
G01D02*
Y1662612D01*
G01Y1671825D02*
Y1670486D01*
G01Y1667888D02*
Y1666549D01*
G01Y1675762D02*
Y1674423D01*
G01Y1679699D02*
Y1678360D01*
G01X8523Y1663951D02*
Y1662612D01*
G01Y1663951D02*
Y1662612D01*
G01Y1667888D02*
Y1666549D01*
G01Y1671825D02*
Y1670486D01*
G01Y1671825D02*
Y1670486D01*
G01Y1667888D02*
Y1666549D01*
G01Y1675762D02*
Y1674423D01*
G01Y1675762D02*
Y1674423D01*
G01Y1679699D02*
Y1678360D01*
G01Y1679699D02*
Y1678360D01*
G01X0Y1679699D02*
Y1680486D01*
G01Y1677573D02*
Y1678360D01*
G01Y1671825D02*
Y1672612D01*
G01Y1675762D02*
Y1676549D01*
G01Y1673636D02*
Y1674423D01*
G01Y1667888D02*
Y1668675D01*
G01Y1669699D02*
Y1670486D01*
G01Y1663951D02*
Y1664738D01*
G01Y1665762D02*
Y1666549D01*
G01Y1660014D02*
Y1660801D01*
G01Y1661825D02*
Y1662612D01*
G01D02*
Y1661825D01*
G01Y1660801D02*
Y1660014D01*
G01Y1666549D02*
Y1665762D01*
G01Y1664738D02*
Y1663951D01*
G01Y1670486D02*
Y1669699D01*
G01Y1668675D02*
Y1667888D01*
G01Y1674423D02*
Y1673636D01*
G01Y1676549D02*
Y1675762D01*
G01Y1672612D02*
Y1671825D01*
G01Y1678360D02*
Y1677573D01*
G01Y1680486D02*
Y1679699D01*
G01X-984Y1678360D02*
Y1679699D01*
G01Y1674423D02*
Y1675762D01*
G01Y1670486D02*
Y1671825D01*
G01Y1666549D02*
Y1667888D01*
G01Y1662612D02*
Y1663951D01*
G01D02*
Y1662612D01*
G01Y1671825D02*
Y1670486D01*
G01Y1667888D02*
Y1666549D01*
G01Y1675762D02*
Y1674423D01*
G01Y1679699D02*
Y1678360D01*
G01X-2251Y1664699D02*
Y1661864D01*
G01Y1668636D02*
Y1665801D01*
G01Y1672573D02*
Y1669738D01*
G01Y1676510D02*
Y1673675D01*
G01Y1680447D02*
Y1677612D01*
G01X-2520Y1664384D02*
Y1662179D01*
G01Y1672258D02*
Y1670053D01*
G01Y1668321D02*
Y1666116D01*
G01Y1676195D02*
Y1673990D01*
G01Y1680132D02*
Y1677927D01*
G01X-1969Y1660801D02*
X-2196Y1660408D01*
G01X-1969Y1660801D02*
X-2196Y1660408D01*
G01X-1969Y1664738D02*
X-2196Y1664345D01*
G01X-1969Y1664738D02*
X-2196Y1664345D01*
G01X-1969Y1668675D02*
X-2196Y1668282D01*
G01X-1969Y1668675D02*
X-2196Y1668282D01*
G01X-1969Y1672612D02*
X-2196Y1672219D01*
G01X-1969Y1672612D02*
X-2196Y1672219D01*
G01X-1969Y1676549D02*
X-2196Y1676156D01*
G01X-1969Y1676549D02*
X-2196Y1676156D01*
G01X-1969Y1680486D02*
X-2196Y1680093D01*
G01X-1969Y1680486D02*
X-2196Y1680093D01*
G01X13779Y1701963D02*
G03I-3937J0D01*
G01X14370D02*
G03I-4528J0D01*
G01X14580Y1682297D02*
X15464Y1682494D01*
G01X14580Y1682297D02*
X15464Y1682494D01*
G01X15078Y1682297D02*
X15962Y1682494D01*
G01D02*
X15078Y1682297D01*
G01X0Y1688577D02*
X24803D01*
G01X-1969Y1684423D02*
X0D01*
G01X-1969D02*
X0D01*
G01X12601Y1683636D02*
X15078D01*
G01X-984D02*
X15078D01*
G01X8523D02*
X12601D01*
G01X0D02*
X8523D01*
G01X0D02*
X-984D01*
G01X15464Y1683439D02*
X15962D01*
G01D02*
X15464D01*
G01Y1682494D02*
X15962D01*
G01D02*
X15464D01*
G01X8523Y1682297D02*
X15078D01*
G01X-984D02*
X0D01*
G01X8523D02*
X0D01*
G01X15078D02*
X-984D01*
G01X-1969Y1681510D02*
X0D01*
G01D02*
X-1969D01*
G01X15078Y1683636D02*
X15962Y1683439D01*
G01D02*
X15078Y1683636D01*
G01X14580D02*
X15464Y1683439D01*
G01X14580Y1683636D02*
X15464Y1683439D01*
G01X-2196Y1681904D02*
X-1969Y1681510D01*
G01X-2196Y1681904D02*
X-1969Y1681510D01*
G01X15962Y1682494D02*
Y1683439D01*
G01D02*
Y1682494D01*
G01X15464D02*
Y1683439D01*
G01D02*
Y1682494D01*
G01X13424Y1682297D02*
Y1683636D01*
G01D02*
Y1682297D01*
G01X12601D02*
Y1683636D01*
G01D02*
Y1682297D01*
G01X8523Y1683636D02*
Y1682297D01*
G01Y1683636D02*
Y1682297D01*
G01X0Y1683636D02*
Y1684423D01*
G01Y1681510D02*
Y1682297D01*
G01D02*
Y1681510D01*
G01Y1684423D02*
Y1683636D01*
G01Y1714167D02*
Y1694876D01*
G01X-984Y1682297D02*
Y1683636D01*
G01D02*
Y1682297D01*
G01X-2251Y1684384D02*
Y1681549D01*
G01X-2520Y1684069D02*
Y1681864D01*
G01X-1969Y1684423D02*
X-2196Y1684030D01*
G01X-1969Y1684423D02*
X-2196Y1684030D01*
G01X26771Y1716136D02*
X0D01*
G01Y1714167D02*
Y1734654D01*
G01Y1714167D02*
Y1734654D01*
G01X13779Y1746858D02*
G03I-3937J0D01*
G01X14370D02*
G03I-4528J0D01*
G01X0Y1732685D02*
X26771D01*
G01X0Y1734654D02*
Y1803347D01*
G01Y1734654D02*
Y1803347D01*
G01Y1734654D02*
Y1753945D01*
G01X15464Y1765170D02*
X14689Y1764973D01*
G01X15473D02*
X16249Y1765170D01*
G01D02*
X15464D01*
G01X12829Y1764973D02*
X9001D01*
G01X0D02*
X-984D01*
G01X9001D02*
X0D01*
G01X15473D02*
X12829D01*
G01X8788Y1763758D02*
X9726D01*
G01X11133D02*
X10128D01*
G01X11535Y1763365D02*
X8386D01*
G01X24803Y1760244D02*
X0D01*
G01X10932Y1765333D02*
X11066Y1765202D01*
G01X9659D02*
X9525Y1765333D01*
G01X11267Y1765530D02*
X11468Y1765268D01*
G01X-2196Y1764579D02*
X-2000Y1764240D01*
G01X11066Y1765202D02*
X11133Y1765005D01*
G01X9726D02*
X9659Y1765202D01*
G01X11468Y1765268D02*
X11535Y1764940D01*
G01X16249Y1765170D02*
Y1766115D01*
G01X15464D02*
Y1765170D01*
G01X13614Y1766312D02*
Y1764973D01*
G01X12829D02*
Y1766312D01*
G01X11535Y1764940D02*
Y1763365D01*
G01X11133Y1765005D02*
Y1763758D01*
G01X10128D02*
Y1765005D01*
G01X9726Y1763758D02*
Y1765005D01*
G01X9001Y1766312D02*
Y1764973D01*
G01X8788Y1765005D02*
Y1763758D01*
G01X8386Y1763365D02*
Y1764940D01*
G01X197Y1766312D02*
Y1764973D01*
G01X0Y1753945D02*
Y1852370D01*
G01X-984Y1766312D02*
Y1764973D01*
G01X-2251Y1767075D02*
Y1764240D01*
G01X-2520Y1766760D02*
Y1764555D01*
G01X8386Y1764940D02*
X8453Y1765268D01*
G01X10128Y1765005D02*
X10195Y1765202D01*
G01X8855D02*
X8788Y1765005D01*
G01X8453Y1765268D02*
X8654Y1765530D01*
G01X10195Y1765202D02*
X10329Y1765333D01*
G01X8989D02*
X8855Y1765202D01*
G01X15464Y1784855D02*
X14689Y1784658D01*
G01X15473D02*
X16249Y1784855D01*
G01X15464Y1780918D02*
X14689Y1780721D01*
G01X15473D02*
X16249Y1780918D01*
G01X15464Y1776981D02*
X14689Y1776784D01*
G01X15473D02*
X16249Y1776981D01*
G01X15464Y1773044D02*
X14689Y1772847D01*
G01X15473D02*
X16249Y1773044D01*
G01X15464Y1769107D02*
X14689Y1768910D01*
G01X15473D02*
X16249Y1769107D01*
G01X9001Y1785997D02*
X12829D01*
G01X-984D02*
X0D01*
G01X15473D02*
X12829D01*
G01X0D02*
X9001D01*
G01X16249Y1785800D02*
X15464D01*
G01X16249Y1784855D02*
X15464D01*
G01X12829Y1784658D02*
X9001D01*
G01X0D02*
X-984D01*
G01X9001D02*
X0D01*
G01X15473D02*
X12829D01*
G01X9001Y1782060D02*
X12829D01*
G01X-984D02*
X0D01*
G01X15473D02*
X12829D01*
G01X0D02*
X9001D01*
G01X16249Y1781863D02*
X15464D01*
G01X16249Y1780918D02*
X15464D01*
G01X12829Y1780721D02*
X9001D01*
G01X0D02*
X-984D01*
G01X9001D02*
X0D01*
G01X15473D02*
X12829D01*
G01X9001Y1778123D02*
X12829D01*
G01X-984D02*
X0D01*
G01X15473D02*
X12829D01*
G01X0D02*
X9001D01*
G01X16249Y1777926D02*
X15464D01*
G01X16249Y1776981D02*
X15464D01*
G01X12829Y1776784D02*
X9001D01*
G01X0D02*
X-984D01*
G01X9001D02*
X0D01*
G01X15473D02*
X12829D01*
G01X9001Y1774186D02*
X12829D01*
G01X-984D02*
X0D01*
G01X15473D02*
X12829D01*
G01X0D02*
X9001D01*
G01X16249Y1773989D02*
X15464D01*
G01X16249Y1773044D02*
X15464D01*
G01X12829Y1772847D02*
X9001D01*
G01X0D02*
X-984D01*
G01X9001D02*
X0D01*
G01X15473D02*
X12829D01*
G01X9001Y1770249D02*
X12829D01*
G01X-984D02*
X0D01*
G01X15473D02*
X12829D01*
G01X0D02*
X9001D01*
G01X16249Y1770052D02*
X15464D01*
G01X16249Y1769107D02*
X15464D01*
G01X12829Y1768910D02*
X9001D01*
G01X0D02*
X-984D01*
G01X9001D02*
X0D01*
G01X15473D02*
X12829D01*
G01X8386Y1767105D02*
X11535D01*
G01Y1766711D02*
X8922D01*
G01X9391Y1766317D02*
X8855D01*
G01X9001Y1766312D02*
X12829D01*
G01X-984D02*
X0D01*
G01X15473D02*
X12829D01*
G01X0D02*
X9001D01*
G01X16249Y1766115D02*
X15464D01*
G01X10463Y1765793D02*
X10798D01*
G01X9123D02*
X9391D01*
G01X10530Y1765399D02*
X10731D01*
G01X9324D02*
X9190D01*
G01X16249Y1785800D02*
X15473Y1785997D01*
G01X14689D02*
X15464Y1785800D01*
G01X16249Y1781863D02*
X15473Y1782060D01*
G01X14689D02*
X15464Y1781863D01*
G01X16249Y1777926D02*
X15473Y1778123D01*
G01X14689D02*
X15464Y1777926D01*
G01X16249Y1773989D02*
X15473Y1774186D01*
G01X14689D02*
X15464Y1773989D01*
G01X16249Y1770052D02*
X15473Y1770249D01*
G01X14689D02*
X15464Y1770052D01*
G01X16249Y1766115D02*
X15473Y1766312D01*
G01X14689D02*
X15464Y1766115D01*
G01X10798Y1765793D02*
X10999Y1765727D01*
G01X10731Y1765399D02*
X10932Y1765333D01*
G01X9391Y1765793D02*
X9592Y1765727D01*
G01X9525Y1765333D02*
X9324Y1765399D01*
G01X10999Y1765727D02*
X11267Y1765530D01*
G01X9592Y1765727D02*
X9860Y1765530D01*
G01X8922Y1766711D02*
X9391Y1766317D01*
G01X8855D02*
X8386Y1766711D01*
G01X-2196Y1784264D02*
X-2000Y1783925D01*
G01X-2196Y1780327D02*
X-2000Y1779988D01*
G01X-2196Y1776390D02*
X-2000Y1776051D01*
G01X-2196Y1772453D02*
X-2000Y1772114D01*
G01X-2196Y1768516D02*
X-2000Y1768177D01*
G01X9860Y1765530D02*
X9927Y1765399D01*
G01X16249Y1784855D02*
Y1785800D01*
G01Y1780918D02*
Y1781863D01*
G01Y1776981D02*
Y1777926D01*
G01Y1773044D02*
Y1773989D01*
G01Y1769107D02*
Y1770052D01*
G01X15464D02*
Y1769107D01*
G01Y1773989D02*
Y1773044D01*
G01Y1777926D02*
Y1776981D01*
G01Y1781863D02*
Y1780918D01*
G01Y1785800D02*
Y1784855D01*
G01X13614Y1770249D02*
Y1768910D01*
G01Y1774186D02*
Y1772847D01*
G01Y1778123D02*
Y1776784D01*
G01Y1782060D02*
Y1780721D01*
G01Y1785997D02*
Y1784658D01*
G01X12829D02*
Y1785997D01*
G01Y1780721D02*
Y1782060D01*
G01Y1776784D02*
Y1778123D01*
G01Y1772847D02*
Y1774186D01*
G01Y1768910D02*
Y1770249D01*
G01X11535Y1767105D02*
Y1766711D01*
G01X9001Y1770249D02*
Y1768910D01*
G01Y1774186D02*
Y1772847D01*
G01Y1778123D02*
Y1776784D01*
G01Y1782060D02*
Y1780721D01*
G01Y1785997D02*
Y1784658D01*
G01X8386Y1766711D02*
Y1767105D01*
G01X197Y1770249D02*
Y1768910D01*
G01Y1774186D02*
Y1772847D01*
G01Y1778123D02*
Y1776784D01*
G01Y1782060D02*
Y1780721D01*
G01Y1785997D02*
Y1784658D01*
G01X-984Y1770249D02*
Y1768910D01*
G01Y1774186D02*
Y1772847D01*
G01Y1778123D02*
Y1776784D01*
G01Y1782060D02*
Y1780721D01*
G01Y1785997D02*
Y1784658D01*
G01X-2251Y1771012D02*
Y1768177D01*
G01Y1774949D02*
Y1772114D01*
G01Y1778886D02*
Y1776051D01*
G01Y1786760D02*
Y1783925D01*
G01Y1782823D02*
Y1779988D01*
G01X-2520Y1770697D02*
Y1768492D01*
G01Y1774634D02*
Y1772429D01*
G01Y1778571D02*
Y1776366D01*
G01Y1782508D02*
Y1780303D01*
G01Y1786445D02*
Y1784240D01*
G01X9927Y1765399D02*
X9994Y1765530D01*
G01X10329Y1765333D02*
X10530Y1765399D01*
G01X10262Y1765727D02*
X10463Y1765793D01*
G01X9190Y1765399D02*
X8989Y1765333D01*
G01X8922Y1765727D02*
X9123Y1765793D01*
G01X-1983Y1767075D02*
X-2196Y1766705D01*
G01X-1983Y1771012D02*
X-2196Y1770642D01*
G01X-1983Y1774949D02*
X-2196Y1774579D01*
G01X-1983Y1778886D02*
X-2196Y1778516D01*
G01X-1983Y1782823D02*
X-2196Y1782453D01*
G01X-1983Y1786760D02*
X-2196Y1786390D01*
G01X9994Y1765530D02*
X10262Y1765727D01*
G01X8654Y1765530D02*
X8922Y1765727D01*
G01X15464Y1804540D02*
X14689Y1804343D01*
G01X15473D02*
X16249Y1804540D01*
G01X15464Y1800603D02*
X14689Y1800406D01*
G01X15473D02*
X16249Y1800603D01*
G01X15464Y1796666D02*
X14689Y1796469D01*
G01X15473D02*
X16249Y1796666D01*
G01X15464Y1792729D02*
X14689Y1792532D01*
G01X15473D02*
X16249Y1792729D01*
G01X15464Y1788792D02*
X14689Y1788595D01*
G01X15473D02*
X16249Y1788792D01*
G01X0Y1807538D02*
X15551D01*
G01X3937Y1807284D02*
X19882D01*
G01X3937D02*
X19882D01*
G01X9001Y1805682D02*
X12829D01*
G01X-984D02*
X0D01*
G01X15473D02*
X12829D01*
G01X0D02*
X9001D01*
G01X16249Y1805485D02*
X15464D01*
G01X16249Y1804540D02*
X15464D01*
G01X12829Y1804343D02*
X9001D01*
G01X0D02*
X-984D01*
G01X9001D02*
X0D01*
G01X15473D02*
X12829D01*
G01X9001Y1801745D02*
X12829D01*
G01X-984D02*
X0D01*
G01X15473D02*
X12829D01*
G01X0D02*
X9001D01*
G01X16249Y1801548D02*
X15464D01*
G01X16249Y1800603D02*
X15464D01*
G01X12829Y1800406D02*
X9001D01*
G01X0D02*
X-984D01*
G01X9001D02*
X0D01*
G01X15473D02*
X12829D01*
G01X9001Y1797808D02*
X12829D01*
G01X-984D02*
X0D01*
G01X15473D02*
X12829D01*
G01X0D02*
X9001D01*
G01X16249Y1797611D02*
X15464D01*
G01X16249Y1796666D02*
X15464D01*
G01X12829Y1796469D02*
X9001D01*
G01X0D02*
X-984D01*
G01X9001D02*
X0D01*
G01X15473D02*
X12829D01*
G01X9001Y1793871D02*
X12829D01*
G01X-984D02*
X0D01*
G01X15473D02*
X12829D01*
G01X0D02*
X9001D01*
G01X16249Y1793674D02*
X15464D01*
G01X16249Y1792729D02*
X15464D01*
G01X12829Y1792532D02*
X9001D01*
G01X0D02*
X-984D01*
G01X9001D02*
X0D01*
G01X15473D02*
X12829D01*
G01X9001Y1789934D02*
X12829D01*
G01X-984D02*
X0D01*
G01X15473D02*
X12829D01*
G01X0D02*
X9001D01*
G01X16249Y1789737D02*
X15464D01*
G01X16249Y1788792D02*
X15464D01*
G01X12829Y1788595D02*
X9001D01*
G01X0D02*
X-984D01*
G01X9001D02*
X0D01*
G01X15473D02*
X12829D01*
G01X16249Y1805485D02*
X15473Y1805682D01*
G01X14689D02*
X15464Y1805485D01*
G01X16249Y1801548D02*
X15473Y1801745D01*
G01X14689D02*
X15464Y1801548D01*
G01X16249Y1797611D02*
X15473Y1797808D01*
G01X14689D02*
X15464Y1797611D01*
G01X16249Y1793674D02*
X15473Y1793871D01*
G01X14689D02*
X15464Y1793674D01*
G01X16249Y1789737D02*
X15473Y1789934D01*
G01X14689D02*
X15464Y1789737D01*
G01X-2196Y1803949D02*
X-2000Y1803610D01*
G01X-2196Y1800012D02*
X-2000Y1799673D01*
G01X-2196Y1796075D02*
X-2000Y1795736D01*
G01X-2196Y1792138D02*
X-2000Y1791799D01*
G01X-2196Y1788201D02*
X-2000Y1787862D01*
G01X16249Y1804540D02*
Y1805485D01*
G01Y1800603D02*
Y1801548D01*
G01Y1796666D02*
Y1797611D01*
G01Y1788792D02*
Y1789737D01*
G01Y1792729D02*
Y1793674D01*
G01X15551Y1814546D02*
Y1807538D01*
G01X15464Y1789737D02*
Y1788792D01*
G01Y1793674D02*
Y1792729D01*
G01Y1797611D02*
Y1796666D01*
G01Y1801548D02*
Y1800603D01*
G01Y1805485D02*
Y1804540D01*
G01X13614Y1793871D02*
Y1792532D01*
G01Y1789934D02*
Y1788595D01*
G01Y1797808D02*
Y1796469D01*
G01Y1801745D02*
Y1800406D01*
G01Y1805682D02*
Y1804343D01*
G01X12829D02*
Y1805682D01*
G01Y1800406D02*
Y1801745D01*
G01Y1796469D02*
Y1797808D01*
G01Y1788595D02*
Y1789934D01*
G01Y1792532D02*
Y1793871D01*
G01X9001Y1789934D02*
Y1788595D01*
G01Y1793871D02*
Y1792532D01*
G01Y1797808D02*
Y1796469D01*
G01Y1801745D02*
Y1800406D01*
G01Y1805682D02*
Y1804343D01*
G01X197Y1789934D02*
Y1788595D01*
G01Y1793871D02*
Y1792532D01*
G01Y1797808D02*
Y1796469D01*
G01Y1801745D02*
Y1800406D01*
G01Y1805682D02*
Y1804343D01*
G01X-984Y1789934D02*
Y1788595D01*
G01Y1793871D02*
Y1792532D01*
G01Y1797808D02*
Y1796469D01*
G01Y1801745D02*
Y1800406D01*
G01Y1805682D02*
Y1804343D01*
G01X-2251Y1790697D02*
Y1787862D01*
G01Y1794634D02*
Y1791799D01*
G01Y1798571D02*
Y1795736D01*
G01Y1802508D02*
Y1799673D01*
G01Y1806445D02*
Y1803610D01*
G01X-2520Y1790382D02*
Y1788177D01*
G01Y1794319D02*
Y1792114D01*
G01Y1798256D02*
Y1796051D01*
G01Y1802193D02*
Y1799988D01*
G01Y1806130D02*
Y1803925D01*
G01X-1983Y1790697D02*
X-2196Y1790327D01*
G01X-1983Y1794634D02*
X-2196Y1794264D01*
G01X-1983Y1798571D02*
X-2196Y1798201D01*
G01X-1983Y1802508D02*
X-2196Y1802138D01*
G01X-1983Y1806445D02*
X-2196Y1806075D01*
G01X15551Y1807538D02*
X18701Y1808672D01*
G01X996Y1804343D02*
X0Y1803347D01*
G01X996Y1804343D02*
X0Y1803347D01*
G01X2335Y1805682D02*
X996Y1804343D01*
G01X2335Y1805682D02*
X996Y1804343D01*
G01X3937Y1807284D02*
X2335Y1805682D01*
G01X3937Y1807284D02*
X2335Y1805682D01*
G01X15464Y1828162D02*
X14689Y1827965D01*
G01X15473D02*
X16249Y1828162D01*
G01X15464Y1824225D02*
X14689Y1824028D01*
G01X15473D02*
X16249Y1824225D01*
G01X15464Y1820288D02*
X14689Y1820091D01*
G01X15473D02*
X16249Y1820288D01*
G01X15464Y1816351D02*
X14689Y1816154D01*
G01X15473D02*
X16249Y1816351D01*
G01Y1828162D02*
X15464D01*
G01X12829Y1827965D02*
X9001D01*
G01X0D02*
X-984D01*
G01X9001D02*
X0D01*
G01X15473D02*
X12829D01*
G01X9001Y1825367D02*
X12829D01*
G01X-984D02*
X0D01*
G01X15473D02*
X12829D01*
G01X0D02*
X9001D01*
G01X16249Y1825170D02*
X15464D01*
G01X16249Y1824225D02*
X15464D01*
G01X12829Y1824028D02*
X9001D01*
G01X0D02*
X-984D01*
G01X9001D02*
X0D01*
G01X15473D02*
X12829D01*
G01X9001Y1821430D02*
X12829D01*
G01X-984D02*
X0D01*
G01X15473D02*
X12829D01*
G01X0D02*
X9001D01*
G01X16249Y1821233D02*
X15464D01*
G01X16249Y1820288D02*
X15464D01*
G01X12829Y1820091D02*
X9001D01*
G01X0D02*
X-984D01*
G01X9001D02*
X0D01*
G01X15473D02*
X12829D01*
G01X9001Y1817493D02*
X12829D01*
G01X-984D02*
X0D01*
G01X15473D02*
X12829D01*
G01X0D02*
X9001D01*
G01X16249Y1817296D02*
X15464D01*
G01X16249Y1816351D02*
X15464D01*
G01X0Y1816154D02*
X-984D01*
G01X12829D02*
X9001D01*
G01D02*
X0D01*
G01X15473D02*
X12829D01*
G01X3937Y1814764D02*
X19882D01*
G01X3937D02*
X19882D01*
G01X0Y1814546D02*
X15551D01*
G01X16249Y1825170D02*
X15473Y1825367D01*
G01X14689D02*
X15464Y1825170D01*
G01X16249Y1821233D02*
X15473Y1821430D01*
G01X14689D02*
X15464Y1821233D01*
G01X16249Y1817296D02*
X15473Y1817493D01*
G01X14689D02*
X15464Y1817296D01*
G01X15551Y1814546D02*
X18701Y1813412D01*
G01X2547Y1816154D02*
X3937Y1814764D01*
G01X2547Y1816154D02*
X3937Y1814764D01*
G01X0Y1818701D02*
X1371Y1817329D01*
G01X0Y1818701D02*
X1371Y1817329D01*
G01D02*
X2547Y1816154D01*
G01X1371Y1817329D02*
X2547Y1816154D01*
G01X-2196Y1827571D02*
X-2000Y1827232D01*
G01X-2196Y1823634D02*
X-2000Y1823295D01*
G01X-2196Y1819697D02*
X-2000Y1819358D01*
G01X-2196Y1815760D02*
X-2000Y1815421D01*
G01X16249Y1828162D02*
Y1829107D01*
G01Y1824225D02*
Y1825170D01*
G01Y1820288D02*
Y1821233D01*
G01Y1816351D02*
Y1817296D01*
G01X15464D02*
Y1816351D01*
G01Y1821233D02*
Y1820288D01*
G01Y1825170D02*
Y1824225D01*
G01Y1829107D02*
Y1828162D01*
G01X13614Y1817493D02*
Y1816154D01*
G01Y1821430D02*
Y1820091D01*
G01Y1825367D02*
Y1824028D01*
G01Y1829304D02*
Y1827965D01*
G01X12829D02*
Y1829304D01*
G01Y1824028D02*
Y1825367D01*
G01Y1820091D02*
Y1821430D01*
G01Y1816154D02*
Y1817493D01*
G01X9001D02*
Y1816154D01*
G01Y1821430D02*
Y1820091D01*
G01Y1825367D02*
Y1824028D01*
G01Y1829304D02*
Y1827965D01*
G01X197Y1817493D02*
Y1816154D01*
G01Y1821430D02*
Y1820091D01*
G01Y1825367D02*
Y1824028D01*
G01Y1829304D02*
Y1827965D01*
G01X0Y1818701D02*
Y1871662D01*
G01Y1818701D02*
Y1871662D01*
G01X-984Y1817493D02*
Y1816154D01*
G01Y1821430D02*
Y1820091D01*
G01Y1825367D02*
Y1824028D01*
G01Y1829304D02*
Y1827965D01*
G01X-2251Y1818256D02*
Y1815421D01*
G01Y1822193D02*
Y1819358D01*
G01Y1826130D02*
Y1823295D01*
G01Y1830067D02*
Y1827232D01*
G01X-2520Y1821878D02*
Y1819673D01*
G01Y1817941D02*
Y1815736D01*
G01Y1825815D02*
Y1823610D01*
G01Y1829752D02*
Y1827547D01*
G01X-1983Y1818256D02*
X-2196Y1817886D01*
G01X-1983Y1822193D02*
X-2196Y1821823D01*
G01X-1983Y1826130D02*
X-2196Y1825760D01*
G01X15464Y1839973D02*
X14689Y1839776D01*
G01X15473D02*
X16249Y1839973D01*
G01X15464Y1836036D02*
X14689Y1835839D01*
G01X15473D02*
X16249Y1836036D01*
G01X15464Y1832099D02*
X14689Y1831902D01*
G01X15473D02*
X16249Y1832099D01*
G01X24803Y1846071D02*
X0D01*
G01X9001Y1841115D02*
X12829D01*
G01X-984D02*
X0D01*
G01X15473D02*
X12829D01*
G01X0D02*
X9001D01*
G01X16249Y1840918D02*
X15464D01*
G01X16249Y1839973D02*
X15464D01*
G01X12829Y1839776D02*
X9001D01*
G01X0D02*
X-984D01*
G01X9001D02*
X0D01*
G01X15473D02*
X12829D01*
G01X9001Y1837178D02*
X12829D01*
G01X-984D02*
X0D01*
G01X15473D02*
X12829D01*
G01X0D02*
X9001D01*
G01X16249Y1836981D02*
X15464D01*
G01X16249Y1836036D02*
X15464D01*
G01X12829Y1835839D02*
X9001D01*
G01X0D02*
X-984D01*
G01X9001D02*
X0D01*
G01X15473D02*
X12829D01*
G01X9001Y1833241D02*
X12829D01*
G01X-984D02*
X0D01*
G01X15473D02*
X12829D01*
G01X0D02*
X9001D01*
G01X16249Y1833044D02*
X15464D01*
G01X16249Y1832099D02*
X15464D01*
G01X12829Y1831902D02*
X9001D01*
G01X0D02*
X-984D01*
G01X9001D02*
X0D01*
G01X15473D02*
X12829D01*
G01X9001Y1829304D02*
X12829D01*
G01X-984D02*
X0D01*
G01X15473D02*
X12829D01*
G01X0D02*
X9001D01*
G01X16249Y1829107D02*
X15464D01*
G01X16249Y1840918D02*
X15473Y1841115D01*
G01X14689D02*
X15464Y1840918D01*
G01X16249Y1836981D02*
X15473Y1837178D01*
G01X14689D02*
X15464Y1836981D01*
G01X16249Y1833044D02*
X15473Y1833241D01*
G01X14689D02*
X15464Y1833044D01*
G01X16249Y1829107D02*
X15473Y1829304D01*
G01X14689D02*
X15464Y1829107D01*
G01X-2196Y1839382D02*
X-2000Y1839043D01*
G01X-2196Y1835445D02*
X-2000Y1835106D01*
G01X-2196Y1831508D02*
X-2000Y1831169D01*
G01X16249Y1839973D02*
Y1840918D01*
G01Y1836036D02*
Y1836981D01*
G01Y1832099D02*
Y1833044D01*
G01X15464D02*
Y1832099D01*
G01Y1840918D02*
Y1839973D01*
G01Y1836981D02*
Y1836036D01*
G01X13614Y1833241D02*
Y1831902D01*
G01Y1837178D02*
Y1835839D01*
G01Y1841115D02*
Y1839776D01*
G01X12829D02*
Y1841115D01*
G01Y1835839D02*
Y1837178D01*
G01Y1831902D02*
Y1833241D01*
G01X9001D02*
Y1831902D01*
G01Y1837178D02*
Y1835839D01*
G01Y1841115D02*
Y1839776D01*
G01X197Y1833241D02*
Y1831902D01*
G01Y1837178D02*
Y1835839D01*
G01Y1841115D02*
Y1839776D01*
G01X-984Y1833241D02*
Y1831902D01*
G01Y1837178D02*
Y1835839D01*
G01Y1841115D02*
Y1839776D01*
G01X-2251Y1834004D02*
Y1831169D01*
G01Y1837941D02*
Y1835106D01*
G01Y1841878D02*
Y1839043D01*
G01X-2520Y1833689D02*
Y1831484D01*
G01Y1837626D02*
Y1835421D01*
G01Y1841563D02*
Y1839358D01*
G01X-1983Y1830067D02*
X-2196Y1829697D01*
G01X-1983Y1834004D02*
X-2196Y1833634D01*
G01X-1983Y1837941D02*
X-2196Y1837571D01*
G01X-1983Y1841878D02*
X-2196Y1841508D01*
G01X13779Y1859457D02*
G03I-3937J0D01*
G01X14370D02*
G03I-4528J0D01*
G01X0Y1852370D02*
Y1871662D01*
G01X33464Y1903150D02*
G03I-15748J0D01*
G01X0Y1873630D02*
X26771D01*
G01X0Y1871662D02*
Y1988189D01*
G01Y1871662D02*
Y1988189D01*
G01X24705Y1903150D02*
G03I-6989J0D01*
G01X0Y1988435D02*
Y2061827D01*
G01X3937Y1992126D02*
G03X0Y1988189I0J-3937D01*
G01X3937Y1992126D02*
G03X0Y1988189I0J-3937D01*
G01X3937Y1992126D02*
X1029527D01*
G01X3937D02*
X1029527D01*
G01X119Y2066114D02*
X-680Y2066713D01*
X-1079Y2067412D01*
X-1212Y2068210D01*
X-946Y2069208D01*
X-280Y2069907D01*
X518Y2070107D01*
X1317Y2070007D01*
X1982Y2069607D01*
X3313Y2067611D01*
X4244Y2066713D01*
X5576Y2066114D01*
X6773Y2065914D01*
Y2070107D01*
G01X-1212Y2075995D02*
X-946Y2075197D01*
X-280Y2074598D01*
X518Y2074199D01*
X1583Y2073899D01*
X2781Y2073800D01*
X3978Y2073899D01*
X5043Y2074199D01*
X5842Y2074598D01*
X6507Y2075197D01*
X6773Y2075995D01*
X6507Y2076794D01*
X5842Y2077393D01*
X5043Y2077792D01*
X3978Y2078092D01*
X2781Y2078191D01*
X1583Y2078092D01*
X518Y2077792D01*
X-280Y2077393D01*
X-946Y2076794D01*
X-1212Y2075995D01*
G01X7039Y2083980D02*
X6906Y2083781D01*
X6640D01*
X6507Y2083980D01*
X6640Y2084180D01*
X6906D01*
X7039Y2083980D01*
G01X-1212Y2091965D02*
X-946Y2091167D01*
X-280Y2090568D01*
X518Y2090169D01*
X1583Y2089869D01*
X2781Y2089770D01*
X3978Y2089869D01*
X5043Y2090169D01*
X5842Y2090568D01*
X6507Y2091167D01*
X6773Y2091965D01*
X6507Y2092764D01*
X5842Y2093363D01*
X5043Y2093762D01*
X3978Y2094062D01*
X2781Y2094161D01*
X1583Y2094062D01*
X518Y2093762D01*
X-280Y2093363D01*
X-946Y2092764D01*
X-1212Y2091965D01*
G01Y2099950D02*
X-946Y2099152D01*
X-280Y2098553D01*
X518Y2098154D01*
X1583Y2097854D01*
X2781Y2097755D01*
X3978Y2097854D01*
X5043Y2098154D01*
X5842Y2098553D01*
X6507Y2099152D01*
X6773Y2099950D01*
X6507Y2100749D01*
X5842Y2101348D01*
X5043Y2101747D01*
X3978Y2102047D01*
X2781Y2102146D01*
X1583Y2102047D01*
X518Y2101747D01*
X-280Y2101348D01*
X-946Y2100749D01*
X-1212Y2099950D01*
G01X2836Y2063244D02*
Y2064661D01*
G01X0Y2061827D02*
X2836Y2063244D01*
G01X27172Y-51088D02*
Y-70025D01*
G01X36548Y24746D02*
X36556Y24805D01*
G01X36540Y24688D02*
X36548Y24746D01*
G01X36533Y24633D02*
X36540Y24688D01*
G01X36528Y24580D02*
X36533Y24633D01*
G01X36523Y24529D02*
X36528Y24580D01*
G01X36519Y24480D02*
X36523Y24529D01*
G01X36517Y24434D02*
X36519Y24480D01*
G01X36516Y24391D02*
X36517Y24434D01*
G01X36516Y24350D02*
Y24391D01*
G01X36518Y24312D02*
X36516Y24350D01*
G01X36521Y24276D02*
X36518Y24312D01*
G01X36525Y24243D02*
X36521Y24276D01*
G01X36531Y24213D02*
X36525Y24243D01*
G01X36538Y24186D02*
X36531Y24213D01*
G01X36547Y24162D02*
X36538Y24186D01*
G01X36557Y24140D02*
X36547Y24162D01*
G01X36569Y24121D02*
X36557Y24140D01*
G01X36582Y24106D02*
X36569Y24121D01*
G01X36602Y25119D02*
X36610Y25182D01*
G01X36593Y25056D02*
X36602Y25119D01*
G01X36517Y24434D02*
X36516Y24391D01*
G01X36519Y24480D02*
X36517Y24434D01*
G01X36523Y24529D02*
X36519Y24480D01*
G01X36528Y24580D02*
X36523Y24529D01*
G01X36533Y24633D02*
X36528Y24580D01*
G01X36540Y24688D02*
X36533Y24633D01*
G01X36548Y24746D02*
X36540Y24688D01*
G01X36556Y24805D02*
X36548Y24746D01*
G01X35299Y32421D02*
X31890Y30453D01*
G01X36556Y24805D02*
X36593Y25056D01*
G01X36584Y24992D02*
X36565Y24866D01*
G01X36614Y25256D02*
Y32421D01*
G01X31890Y28721D02*
Y30453D01*
G01X27953Y187185D02*
Y20138D01*
G01X36518Y24312D02*
X36521Y24276D01*
G01X36547Y24161D02*
X36557Y24140D01*
G01X70079Y25256D02*
X36614D01*
G01Y24075D02*
X90551D01*
G01X55118Y20138D02*
X27953D01*
G01X36569Y24121D02*
X36582Y24106D01*
G01X31890Y29824D02*
X36610Y25182D01*
G01X36614Y24075D02*
X31890Y28721D01*
G01X39764Y37343D02*
X38582Y36162D01*
G01Y32421D02*
Y174902D01*
G01Y52047D02*
X70866D01*
G01X38582Y50276D02*
X70866D01*
G01X38582Y47047D02*
X70866D01*
G01X38582Y45276D02*
X70866D01*
G01X38582Y42047D02*
X70866D01*
G01X38582Y40276D02*
X70866D01*
G01X35299Y32421D02*
X38582D01*
G01Y34390D02*
X40551Y32421D01*
G01X38582Y72047D02*
X70866D01*
G01X38582Y70276D02*
X70866D01*
G01X38582Y67047D02*
X70866D01*
G01X38582Y65276D02*
X70866D01*
G01X38582Y62047D02*
X70866D01*
G01X38582Y60276D02*
X70866D01*
G01X38582Y57047D02*
X69685D01*
G01X38582Y55276D02*
X69685D01*
G01X38582Y92047D02*
X70866D01*
G01X38582Y90276D02*
X70866D01*
G01X38582Y87047D02*
X70866D01*
G01X38582Y85276D02*
X70866D01*
G01X38582Y82047D02*
X70866D01*
G01X38582Y80276D02*
X70866D01*
G01X38582Y77047D02*
X70866D01*
G01X38582Y75276D02*
X70866D01*
G01X40551Y113898D02*
X38582Y111929D01*
G01X38779Y114902D02*
Y113524D01*
G01Y114902D02*
X38582D01*
G01X68110D02*
X38779D01*
G01X38582Y113524D02*
X38779D01*
G01X68110D02*
X38779D01*
G01X38582Y111457D02*
X70866D01*
G01X38582Y107047D02*
X70866D01*
G01X38582Y105276D02*
X70866D01*
G01X38582Y102047D02*
X70866D01*
G01X38582Y100276D02*
X70866D01*
G01X38582Y97047D02*
X69685D01*
G01X38582Y95276D02*
X69685D01*
G01X38779Y132421D02*
Y133799D01*
G01Y129272D02*
Y130650D01*
G01Y122973D02*
Y124351D01*
G01Y126122D02*
Y127500D01*
G01Y119823D02*
Y121201D01*
G01Y116673D02*
Y118051D01*
G01X38582Y135866D02*
X70866D01*
G01X38779Y133799D02*
X68110D01*
G01X38779D02*
X38582D01*
G01X38779Y132421D02*
X68110D01*
G01X38582D02*
X38779D01*
G01Y130650D02*
X68110D01*
G01X38779D02*
X38582D01*
G01X38779Y129272D02*
X68110D01*
G01X38582D02*
X38779D01*
G01Y127500D02*
X68110D01*
G01X38779D02*
X38582D01*
G01X38779Y126122D02*
X68110D01*
G01X38582D02*
X38779D01*
G01Y124351D02*
X68110D01*
G01X38779D02*
X38582D01*
G01X38779Y122973D02*
X68110D01*
G01X38582D02*
X38779D01*
G01Y121201D02*
X68110D01*
G01X38779D02*
X38582D01*
G01X38779Y119823D02*
X68110D01*
G01X38582D02*
X38779D01*
G01Y118051D02*
X68110D01*
G01X38779D02*
X38582D01*
G01X38779Y116673D02*
X68110D01*
G01X38582D02*
X38779D01*
G01X40551Y133425D02*
X38582Y135394D01*
G01Y157047D02*
X70866D01*
G01X38582Y155276D02*
X70866D01*
G01X38582Y152047D02*
X70866D01*
G01X38582Y150276D02*
X70866D01*
G01X38582Y147047D02*
X70866D01*
G01X38582Y145276D02*
X70866D01*
G01X38582Y142047D02*
X70866D01*
G01X38582Y140276D02*
X70866D01*
G01X36610Y182141D02*
X31890Y177499D01*
G01Y178603D02*
X36614Y183248D01*
G01X40551Y174902D02*
X38582Y172933D01*
G01X36614Y174902D02*
Y182067D01*
G01X31890Y176870D02*
Y178603D01*
G01X35299Y174902D02*
X38582D01*
G01Y167047D02*
X70866D01*
G01X38582Y165276D02*
X70866D01*
G01X38582Y162047D02*
X70866D01*
G01X38582Y160276D02*
X70866D01*
G01X39764Y169980D02*
X38582Y171162D01*
G01X31890Y176870D02*
X35299Y174902D01*
G01X36569Y183201D02*
X36582Y183217D01*
G01X36557Y183183D02*
X36569Y183201D01*
G01X36547Y183162D02*
X36557Y183183D01*
G01X36538Y183137D02*
X36547Y183162D01*
G01X36531Y183110D02*
X36538Y183137D01*
G01X36525Y183080D02*
X36531Y183110D01*
G01X36521Y183047D02*
X36525Y183080D01*
G01X36518Y183011D02*
X36521Y183047D01*
G01X36516Y182973D02*
X36518Y183011D01*
G01X36516Y182932D02*
Y182973D01*
G01X36517Y182888D02*
X36516Y182932D01*
G01X36519Y182842D02*
X36517Y182888D01*
G01X36523Y182794D02*
X36519Y182842D01*
G01X36528Y182743D02*
X36523Y182794D01*
G01X36533Y182690D02*
X36528Y182743D01*
G01X36540Y182635D02*
X36533Y182690D01*
G01X36548Y182577D02*
X36540Y182635D01*
G01X36556Y182518D02*
X36548Y182577D01*
G01X36593Y182267D02*
X36556Y182518D01*
G01X36602Y182204D02*
X36593Y182267D01*
G01X36610Y182141D02*
X36602Y182204D01*
G01X36556Y182518D02*
X36565Y182457D01*
G01X36548Y182577D02*
X36556Y182518D01*
G01X36540Y182634D02*
X36548Y182577D01*
G01X36533Y182690D02*
X36540Y182634D01*
G01X36528Y182743D02*
X36533Y182690D01*
G01X36523Y182794D02*
X36528Y182743D01*
G01X36519Y182842D02*
X36523Y182794D01*
G01X36517Y182888D02*
X36519Y182842D01*
G01X36516Y182932D02*
X36517Y182888D01*
G01X36516Y182973D02*
Y182932D01*
G01X36518Y183011D02*
X36516Y182973D01*
G01X36569Y183201D02*
X36557Y183183D01*
G01X36584Y182331D02*
X36593Y182267D01*
G01X27953Y187185D02*
X55118D01*
G01X36614Y183248D02*
X90551D01*
G01X36614Y182067D02*
X70079D01*
G01X36516Y309567D02*
G03I-6989J0D01*
G01X26771Y731884D02*
Y338971D01*
G01X24803Y366530D02*
Y340939D01*
G01X22834Y366530D02*
Y340939D01*
G01X36548Y430258D02*
X36556Y430317D01*
G01X36540Y430200D02*
X36548Y430258D01*
G01X36533Y430145D02*
X36540Y430200D01*
G01X36528Y430092D02*
X36533Y430145D01*
G01X36523Y430041D02*
X36528Y430092D01*
G01X36519Y429992D02*
X36523Y430041D01*
G01X36517Y429946D02*
X36519Y429992D01*
G01X36516Y429903D02*
X36517Y429946D01*
G01X36516Y429862D02*
Y429903D01*
G01X36518Y429824D02*
X36516Y429862D01*
G01X36521Y429788D02*
X36518Y429824D01*
G01X36525Y429755D02*
X36521Y429788D01*
G01X36531Y429725D02*
X36525Y429755D01*
G01X36538Y429698D02*
X36531Y429725D01*
G01X36547Y429673D02*
X36538Y429698D01*
G01X36557Y429652D02*
X36547Y429673D01*
G01X36569Y429633D02*
X36557Y429652D01*
G01X36582Y429618D02*
X36569Y429633D01*
G01X36602Y430631D02*
X36610Y430694D01*
G01X36593Y430567D02*
X36602Y430631D01*
G01X36517Y429946D02*
X36516Y429903D01*
G01X36519Y429992D02*
X36517Y429946D01*
G01X36523Y430041D02*
X36519Y429992D01*
G01X36528Y430092D02*
X36523Y430041D01*
G01X36533Y430145D02*
X36528Y430092D01*
G01X36540Y430200D02*
X36533Y430145D01*
G01X36548Y430258D02*
X36540Y430200D01*
G01X36556Y430317D02*
X36548Y430258D01*
G01X19882Y413583D02*
G03Y421063I0J3740D01*
G01Y413583D02*
G03Y421063I0J3740D01*
G01X36556Y430317D02*
X36593Y430567D01*
G01X36575Y430440D02*
X36565Y430378D01*
G01X36614Y430768D02*
Y437933D01*
G01X27953Y592697D02*
Y425650D01*
G01X18701Y419569D02*
Y414829D01*
G01X70079Y430768D02*
X36614D01*
G01Y429587D02*
X90551D01*
G01X55118Y425650D02*
X27953D01*
G01X36518Y429823D02*
X36521Y429788D01*
G01X36547Y429673D02*
X36557Y429652D01*
G01X36569Y429633D02*
X36582Y429618D01*
G01X31890Y435336D02*
X36610Y430694D01*
G01X36614Y429587D02*
X31890Y434232D01*
G01X35299Y437933D02*
X31890Y435965D01*
G01X39764Y442854D02*
X38582Y441673D01*
G01Y437933D02*
Y580414D01*
G01X31890Y434232D02*
Y435965D01*
G01X38582Y452559D02*
X70866D01*
G01X38582Y450788D02*
X70866D01*
G01X38582Y447559D02*
X70866D01*
G01X38582Y445788D02*
X70866D01*
G01X35299Y437933D02*
X38582D01*
G01Y439902D02*
X40551Y437933D01*
G01X38582Y472559D02*
X70866D01*
G01X38582Y470788D02*
X70866D01*
G01X38582Y467559D02*
X70866D01*
G01X38582Y465788D02*
X70866D01*
G01X38582Y462559D02*
X69685D01*
G01X38582Y460788D02*
X69685D01*
G01X38582Y457559D02*
X70866D01*
G01X38582Y455788D02*
X70866D01*
G01X38582Y495788D02*
X70866D01*
G01X38582Y492559D02*
X70866D01*
G01X38582Y490788D02*
X70866D01*
G01X38582Y487559D02*
X70866D01*
G01X38582Y485788D02*
X70866D01*
G01X38582Y482559D02*
X70866D01*
G01X38582Y480788D02*
X70866D01*
G01X38582Y477559D02*
X70866D01*
G01X38582Y475788D02*
X70866D01*
G01X38582Y516969D02*
X70866D01*
G01X38582Y512559D02*
X70866D01*
G01X38582Y510788D02*
X70866D01*
G01X38582Y507559D02*
X70866D01*
G01X38582Y505788D02*
X70866D01*
G01X38582Y502559D02*
X69685D01*
G01X38582Y500788D02*
X69685D01*
G01X38582Y497559D02*
X70866D01*
G01X40551Y519410D02*
X38582Y517441D01*
G01X38779Y537933D02*
X68110D01*
G01X38582D02*
X38779D01*
G01Y536162D02*
X68110D01*
G01X38779D02*
X38582D01*
G01X38779Y534784D02*
X68110D01*
G01X38582D02*
X38779D01*
G01Y533012D02*
X68110D01*
G01X38779D02*
X38582D01*
G01X38779Y531634D02*
X68110D01*
G01X38582D02*
X38779D01*
G01Y529862D02*
X68110D01*
G01X38779D02*
X38582D01*
G01X38779Y528484D02*
X68110D01*
G01X38582D02*
X38779D01*
G01Y526713D02*
X68110D01*
G01X38779D02*
X38582D01*
G01X38779Y525335D02*
X68110D01*
G01X38582D02*
X38779D01*
G01Y523563D02*
X68110D01*
G01X38779D02*
X38582D01*
G01X38779Y522185D02*
X68110D01*
G01X38582D02*
X38779D01*
G01Y520414D02*
X38582D01*
G01X68110D02*
X38779D01*
G01X38582Y519036D02*
X38779D01*
G01X68110D02*
X38779D01*
G01Y534784D02*
Y536162D01*
G01Y537933D02*
Y539311D01*
G01Y531634D02*
Y533012D01*
G01Y525335D02*
Y526713D01*
G01Y528484D02*
Y529862D01*
G01Y522185D02*
Y523563D01*
G01Y520414D02*
Y519036D01*
G01X38582Y557559D02*
X70866D01*
G01X38582Y555788D02*
X70866D01*
G01X38582Y552559D02*
X70866D01*
G01X38582Y550788D02*
X70866D01*
G01X38582Y547559D02*
X70866D01*
G01X38582Y545788D02*
X70866D01*
G01X38582Y541378D02*
X70866D01*
G01X38779Y539311D02*
X68110D01*
G01X38779D02*
X38582D01*
G01X40551Y538937D02*
X38582Y540906D01*
G01X40551Y580414D02*
X38582Y578445D01*
G01X35299Y580414D02*
X38582D01*
G01Y572559D02*
X70866D01*
G01X38582Y570788D02*
X70866D01*
G01X38582Y567559D02*
X70866D01*
G01X38582Y565788D02*
X70866D01*
G01X38582Y562559D02*
X70866D01*
G01X38582Y560788D02*
X70866D01*
G01X36614Y580414D02*
Y587579D01*
G01X39764Y575492D02*
X38582Y576673D01*
G01X31890Y582382D02*
X35299Y580414D01*
G01X36569Y588713D02*
X36582Y588729D01*
G01X36557Y588695D02*
X36569Y588713D01*
G01X36547Y588673D02*
X36557Y588695D01*
G01X36538Y588649D02*
X36547Y588673D01*
G01X36531Y588622D02*
X36538Y588649D01*
G01X36525Y588591D02*
X36531Y588622D01*
G01X36521Y588559D02*
X36525Y588591D01*
G01X36518Y588523D02*
X36521Y588559D01*
G01X36516Y588485D02*
X36518Y588523D01*
G01X36516Y588444D02*
Y588485D01*
G01X36517Y588400D02*
X36516Y588444D01*
G01X36519Y588354D02*
X36517Y588400D01*
G01X36523Y588306D02*
X36519Y588354D01*
G01X36528Y588255D02*
X36523Y588306D01*
G01X36533Y588202D02*
X36528Y588255D01*
G01X36540Y588147D02*
X36533Y588202D01*
G01X36548Y588089D02*
X36540Y588147D01*
G01X36556Y588030D02*
X36548Y588089D01*
G01X36593Y587779D02*
X36556Y588030D01*
G01X36602Y587716D02*
X36593Y587779D01*
G01X36610Y587653D02*
X36602Y587716D01*
G01X36556Y588030D02*
X36565Y587969D01*
G01X36548Y588089D02*
X36556Y588030D01*
G01X36540Y588146D02*
X36548Y588089D01*
G01X36533Y588202D02*
X36540Y588146D01*
G01X36528Y588255D02*
X36533Y588202D01*
G01X36523Y588306D02*
X36528Y588255D01*
G01X36519Y588354D02*
X36523Y588306D01*
G01X36517Y588400D02*
X36519Y588354D01*
G01X36516Y588444D02*
X36517Y588400D01*
G01X36516Y588485D02*
Y588444D01*
G01X36518Y588523D02*
X36516Y588485D01*
G01X36610Y587653D02*
X31890Y583011D01*
G01Y584114D02*
X36614Y588760D01*
G01X36569Y588713D02*
X36557Y588695D01*
G01X27953Y592697D02*
X55118D01*
G01X36614Y588760D02*
X90551D01*
G01X36614Y587579D02*
X70079D01*
G01X31890Y582382D02*
Y584114D01*
G01X24803Y704325D02*
Y729916D01*
G01X22834D02*
Y704325D01*
G01X26771Y889378D02*
Y748433D01*
G01X24803Y775992D02*
Y750402D01*
G01X22852Y775992D02*
Y750402D01*
G01X19882Y823032D02*
G03Y830512I0J3740D01*
G01Y823032D02*
G03Y830512I0J3740D01*
G01X55118Y831162D02*
X27953D01*
G01Y998209D02*
Y831162D01*
G01X18701Y829160D02*
Y824420D01*
G01X36602Y836143D02*
X36610Y836206D01*
G01X36593Y836079D02*
X36602Y836143D01*
G01X36517Y835458D02*
X36516Y835415D01*
G01X36519Y835504D02*
X36517Y835458D01*
G01X36523Y835553D02*
X36519Y835504D01*
G01X36528Y835604D02*
X36523Y835553D01*
G01X36533Y835657D02*
X36528Y835604D01*
G01X36540Y835712D02*
X36533Y835657D01*
G01X36548Y835769D02*
X36540Y835712D01*
G01X36556Y835829D02*
X36548Y835769D01*
G01D02*
X36556Y835829D01*
G01X36540Y835712D02*
X36548Y835769D01*
G01X36533Y835657D02*
X36540Y835712D01*
G01X36528Y835604D02*
X36533Y835657D01*
G01X36523Y835553D02*
X36528Y835604D01*
G01X36519Y835504D02*
X36523Y835553D01*
G01X36517Y835458D02*
X36519Y835504D01*
G01X36516Y835415D02*
X36517Y835458D01*
G01X36516Y835374D02*
Y835415D01*
G01X36518Y835336D02*
X36516Y835374D01*
G01X36521Y835300D02*
X36518Y835336D01*
G01X36525Y835267D02*
X36521Y835300D01*
G01X36531Y835237D02*
X36525Y835267D01*
G01X36538Y835210D02*
X36531Y835237D01*
G01X36547Y835185D02*
X36538Y835210D01*
G01X36557Y835164D02*
X36547Y835185D01*
G01X36569Y835145D02*
X36557Y835164D01*
G01X36582Y835130D02*
X36569Y835145D01*
G01X35299Y843445D02*
X31890Y841477D01*
G01X38582Y853071D02*
X70866D01*
G01X38582Y851299D02*
X70866D01*
G01X35299Y843445D02*
X38582D01*
G01X70079Y836280D02*
X36614D01*
G01Y835099D02*
X90551D01*
G01X39764Y848366D02*
X38582Y847185D01*
G01X36547Y835185D02*
X36557Y835164D01*
G01X36569Y835145D02*
X36582Y835130D01*
G01X38582Y845414D02*
X40551Y843445D01*
G01X31890Y840847D02*
X36610Y836206D01*
G01X36614Y835099D02*
X31890Y839744D01*
G01X36556Y835829D02*
X36593Y836079D01*
G01X38582Y843445D02*
Y985925D01*
G01X36614Y836280D02*
Y843445D01*
G01X31890Y839744D02*
Y841477D01*
G01X36518Y835335D02*
X36521Y835300D01*
G01X38582Y876299D02*
X70866D01*
G01X38582Y873071D02*
X70866D01*
G01X38582Y871299D02*
X70866D01*
G01X38582Y868071D02*
X69685D01*
G01X38582Y866299D02*
X69685D01*
G01X38582Y863071D02*
X70866D01*
G01X38582Y861299D02*
X70866D01*
G01X38582Y858071D02*
X70866D01*
G01X38582Y856299D02*
X70866D01*
G01X24803Y887410D02*
Y861819D01*
G01X22852Y887410D02*
Y861819D01*
G01X38582Y898071D02*
X70866D01*
G01X38582Y896299D02*
X70866D01*
G01X38582Y893071D02*
X70866D01*
G01X38582Y891299D02*
X70866D01*
G01X38582Y888071D02*
X70866D01*
G01X38582Y886299D02*
X70866D01*
G01X38582Y883071D02*
X70866D01*
G01X38582Y881299D02*
X70866D01*
G01X38582Y878071D02*
X70866D01*
G01X38582Y918071D02*
X70866D01*
G01X38582Y916299D02*
X70866D01*
G01X38582Y913071D02*
X70866D01*
G01X38582Y911299D02*
X70866D01*
G01X38582Y908071D02*
X69685D01*
G01X38582Y906299D02*
X69685D01*
G01X38582Y903071D02*
X70866D01*
G01X38582Y901299D02*
X70866D01*
G01X38779Y940295D02*
X68110D01*
G01X38582D02*
X38779D01*
G01Y938524D02*
X68110D01*
G01X38779D02*
X38582D01*
G01X38779Y937146D02*
X68110D01*
G01X38582D02*
X38779D01*
G01Y935374D02*
X68110D01*
G01X38779D02*
X38582D01*
G01X38779Y933996D02*
X68110D01*
G01X38582D02*
X38779D01*
G01Y932225D02*
X68110D01*
G01X38779D02*
X38582D01*
G01X38779Y930847D02*
X68110D01*
G01X38582D02*
X38779D01*
G01Y929075D02*
X68110D01*
G01X38779D02*
X38582D01*
G01X38779Y927697D02*
X68110D01*
G01X38582D02*
X38779D01*
G01Y925925D02*
X38582D01*
G01X68110D02*
X38779D01*
G01X38582Y924547D02*
X38779D01*
G01X68110D02*
X38779D01*
G01X38582Y922480D02*
X70866D01*
G01X40551Y924921D02*
X38582Y922953D01*
G01X38779Y937146D02*
Y938524D01*
G01Y940295D02*
Y941673D01*
G01Y933996D02*
Y935374D01*
G01Y927697D02*
Y929075D01*
G01Y930847D02*
Y932225D01*
G01Y925925D02*
Y924547D01*
G01X38582Y961299D02*
X70866D01*
G01X38582Y958071D02*
X70866D01*
G01X38582Y956299D02*
X70866D01*
G01X38582Y953071D02*
X70866D01*
G01X38582Y951299D02*
X70866D01*
G01X38582Y946890D02*
X70866D01*
G01X38779Y944823D02*
X68110D01*
G01X38779D02*
X38582D01*
G01X38779Y943445D02*
X68110D01*
G01X38582D02*
X38779D01*
G01Y941673D02*
X68110D01*
G01X38779D02*
X38582D01*
G01X40551Y944449D02*
X38582Y946417D01*
G01X38779Y943445D02*
Y944823D01*
G01X38582Y978071D02*
X70866D01*
G01X38582Y976299D02*
X70866D01*
G01X38582Y973071D02*
X70866D01*
G01X38582Y971299D02*
X70866D01*
G01X38582Y968071D02*
X70866D01*
G01X38582Y966299D02*
X70866D01*
G01X38582Y963071D02*
X70866D01*
G01X39764Y981004D02*
X38582Y982185D01*
G01X36569Y994225D02*
X36582Y994241D01*
G01X36557Y994207D02*
X36569Y994225D01*
G01X36547Y994185D02*
X36557Y994207D01*
G01X36538Y994161D02*
X36547Y994185D01*
G01X36531Y994134D02*
X36538Y994161D01*
G01X36525Y994103D02*
X36531Y994134D01*
G01X36521Y994071D02*
X36525Y994103D01*
G01X36518Y994035D02*
X36521Y994071D01*
G01X36516Y993997D02*
X36518Y994035D01*
G01X36516Y993956D02*
Y993997D01*
G01X36517Y993912D02*
X36516Y993956D01*
G01X36519Y993866D02*
X36517Y993912D01*
G01X36523Y993817D02*
X36519Y993866D01*
G01X36528Y993767D02*
X36523Y993817D01*
G01X36533Y993714D02*
X36528Y993767D01*
G01X36540Y993658D02*
X36533Y993714D01*
G01X36548Y993601D02*
X36540Y993658D01*
G01X36556Y993541D02*
X36548Y993601D01*
G01X36593Y993291D02*
X36556Y993541D01*
G01X36602Y993227D02*
X36593Y993291D01*
G01X36610Y993164D02*
X36602Y993227D01*
G01X27953Y998209D02*
X55118D01*
G01X36614Y994272D02*
X90551D01*
G01X36614Y993091D02*
X70079D01*
G01X35299Y985925D02*
X38582D01*
G01X31890Y987894D02*
X35299Y985925D01*
G01X36610Y993164D02*
X31890Y988523D01*
G01Y989626D02*
X36614Y994272D01*
G01X40551Y985925D02*
X38582Y983957D01*
G01X36569Y994225D02*
X36557Y994206D01*
G01X36518Y994035D02*
X36516Y993997D01*
G01X36614Y985925D02*
Y993091D01*
G01X31890Y987894D02*
Y989626D01*
G01X36516Y1029528D02*
G03I-6989J0D01*
G01X36602Y1241655D02*
X36610Y1241718D01*
G01X36593Y1241591D02*
X36602Y1241655D01*
G01X36517Y1240970D02*
X36516Y1240927D01*
G01X36519Y1241016D02*
X36517Y1240970D01*
G01X36523Y1241064D02*
X36519Y1241016D01*
G01X36528Y1241116D02*
X36523Y1241064D01*
G01X36533Y1241169D02*
X36528Y1241116D01*
G01X36540Y1241224D02*
X36533Y1241169D01*
G01X36548Y1241281D02*
X36540Y1241224D01*
G01X36556Y1241341D02*
X36548Y1241281D01*
G01D02*
X36556Y1241341D01*
G01X36540Y1241224D02*
X36548Y1241281D01*
G01X36533Y1241169D02*
X36540Y1241224D01*
G01X36528Y1241116D02*
X36533Y1241169D01*
G01X36523Y1241065D02*
X36528Y1241116D01*
G01X36519Y1241016D02*
X36523Y1241065D01*
G01X36517Y1240970D02*
X36519Y1241016D01*
G01X36516Y1240927D02*
X36517Y1240970D01*
G01X36516Y1240886D02*
Y1240927D01*
G01X36518Y1240847D02*
X36516Y1240886D01*
G01X36521Y1240812D02*
X36518Y1240847D01*
G01X36525Y1240778D02*
X36521Y1240812D01*
G01X36531Y1240749D02*
X36525Y1240778D01*
G01X36538Y1240721D02*
X36531Y1240749D01*
G01X36547Y1240697D02*
X36538Y1240721D01*
G01X36557Y1240675D02*
X36547Y1240697D01*
G01X36569Y1240657D02*
X36557Y1240675D01*
G01X36582Y1240641D02*
X36569Y1240657D01*
G01X38582Y1256811D02*
X70866D01*
G01X35299Y1248957D02*
X38582D01*
G01X70079Y1241791D02*
X36614D01*
G01Y1240610D02*
X90551D01*
G01X55118Y1236673D02*
X27953D01*
G01X36569Y1240657D02*
X36582Y1240641D01*
G01X38582Y1250925D02*
X40551Y1248957D01*
G01X31890Y1246359D02*
X36610Y1241718D01*
G01X36614Y1240610D02*
X31890Y1245256D01*
G01X36547Y1240697D02*
X36557Y1240675D01*
G01X35299Y1248957D02*
X31890Y1246988D01*
G01X39764Y1253878D02*
X38582Y1252697D01*
G01X36556Y1241341D02*
X36593Y1241591D01*
G01X38582Y1248957D02*
Y1391437D01*
G01X36614Y1241791D02*
Y1248957D01*
G01X31890Y1245256D02*
Y1246988D01*
G01X27953Y1403721D02*
Y1236673D01*
G01X36518Y1240847D02*
X36521Y1240812D01*
G01X38582Y1278583D02*
X70866D01*
G01X38582Y1276811D02*
X70866D01*
G01X38582Y1273583D02*
X69685D01*
G01X38582Y1271811D02*
X69685D01*
G01X38582Y1268583D02*
X70866D01*
G01X38582Y1266811D02*
X70866D01*
G01X38582Y1263583D02*
X70866D01*
G01X38582Y1261811D02*
X70866D01*
G01X38582Y1258583D02*
X70866D01*
G01X38582Y1298583D02*
X70866D01*
G01X38582Y1296811D02*
X70866D01*
G01X38582Y1293583D02*
X70866D01*
G01X38582Y1291811D02*
X70866D01*
G01X38582Y1288583D02*
X70866D01*
G01X38582Y1286811D02*
X70866D01*
G01X38582Y1283583D02*
X70866D01*
G01X38582Y1281811D02*
X70866D01*
G01X38582Y1318583D02*
X70866D01*
G01X38582Y1316811D02*
X70866D01*
G01X38582Y1313583D02*
X69685D01*
G01X38582Y1311811D02*
X69685D01*
G01X38582Y1308583D02*
X70866D01*
G01X38582Y1306811D02*
X70866D01*
G01X38582Y1303583D02*
X70866D01*
G01X38582Y1301811D02*
X70866D01*
G01X38779Y1340886D02*
X68110D01*
G01X38779D02*
X38582D01*
G01X38779Y1339508D02*
X68110D01*
G01X38582D02*
X38779D01*
G01Y1337736D02*
X68110D01*
G01X38779D02*
X38582D01*
G01X38779Y1336358D02*
X68110D01*
G01X38582D02*
X38779D01*
G01Y1334587D02*
X68110D01*
G01X38779D02*
X38582D01*
G01X38779Y1333209D02*
X68110D01*
G01X38582D02*
X38779D01*
G01Y1331437D02*
X38582D01*
G01X68110D02*
X38779D01*
G01X38582Y1330059D02*
X38779D01*
G01X68110D02*
X38779D01*
G01X38582Y1327992D02*
X70866D01*
G01X38582Y1323583D02*
X70866D01*
G01X38582Y1321811D02*
X70866D01*
G01X38779Y1339508D02*
Y1340886D01*
G01Y1336358D02*
Y1337736D01*
G01Y1333209D02*
Y1334587D01*
G01Y1331437D02*
Y1330059D01*
G01X26771Y1716136D02*
Y1323223D01*
G01X24803Y1350782D02*
Y1325191D01*
G01X22834Y1350782D02*
Y1325191D01*
G01X40551Y1330433D02*
X38582Y1328465D01*
G01Y1361811D02*
X70866D01*
G01X38582Y1358583D02*
X70866D01*
G01X38582Y1356811D02*
X70866D01*
G01X38582Y1352402D02*
X70866D01*
G01X38779Y1350335D02*
X68110D01*
G01X38779D02*
X38582D01*
G01X38779Y1348957D02*
X68110D01*
G01X38582D02*
X38779D01*
G01Y1347185D02*
X68110D01*
G01X38779D02*
X38582D01*
G01X38779Y1345807D02*
X68110D01*
G01X38582D02*
X38779D01*
G01Y1344036D02*
X68110D01*
G01X38779D02*
X38582D01*
G01X38779Y1342658D02*
X68110D01*
G01X38582D02*
X38779D01*
G01X40551Y1349961D02*
X38582Y1351929D01*
G01X38779Y1348957D02*
Y1350335D01*
G01Y1345807D02*
Y1347185D01*
G01Y1342658D02*
Y1344036D01*
G01X38582Y1383583D02*
X70866D01*
G01X38582Y1381811D02*
X70866D01*
G01X38582Y1378583D02*
X70866D01*
G01X38582Y1376811D02*
X70866D01*
G01X38582Y1373583D02*
X70866D01*
G01X38582Y1371811D02*
X70866D01*
G01X38582Y1368583D02*
X70866D01*
G01X38582Y1366811D02*
X70866D01*
G01X38582Y1363583D02*
X70866D01*
G01X36548Y1399112D02*
X36556Y1399053D01*
G01X36540Y1399170D02*
X36548Y1399112D01*
G01X36533Y1399225D02*
X36540Y1399170D01*
G01X36528Y1399278D02*
X36533Y1399225D01*
G01X36523Y1399329D02*
X36528Y1399278D01*
G01X36519Y1399378D02*
X36523Y1399329D01*
G01X36517Y1399424D02*
X36519Y1399378D01*
G01X36516Y1399467D02*
X36517Y1399424D01*
G01X36516Y1399508D02*
Y1399467D01*
G01X36518Y1399547D02*
X36516Y1399508D01*
G01X36569Y1399737D02*
X36582Y1399753D01*
G01X36557Y1399719D02*
X36569Y1399737D01*
G01X36547Y1399697D02*
X36557Y1399719D01*
G01X36538Y1399673D02*
X36547Y1399697D01*
G01X36531Y1399645D02*
X36538Y1399673D01*
G01X36525Y1399615D02*
X36531Y1399645D01*
G01X36521Y1399582D02*
X36525Y1399615D01*
G01X36518Y1399547D02*
X36521Y1399582D01*
G01X36516Y1399508D02*
X36518Y1399547D01*
G01X36516Y1399467D02*
Y1399508D01*
G01X36517Y1399424D02*
X36516Y1399467D01*
G01X36519Y1399378D02*
X36517Y1399424D01*
G01X36523Y1399329D02*
X36519Y1399378D01*
G01X36528Y1399278D02*
X36523Y1399329D01*
G01X36533Y1399225D02*
X36528Y1399278D01*
G01X36540Y1399170D02*
X36533Y1399225D01*
G01X36548Y1399113D02*
X36540Y1399170D01*
G01X36556Y1399053D02*
X36548Y1399113D01*
G01X36593Y1398803D02*
X36556Y1399053D01*
G01X36602Y1398739D02*
X36593Y1398803D01*
G01X36610Y1398676D02*
X36602Y1398739D01*
G01X19882Y1397835D02*
G03Y1405315I0J3740D01*
G01Y1397835D02*
G03Y1405315I0J3740D01*
G01X27953Y1403721D02*
X55118D01*
G01X36614Y1399784D02*
X90551D01*
G01X36614Y1398603D02*
X70079D01*
G01X35299Y1391437D02*
X38582D01*
G01X31890Y1393406D02*
X35299Y1391437D01*
G01X39764Y1386516D02*
X38582Y1387697D01*
G01X36614Y1391437D02*
Y1398603D01*
G01X31890Y1393406D02*
Y1395138D01*
G01X18701Y1403821D02*
Y1399081D01*
G01X36610Y1398676D02*
X31890Y1394034D01*
G01Y1395138D02*
X36614Y1399784D01*
G01X40551Y1391437D02*
X38582Y1389469D01*
G01X36569Y1399737D02*
X36557Y1399718D01*
G01X36602Y1647167D02*
X36610Y1647230D01*
G01X36593Y1647103D02*
X36602Y1647167D01*
G01X36517Y1646482D02*
X36516Y1646438D01*
G01X36519Y1646528D02*
X36517Y1646482D01*
G01X36523Y1646576D02*
X36519Y1646528D01*
G01X36528Y1646627D02*
X36523Y1646576D01*
G01X36533Y1646680D02*
X36528Y1646627D01*
G01X36540Y1646736D02*
X36533Y1646680D01*
G01X36548Y1646793D02*
X36540Y1646736D01*
G01X36556Y1646853D02*
X36548Y1646793D01*
G01D02*
X36556Y1646853D01*
G01X36540Y1646736D02*
X36548Y1646793D01*
G01X36533Y1646680D02*
X36540Y1646736D01*
G01X36528Y1646627D02*
X36533Y1646680D01*
G01X36523Y1646577D02*
X36528Y1646627D01*
G01X36519Y1646528D02*
X36523Y1646577D01*
G01X36517Y1646482D02*
X36519Y1646528D01*
G01X36516Y1646438D02*
X36517Y1646482D01*
G01X36516Y1646397D02*
Y1646438D01*
G01X36518Y1646359D02*
X36516Y1646397D01*
G01X36521Y1646323D02*
X36518Y1646359D01*
G01X36525Y1646290D02*
X36521Y1646323D01*
G01X36531Y1646260D02*
X36525Y1646290D01*
G01X36538Y1646233D02*
X36531Y1646260D01*
G01X36547Y1646209D02*
X36538Y1646233D01*
G01X36557Y1646187D02*
X36547Y1646209D01*
G01X36569Y1646169D02*
X36557Y1646187D01*
G01X36582Y1646153D02*
X36569Y1646169D01*
G01X35299Y1654469D02*
X38582D01*
G01X70079Y1647303D02*
X36614D01*
G01Y1646122D02*
X90551D01*
G01X55118Y1642185D02*
X27953D01*
G01X38582Y1656437D02*
X40551Y1654469D01*
G01X31890Y1651871D02*
X36610Y1647230D01*
G01X36614Y1646122D02*
X31890Y1650768D01*
G01X36569Y1646169D02*
X36582Y1646153D01*
G01X36547Y1646208D02*
X36557Y1646187D01*
G01X36518Y1646359D02*
X36521Y1646323D01*
G01X38582Y1654469D02*
Y1796949D01*
G01X36614Y1647303D02*
Y1654469D01*
G01X31890Y1650768D02*
Y1652500D01*
G01X27953Y1809232D02*
Y1642185D01*
G01X36556Y1646853D02*
X36593Y1647103D01*
G01X35299Y1654469D02*
X31890Y1652500D01*
G01X39764Y1659390D02*
X38582Y1658209D01*
G01Y1679095D02*
X69685D01*
G01X38582Y1677323D02*
X69685D01*
G01X38582Y1674095D02*
X70866D01*
G01X38582Y1672323D02*
X70866D01*
G01X38582Y1669095D02*
X70866D01*
G01X38582Y1667323D02*
X70866D01*
G01X38582Y1664095D02*
X70866D01*
G01X38582Y1662323D02*
X70866D01*
G01X38582Y1699095D02*
X70866D01*
G01X38582Y1697323D02*
X70866D01*
G01X38582Y1694095D02*
X70866D01*
G01X38582Y1692323D02*
X70866D01*
G01X38582Y1689095D02*
X70866D01*
G01X38582Y1687323D02*
X70866D01*
G01X38582Y1684095D02*
X70866D01*
G01X38582Y1682323D02*
X70866D01*
G01X24803Y1688577D02*
Y1714167D01*
G01X22834D02*
Y1688577D01*
G01X38582Y1722323D02*
X70866D01*
G01X38582Y1719095D02*
X69685D01*
G01X38582Y1717323D02*
X69685D01*
G01X38582Y1714095D02*
X70866D01*
G01X38582Y1712323D02*
X70866D01*
G01X38582Y1709095D02*
X70866D01*
G01X38582Y1707323D02*
X70866D01*
G01X38582Y1704095D02*
X70866D01*
G01X38582Y1702323D02*
X70866D01*
G01X38779Y1743248D02*
X68110D01*
G01X38779D02*
X38582D01*
G01X38779Y1741870D02*
X68110D01*
G01X38582D02*
X38779D01*
G01Y1740099D02*
X68110D01*
G01X38779D02*
X38582D01*
G01X38779Y1738721D02*
X68110D01*
G01X38582D02*
X38779D01*
G01Y1736949D02*
X38582D01*
G01X68110D02*
X38779D01*
G01X38582Y1735571D02*
X38779D01*
G01X68110D02*
X38779D01*
G01X38582Y1733504D02*
X70866D01*
G01X38582Y1729095D02*
X70866D01*
G01X38582Y1727323D02*
X70866D01*
G01X38582Y1724095D02*
X70866D01*
G01X38779Y1741870D02*
Y1743248D01*
G01Y1738721D02*
Y1740099D01*
G01Y1736949D02*
Y1735571D01*
G01X26771Y1873630D02*
Y1732685D01*
G01X24803Y1760244D02*
Y1734654D01*
G01X22852Y1760244D02*
Y1734654D01*
G01X40551Y1735945D02*
X38582Y1733977D01*
G01Y1764095D02*
X70866D01*
G01X38582Y1762323D02*
X70866D01*
G01X38582Y1757914D02*
X70866D01*
G01X38779Y1755847D02*
X68110D01*
G01X38779D02*
X38582D01*
G01X38779Y1754469D02*
X68110D01*
G01X38582D02*
X38779D01*
G01Y1752697D02*
X68110D01*
G01X38779D02*
X38582D01*
G01X38779Y1751319D02*
X68110D01*
G01X38582D02*
X38779D01*
G01Y1749547D02*
X68110D01*
G01X38779D02*
X38582D01*
G01X38779Y1748169D02*
X68110D01*
G01X38582D02*
X38779D01*
G01Y1746398D02*
X68110D01*
G01X38779D02*
X38582D01*
G01X38779Y1745020D02*
X68110D01*
G01X38582D02*
X38779D01*
G01X40551Y1755473D02*
X38582Y1757441D01*
G01X38779Y1751319D02*
Y1752697D01*
G01Y1754469D02*
Y1755847D01*
G01Y1748169D02*
Y1749547D01*
G01Y1745020D02*
Y1746398D01*
G01X38582Y1784095D02*
X70866D01*
G01X38582Y1782323D02*
X70866D01*
G01X38582Y1779095D02*
X70866D01*
G01X38582Y1777323D02*
X70866D01*
G01X38582Y1774095D02*
X70866D01*
G01X38582Y1772323D02*
X70866D01*
G01X38582Y1769095D02*
X70866D01*
G01X38582Y1767323D02*
X70866D01*
G01X36556Y1804565D02*
X36584Y1804378D01*
G01X36548Y1804624D02*
X36556Y1804565D01*
G01X36540Y1804682D02*
X36548Y1804624D01*
G01X36533Y1804737D02*
X36540Y1804682D01*
G01X36528Y1804790D02*
X36533Y1804737D01*
G01X36523Y1804841D02*
X36528Y1804790D01*
G01X36519Y1804890D02*
X36523Y1804841D01*
G01X36517Y1804936D02*
X36519Y1804890D01*
G01X36516Y1804979D02*
X36517Y1804936D01*
G01X36516Y1805020D02*
Y1804979D01*
G01X36518Y1805058D02*
X36516Y1805020D01*
G01X36593Y1804315D02*
X36556Y1804565D01*
G01X36602Y1804251D02*
X36593Y1804315D01*
G01X36610Y1804188D02*
X36602Y1804251D01*
G01X36569Y1805249D02*
X36582Y1805264D01*
G01X36557Y1805230D02*
X36569Y1805249D01*
G01X36547Y1805209D02*
X36557Y1805230D01*
G01X36538Y1805184D02*
X36547Y1805209D01*
G01X36531Y1805157D02*
X36538Y1805184D01*
G01X36525Y1805127D02*
X36531Y1805157D01*
G01X36521Y1805094D02*
X36525Y1805127D01*
G01X36518Y1805058D02*
X36521Y1805094D01*
G01X36516Y1805020D02*
X36518Y1805058D01*
G01X36516Y1804979D02*
Y1805020D01*
G01X36517Y1804936D02*
X36516Y1804979D01*
G01X36519Y1804890D02*
X36517Y1804936D01*
G01X36523Y1804841D02*
X36519Y1804890D01*
G01X36528Y1804790D02*
X36523Y1804841D01*
G01X36533Y1804737D02*
X36528Y1804790D01*
G01X36540Y1804682D02*
X36533Y1804737D01*
G01X36548Y1804625D02*
X36540Y1804682D01*
G01X36556Y1804565D02*
X36548Y1804625D01*
G01X19882Y1807284D02*
G03Y1814764I0J3740D01*
G01Y1807284D02*
G03Y1814764I0J3740D01*
G01X36614Y1805295D02*
X90551D01*
G01X36614Y1804114D02*
X70079D01*
G01X35299Y1796949D02*
X38582D01*
G01Y1789095D02*
X70866D01*
G01X38582Y1787323D02*
X70866D01*
G01X31890Y1798917D02*
X35299Y1796949D01*
G01X39764Y1792028D02*
X38582Y1793209D01*
G01X36584Y1804378D02*
X36593Y1804315D01*
G01X36614Y1796949D02*
Y1804114D01*
G01X31890Y1798917D02*
Y1800650D01*
G01X36569Y1805249D02*
X36557Y1805230D01*
G01X36610Y1804188D02*
X31890Y1799546D01*
G01Y1800650D02*
X36614Y1805295D01*
G01X40551Y1796949D02*
X38582Y1794980D01*
G01X27953Y1809232D02*
X55118D01*
G01X18701Y1813412D02*
Y1808672D01*
G01X24803Y1871662D02*
Y1846071D01*
G01X22852Y1871662D02*
Y1846071D01*
G01X27172Y2126667D02*
Y2107730D01*
G01X55118Y7185D02*
Y20138D01*
G01X82677Y7185D02*
X55118D01*
G01X59252Y17835D02*
Y16260D01*
G01X59055Y24075D02*
Y183248D01*
G01Y11122D02*
Y24075D01*
G01Y29469D02*
X70079D01*
G01X59055Y22106D02*
X78740D01*
G01Y19016D02*
X59055D01*
G01Y18032D02*
X78740D01*
G01X59252Y17835D02*
X78543D01*
G01X59252Y16260D02*
X78543D01*
G01X78740Y16063D02*
X59055D01*
G01Y15079D02*
X78740D01*
G01X59055Y13091D02*
X78740D01*
G01X59055Y11122D02*
X78740D01*
G01X46553Y41949D02*
Y40374D01*
G01Y46949D02*
Y45374D01*
G01Y51949D02*
Y50374D01*
G01X45447Y41949D02*
Y40374D01*
G01Y46949D02*
Y45374D01*
G01Y51949D02*
Y50374D01*
G01X45201Y41949D02*
Y40374D01*
G01Y46949D02*
Y45374D01*
G01Y51949D02*
Y50374D01*
G01X41535Y42047D02*
Y40276D01*
G01Y47047D02*
Y45276D01*
G01Y52047D02*
Y50276D01*
G01X41026Y50374D02*
Y51949D01*
G01Y45374D02*
Y46949D01*
G01Y40374D02*
Y41949D01*
G01X40344D02*
Y40374D01*
G01Y46949D02*
Y45374D01*
G01Y51949D02*
Y50374D01*
G01X39764Y37343D02*
Y169980D01*
G01X40344Y51949D02*
X70866D01*
G01X40344Y50374D02*
X70866D01*
G01X40344Y46949D02*
X70866D01*
G01X40344Y45374D02*
X70866D01*
G01X40344Y41949D02*
X70866D01*
G01X40344Y40374D02*
X70866D01*
G01X39764Y37343D02*
X68208D01*
G01X40551Y32421D02*
X90551D01*
G01X46553Y56949D02*
Y55374D01*
G01Y61949D02*
Y60374D01*
G01Y66949D02*
Y65374D01*
G01Y71949D02*
Y70374D01*
G01X45447Y56949D02*
Y55374D01*
G01Y61949D02*
Y60374D01*
G01Y66949D02*
Y65374D01*
G01Y71949D02*
Y70374D01*
G01X45201Y56949D02*
Y55374D01*
G01Y61949D02*
Y60374D01*
G01Y66949D02*
Y65374D01*
G01Y71949D02*
Y70374D01*
G01X41535Y57047D02*
Y55276D01*
G01Y62047D02*
Y60276D01*
G01Y67047D02*
Y65276D01*
G01Y72047D02*
Y70276D01*
G01X41026Y70374D02*
Y71949D01*
G01Y65374D02*
Y66949D01*
G01Y60374D02*
Y61949D01*
G01Y55374D02*
Y56949D01*
G01X40344D02*
Y55374D01*
G01Y61949D02*
Y60374D01*
G01Y66949D02*
Y65374D01*
G01Y71949D02*
Y70374D01*
G01Y71949D02*
X70866D01*
G01X40344Y70374D02*
X70866D01*
G01X40344Y66949D02*
X70866D01*
G01X40344Y65374D02*
X70866D01*
G01X40344Y61949D02*
X70866D01*
G01X40344Y60374D02*
X70866D01*
G01X40344Y56949D02*
X69685D01*
G01X40344Y55374D02*
X69685D01*
G01X46553Y76949D02*
Y75374D01*
G01Y81949D02*
Y80374D01*
G01Y86949D02*
Y85374D01*
G01Y91949D02*
Y90374D01*
G01X45447Y76949D02*
Y75374D01*
G01Y81949D02*
Y80374D01*
G01Y86949D02*
Y85374D01*
G01Y91949D02*
Y90374D01*
G01X45201Y76949D02*
Y75374D01*
G01Y81949D02*
Y80374D01*
G01Y86949D02*
Y85374D01*
G01Y91949D02*
Y90374D01*
G01X41535Y77047D02*
Y75276D01*
G01Y82047D02*
Y80276D01*
G01Y87047D02*
Y85276D01*
G01Y92047D02*
Y90276D01*
G01X41026Y90374D02*
Y91949D01*
G01Y85374D02*
Y86949D01*
G01Y80374D02*
Y81949D01*
G01Y75374D02*
Y76949D01*
G01X40344D02*
Y75374D01*
G01Y81949D02*
Y80374D01*
G01Y86949D02*
Y85374D01*
G01Y91949D02*
Y90374D01*
G01Y91949D02*
X70866D01*
G01X40344Y90374D02*
X70866D01*
G01X40344Y86949D02*
X70866D01*
G01X40344Y85374D02*
X70866D01*
G01X40344Y81949D02*
X70866D01*
G01X40344Y80374D02*
X70866D01*
G01X40344Y76949D02*
X70866D01*
G01X40344Y75374D02*
X70866D01*
G01X51039Y113622D02*
Y114803D01*
G01X48800D02*
Y113622D01*
G01X48302D02*
Y114803D01*
G01X47559Y113524D02*
Y114902D01*
G01X46553Y96949D02*
Y95374D01*
G01Y101949D02*
Y100374D01*
G01Y106949D02*
Y105374D01*
G01Y111949D02*
Y110374D01*
G01X45447Y96949D02*
Y95374D01*
G01Y101949D02*
Y100374D01*
G01Y106949D02*
Y105374D01*
G01Y111949D02*
Y110374D01*
G01X45201D02*
Y111949D01*
G01Y96949D02*
Y95374D01*
G01Y101949D02*
Y100374D01*
G01Y106949D02*
Y105374D01*
G01X42743Y114803D02*
Y113622D01*
G01X42006D02*
Y114803D01*
G01X41535Y97047D02*
Y95276D01*
G01Y102047D02*
Y100276D01*
G01Y107047D02*
Y105276D01*
G01Y112047D02*
Y110276D01*
G01X41453Y110374D02*
Y111949D01*
G01X41026Y105374D02*
Y106949D01*
G01Y100374D02*
Y101949D01*
G01Y95374D02*
Y96949D01*
G01X40551Y111457D02*
Y135866D01*
G01X40465Y111949D02*
Y110374D01*
G01X40344Y96949D02*
Y95374D01*
G01Y101949D02*
Y100374D01*
G01Y106949D02*
Y105374D01*
G01X42006Y114803D02*
X68110D01*
G01X59055Y113898D02*
X40551D01*
G01X68110Y113622D02*
X42006D01*
G01X70866Y112047D02*
X41535D01*
G01X40465Y111949D02*
X70866D01*
G01X40465Y110374D02*
X70866D01*
G01X41535Y110276D02*
X70866D01*
G01X40344Y106949D02*
X70866D01*
G01X40344Y105374D02*
X70866D01*
G01X40344Y101949D02*
X70866D01*
G01X40344Y100374D02*
X70866D01*
G01X40344Y96949D02*
X69685D01*
G01X40344Y95374D02*
X69685D01*
G01X51039Y132520D02*
Y133701D01*
G01Y129370D02*
Y130551D01*
G01Y126221D02*
Y127402D01*
G01Y123071D02*
Y124252D01*
G01Y119921D02*
Y121103D01*
G01Y116772D02*
Y117953D01*
G01X48800D02*
Y116772D01*
G01Y121103D02*
Y119921D01*
G01Y124252D02*
Y123071D01*
G01Y127402D02*
Y126221D01*
G01Y130551D02*
Y129370D01*
G01Y133701D02*
Y132520D01*
G01X48302D02*
Y133701D01*
G01Y129370D02*
Y130551D01*
G01Y126221D02*
Y127402D01*
G01Y123071D02*
Y124252D01*
G01Y119921D02*
Y121103D01*
G01Y116772D02*
Y117953D01*
G01X47559Y132421D02*
Y133799D01*
G01Y118051D02*
Y116673D01*
G01Y121201D02*
Y119823D01*
G01Y127500D02*
Y126122D01*
G01Y124351D02*
Y122973D01*
G01Y130650D02*
Y129272D01*
G01X46553Y136949D02*
Y135374D01*
G01X45447Y136949D02*
Y135374D01*
G01X45201D02*
Y136949D01*
G01X42743Y117953D02*
Y116772D01*
G01Y121103D02*
Y119921D01*
G01Y127402D02*
Y126221D01*
G01Y124252D02*
Y123071D01*
G01Y130551D02*
Y129370D01*
G01Y133701D02*
Y132520D01*
G01X42006D02*
Y133701D01*
G01Y129370D02*
Y130551D01*
G01Y126221D02*
Y127402D01*
G01Y123071D02*
Y124252D01*
G01Y119921D02*
Y121103D01*
G01Y116772D02*
Y117953D01*
G01X41535Y137047D02*
Y135276D01*
G01X41453Y135374D02*
Y136949D01*
G01X40465D02*
Y135374D01*
G01D02*
X70866D01*
G01X41535Y135276D02*
X70866D01*
G01X42006Y133701D02*
X68110D01*
G01X40551Y133425D02*
X59055D01*
G01X68110Y132520D02*
X42006D01*
G01Y130551D02*
X68110D01*
G01Y129370D02*
X42006D01*
G01Y127402D02*
X68110D01*
G01Y126221D02*
X42006D01*
G01Y124252D02*
X68110D01*
G01Y123071D02*
X42006D01*
G01Y121103D02*
X68110D01*
G01Y119921D02*
X42006D01*
G01Y117953D02*
X68110D01*
G01Y116772D02*
X42006D01*
G01X46553Y141949D02*
Y140374D01*
G01Y146949D02*
Y145374D01*
G01Y151949D02*
Y150374D01*
G01Y156949D02*
Y155374D01*
G01X45447Y141949D02*
Y140374D01*
G01Y146949D02*
Y145374D01*
G01Y151949D02*
Y150374D01*
G01Y156949D02*
Y155374D01*
G01X45201Y141949D02*
Y140374D01*
G01Y146949D02*
Y145374D01*
G01Y151949D02*
Y150374D01*
G01Y156949D02*
Y155374D01*
G01X41535Y142047D02*
Y140276D01*
G01Y147047D02*
Y145276D01*
G01Y152047D02*
Y150276D01*
G01Y157047D02*
Y155276D01*
G01X41026Y155374D02*
Y156949D01*
G01Y150374D02*
Y151949D01*
G01Y145374D02*
Y146949D01*
G01Y140374D02*
Y141949D01*
G01X40344D02*
Y140374D01*
G01Y146949D02*
Y145374D01*
G01Y151949D02*
Y150374D01*
G01Y156949D02*
Y155374D01*
G01Y156949D02*
X70866D01*
G01X40344Y155374D02*
X70866D01*
G01X40344Y151949D02*
X70866D01*
G01X40344Y150374D02*
X70866D01*
G01X40344Y146949D02*
X70866D01*
G01X40344Y145374D02*
X70866D01*
G01X40344Y141949D02*
X70866D01*
G01X40344Y140374D02*
X70866D01*
G01X41535Y137047D02*
X70866D01*
G01X40465Y136949D02*
X70866D01*
G01X46553Y161949D02*
Y160374D01*
G01Y166949D02*
Y165374D01*
G01X45447Y161949D02*
Y160374D01*
G01Y166949D02*
Y165374D01*
G01X45201Y161949D02*
Y160374D01*
G01Y166949D02*
Y165374D01*
G01X41535Y162047D02*
Y160276D01*
G01Y167047D02*
Y165276D01*
G01X41026Y165374D02*
Y166949D01*
G01Y160374D02*
Y161949D01*
G01X40344D02*
Y160374D01*
G01Y166949D02*
Y165374D01*
G01X70079Y177854D02*
X59055D01*
G01X90551Y174902D02*
X40551D01*
G01X68208Y169980D02*
X39764D01*
G01X40344Y166949D02*
X70866D01*
G01X40344Y165374D02*
X70866D01*
G01X40344Y161949D02*
X70866D01*
G01X40344Y160374D02*
X70866D01*
G01X59252Y191063D02*
Y189488D01*
G01X59055Y183248D02*
Y196201D01*
G01X55118Y187185D02*
Y200138D01*
G01D02*
X82677D01*
G01X78740Y196201D02*
X59055D01*
G01X78740Y194232D02*
X59055D01*
G01X78740Y192244D02*
X59055D01*
G01Y191260D02*
X78740D01*
G01X59252Y191063D02*
X78543D01*
G01X59252Y189488D02*
X78543D01*
G01X78740Y189291D02*
X59055D01*
G01Y188307D02*
X78740D01*
G01Y185217D02*
X59055D01*
G01X59252Y423347D02*
Y421772D01*
G01X59055Y429587D02*
Y588760D01*
G01Y416634D02*
Y429587D01*
G01X55118Y412697D02*
Y425650D01*
G01X59055Y427618D02*
X78740D01*
G01Y424528D02*
X59055D01*
G01Y423543D02*
X78740D01*
G01X59252Y423347D02*
X78543D01*
G01X59252Y421772D02*
X78543D01*
G01X78740Y421575D02*
X59055D01*
G01Y420591D02*
X78740D01*
G01X59055Y418603D02*
X78740D01*
G01X59055Y416634D02*
X78740D01*
G01X82677Y412697D02*
X55118D01*
G01X46553Y447461D02*
Y445886D01*
G01Y452461D02*
Y450886D01*
G01X45447Y447461D02*
Y445886D01*
G01Y452461D02*
Y450886D01*
G01X45201Y447461D02*
Y445886D01*
G01Y452461D02*
Y450886D01*
G01X41535Y447559D02*
Y445788D01*
G01Y452559D02*
Y450788D01*
G01X41026Y450886D02*
Y452461D01*
G01Y445886D02*
Y447461D01*
G01X40344D02*
Y445886D01*
G01Y452461D02*
Y450886D01*
G01X39764Y442854D02*
Y575492D01*
G01X40344Y452461D02*
X70866D01*
G01X40344Y450886D02*
X70866D01*
G01X40344Y447461D02*
X70866D01*
G01X40344Y445886D02*
X70866D01*
G01X39764Y442854D02*
X68208D01*
G01X40551Y437933D02*
X90551D01*
G01X59055Y434980D02*
X70079D01*
G01X46553Y457461D02*
Y455886D01*
G01Y462461D02*
Y460886D01*
G01Y467461D02*
Y465886D01*
G01Y472461D02*
Y470886D01*
G01X45447Y457461D02*
Y455886D01*
G01Y462461D02*
Y460886D01*
G01Y467461D02*
Y465886D01*
G01Y472461D02*
Y470886D01*
G01X45201Y457461D02*
Y455886D01*
G01Y462461D02*
Y460886D01*
G01Y467461D02*
Y465886D01*
G01Y472461D02*
Y470886D01*
G01X41535Y457559D02*
Y455788D01*
G01Y462559D02*
Y460788D01*
G01Y467559D02*
Y465788D01*
G01Y472559D02*
Y470788D01*
G01X41026Y470886D02*
Y472461D01*
G01Y465886D02*
Y467461D01*
G01Y460886D02*
Y462461D01*
G01Y455886D02*
Y457461D01*
G01X40344D02*
Y455886D01*
G01Y462461D02*
Y460886D01*
G01Y467461D02*
Y465886D01*
G01Y472461D02*
Y470886D01*
G01Y472461D02*
X70866D01*
G01X40344Y470886D02*
X70866D01*
G01X40344Y467461D02*
X70866D01*
G01X40344Y465886D02*
X70866D01*
G01X40344Y462461D02*
X69685D01*
G01X40344Y460886D02*
X69685D01*
G01X40344Y457461D02*
X70866D01*
G01X40344Y455886D02*
X70866D01*
G01X40344Y495886D02*
X70866D01*
G01X40344Y492461D02*
X70866D01*
G01X40344Y490886D02*
X70866D01*
G01X40344Y487461D02*
X70866D01*
G01X40344Y485886D02*
X70866D01*
G01X40344Y482461D02*
X70866D01*
G01X40344Y480886D02*
X70866D01*
G01X40344Y477461D02*
X70866D01*
G01X40344Y475886D02*
X70866D01*
G01X46553Y477461D02*
Y475886D01*
G01Y482461D02*
Y480886D01*
G01Y487461D02*
Y485886D01*
G01Y492461D02*
Y490886D01*
G01Y497461D02*
Y495886D01*
G01X45447Y477461D02*
Y475886D01*
G01Y482461D02*
Y480886D01*
G01Y487461D02*
Y485886D01*
G01Y492461D02*
Y490886D01*
G01Y497461D02*
Y495886D01*
G01X45201Y477461D02*
Y475886D01*
G01Y482461D02*
Y480886D01*
G01Y487461D02*
Y485886D01*
G01Y492461D02*
Y490886D01*
G01Y497461D02*
Y495886D01*
G01X41535Y477559D02*
Y475788D01*
G01Y482559D02*
Y480788D01*
G01Y487559D02*
Y485788D01*
G01Y492559D02*
Y490788D01*
G01Y497559D02*
Y495788D01*
G01X41026Y495886D02*
Y497461D01*
G01Y490886D02*
Y492461D01*
G01Y485886D02*
Y487461D01*
G01Y480886D02*
Y482461D01*
G01Y475886D02*
Y477461D01*
G01X40344D02*
Y475886D01*
G01Y482461D02*
Y480886D01*
G01Y487461D02*
Y485886D01*
G01Y492461D02*
Y490886D01*
G01Y497461D02*
Y495886D01*
G01X40465Y515886D02*
X70866D01*
G01X41535Y515788D02*
X70866D01*
G01X40344Y512461D02*
X70866D01*
G01X40344Y510886D02*
X70866D01*
G01X40344Y507461D02*
X70866D01*
G01X40344Y505886D02*
X70866D01*
G01X40344Y502461D02*
X69685D01*
G01X40344Y500886D02*
X69685D01*
G01X40344Y497461D02*
X70866D01*
G01X46553Y502461D02*
Y500886D01*
G01Y507461D02*
Y505886D01*
G01Y512461D02*
Y510886D01*
G01Y517461D02*
Y515886D01*
G01X45447Y502461D02*
Y500886D01*
G01Y507461D02*
Y505886D01*
G01Y512461D02*
Y510886D01*
G01Y517461D02*
Y515886D01*
G01X45201D02*
Y517461D01*
G01Y502461D02*
Y500886D01*
G01Y507461D02*
Y505886D01*
G01Y512461D02*
Y510886D01*
G01X41535Y502559D02*
Y500788D01*
G01Y507559D02*
Y505788D01*
G01Y512559D02*
Y510788D01*
G01Y517559D02*
Y515788D01*
G01X41453Y515886D02*
Y517461D01*
G01X41026Y510886D02*
Y512461D01*
G01Y505886D02*
Y507461D01*
G01Y500886D02*
Y502461D01*
G01X40551Y516969D02*
Y541378D01*
G01X40465Y517461D02*
Y515886D01*
G01X40344Y502461D02*
Y500886D01*
G01Y507461D02*
Y505886D01*
G01Y512461D02*
Y510886D01*
G01X68110Y538032D02*
X42006D01*
G01Y536063D02*
X68110D01*
G01Y534882D02*
X42006D01*
G01Y532914D02*
X68110D01*
G01Y531732D02*
X42006D01*
G01Y529764D02*
X68110D01*
G01Y528583D02*
X42006D01*
G01Y526614D02*
X68110D01*
G01Y525433D02*
X42006D01*
G01Y523465D02*
X68110D01*
G01Y522284D02*
X42006D01*
G01Y520315D02*
X68110D01*
G01X59055Y519410D02*
X40551D01*
G01X68110Y519134D02*
X42006D01*
G01X70866Y517559D02*
X41535D01*
G01X40465Y517461D02*
X70866D01*
G01X51039Y534882D02*
Y536063D01*
G01Y538032D02*
Y539213D01*
G01Y531732D02*
Y532914D01*
G01Y528583D02*
Y529764D01*
G01Y525433D02*
Y526614D01*
G01Y522284D02*
Y523465D01*
G01Y519134D02*
Y520315D01*
G01X48800D02*
Y519134D01*
G01Y523465D02*
Y522284D01*
G01Y526614D02*
Y525433D01*
G01Y529764D02*
Y528583D01*
G01Y532914D02*
Y531732D01*
G01Y539213D02*
Y538032D01*
G01Y536063D02*
Y534882D01*
G01X48302Y538032D02*
Y539213D01*
G01Y534882D02*
Y536063D01*
G01Y531732D02*
Y532914D01*
G01Y528583D02*
Y529764D01*
G01Y525433D02*
Y526614D01*
G01Y522284D02*
Y523465D01*
G01Y519134D02*
Y520315D01*
G01X47559Y537933D02*
Y539311D01*
G01Y519036D02*
Y520414D01*
G01Y523563D02*
Y522185D01*
G01Y529862D02*
Y528484D01*
G01Y526713D02*
Y525335D01*
G01Y533012D02*
Y531634D01*
G01Y536162D02*
Y534784D01*
G01X42743Y520315D02*
Y519134D01*
G01Y523465D02*
Y522284D01*
G01Y529764D02*
Y528583D01*
G01Y526614D02*
Y525433D01*
G01Y532914D02*
Y531732D01*
G01Y539213D02*
Y538032D01*
G01Y536063D02*
Y534882D01*
G01X42006D02*
Y536063D01*
G01Y538032D02*
Y539213D01*
G01Y531732D02*
Y532914D01*
G01Y528583D02*
Y529764D01*
G01Y525433D02*
Y526614D01*
G01Y522284D02*
Y523465D01*
G01Y519134D02*
Y520315D01*
G01X40344Y557461D02*
X70866D01*
G01X40344Y555886D02*
X70866D01*
G01X40344Y552461D02*
X70866D01*
G01X40344Y550886D02*
X70866D01*
G01X40344Y547461D02*
X70866D01*
G01X40344Y545886D02*
X70866D01*
G01X41535Y542559D02*
X70866D01*
G01X40465Y542461D02*
X70866D01*
G01X40465Y540886D02*
X70866D01*
G01X41535Y540788D02*
X70866D01*
G01X42006Y539213D02*
X68110D01*
G01X40551Y538937D02*
X59055D01*
G01X46553Y542461D02*
Y540886D01*
G01Y547461D02*
Y545886D01*
G01Y552461D02*
Y550886D01*
G01Y557461D02*
Y555886D01*
G01X45447Y542461D02*
Y540886D01*
G01Y547461D02*
Y545886D01*
G01Y552461D02*
Y550886D01*
G01Y557461D02*
Y555886D01*
G01X45201Y540886D02*
Y542461D01*
G01Y547461D02*
Y545886D01*
G01Y552461D02*
Y550886D01*
G01Y557461D02*
Y555886D01*
G01X41535Y542559D02*
Y540788D01*
G01Y547559D02*
Y545788D01*
G01Y552559D02*
Y550788D01*
G01Y557559D02*
Y555788D01*
G01X41453Y540886D02*
Y542461D01*
G01X41026Y555886D02*
Y557461D01*
G01Y550886D02*
Y552461D01*
G01Y545886D02*
Y547461D01*
G01X40465Y542461D02*
Y540886D01*
G01X40344Y547461D02*
Y545886D01*
G01Y552461D02*
Y550886D01*
G01Y557461D02*
Y555886D01*
G01X90551Y580414D02*
X40551D01*
G01X68208Y575492D02*
X39764D01*
G01X40344Y572461D02*
X70866D01*
G01X40344Y570886D02*
X70866D01*
G01X40344Y567461D02*
X70866D01*
G01X40344Y565886D02*
X70866D01*
G01X40344Y562461D02*
X70866D01*
G01X40344Y560886D02*
X70866D01*
G01X46553Y562461D02*
Y560886D01*
G01Y567461D02*
Y565886D01*
G01Y572461D02*
Y570886D01*
G01X45447Y562461D02*
Y560886D01*
G01Y567461D02*
Y565886D01*
G01Y572461D02*
Y570886D01*
G01X45201Y562461D02*
Y560886D01*
G01Y567461D02*
Y565886D01*
G01Y572461D02*
Y570886D01*
G01X41535Y562559D02*
Y560788D01*
G01Y567559D02*
Y565788D01*
G01Y572559D02*
Y570788D01*
G01X41026Y570886D02*
Y572461D01*
G01Y565886D02*
Y567461D01*
G01Y560886D02*
Y562461D01*
G01X40344D02*
Y560886D01*
G01Y567461D02*
Y565886D01*
G01Y572461D02*
Y570886D01*
G01X78740Y601713D02*
X59055D01*
G01X78740Y599744D02*
X59055D01*
G01X78740Y597756D02*
X59055D01*
G01Y596772D02*
X78740D01*
G01X59252Y596575D02*
X78543D01*
G01X59252Y595000D02*
X78543D01*
G01X78740Y594803D02*
X59055D01*
G01Y593819D02*
X78740D01*
G01Y590728D02*
X59055D01*
G01X70079Y583366D02*
X59055D01*
G01X59252Y596575D02*
Y595000D01*
G01X59055Y588760D02*
Y601713D01*
G01X55118Y592697D02*
Y605650D01*
G01D02*
X82677D01*
G01X59055Y833130D02*
X78740D01*
G01Y830040D02*
X59055D01*
G01Y829055D02*
X78740D01*
G01X59252Y828858D02*
X78543D01*
G01X59252Y827284D02*
X78543D01*
G01X78740Y827087D02*
X59055D01*
G01Y826103D02*
X78740D01*
G01X59055Y824114D02*
X78740D01*
G01X59055Y822146D02*
X78740D01*
G01X82677Y818209D02*
X55118D01*
G01X59252Y828858D02*
Y827284D01*
G01X59055Y822146D02*
Y835099D01*
G01X55118Y818209D02*
Y831162D01*
G01X40344Y852973D02*
X70866D01*
G01X40344Y851398D02*
X70866D01*
G01X39764Y848366D02*
X68208D01*
G01X40551Y843445D02*
X90551D01*
G01X59055Y840492D02*
X70079D01*
G01X59055Y835099D02*
Y994272D01*
G01X46553Y852973D02*
Y851398D01*
G01X45447Y852973D02*
Y851398D01*
G01X45201Y852973D02*
Y851398D01*
G01X41535Y853071D02*
Y851299D01*
G01X41026Y851398D02*
Y852973D01*
G01X40344D02*
Y851398D01*
G01X39764Y848366D02*
Y981004D01*
G01X40344Y876398D02*
X70866D01*
G01X40344Y872973D02*
X70866D01*
G01X40344Y871398D02*
X70866D01*
G01X40344Y867973D02*
X69685D01*
G01X40344Y866398D02*
X69685D01*
G01X40344Y862973D02*
X70866D01*
G01X40344Y861398D02*
X70866D01*
G01X40344Y857973D02*
X70866D01*
G01X40344Y856398D02*
X70866D01*
G01X46553Y857973D02*
Y856398D01*
G01Y862973D02*
Y861398D01*
G01Y867973D02*
Y866398D01*
G01Y872973D02*
Y871398D01*
G01Y877973D02*
Y876398D01*
G01X45447Y857973D02*
Y856398D01*
G01Y862973D02*
Y861398D01*
G01Y867973D02*
Y866398D01*
G01Y872973D02*
Y871398D01*
G01Y877973D02*
Y876398D01*
G01X45201Y857973D02*
Y856398D01*
G01Y862973D02*
Y861398D01*
G01Y867973D02*
Y866398D01*
G01Y872973D02*
Y871398D01*
G01Y877973D02*
Y876398D01*
G01X41535Y858071D02*
Y856299D01*
G01Y863071D02*
Y861299D01*
G01Y868071D02*
Y866299D01*
G01Y873071D02*
Y871299D01*
G01Y878071D02*
Y876299D01*
G01X41026Y876398D02*
Y877973D01*
G01Y871398D02*
Y872973D01*
G01Y866398D02*
Y867973D01*
G01Y861398D02*
Y862973D01*
G01Y856398D02*
Y857973D01*
G01X40344D02*
Y856398D01*
G01Y862973D02*
Y861398D01*
G01Y867973D02*
Y866398D01*
G01Y872973D02*
Y871398D01*
G01Y877973D02*
Y876398D01*
G01Y897973D02*
X70866D01*
G01X40344Y896398D02*
X70866D01*
G01X40344Y892973D02*
X70866D01*
G01X40344Y891398D02*
X70866D01*
G01X40344Y887973D02*
X70866D01*
G01X40344Y886398D02*
X70866D01*
G01X40344Y882973D02*
X70866D01*
G01X40344Y881398D02*
X70866D01*
G01X40344Y877973D02*
X70866D01*
G01X46553Y882973D02*
Y881398D01*
G01Y887973D02*
Y886398D01*
G01Y892973D02*
Y891398D01*
G01Y897973D02*
Y896398D01*
G01X45447Y882973D02*
Y881398D01*
G01Y887973D02*
Y886398D01*
G01Y892973D02*
Y891398D01*
G01Y897973D02*
Y896398D01*
G01X45201Y882973D02*
Y881398D01*
G01Y887973D02*
Y886398D01*
G01Y892973D02*
Y891398D01*
G01Y897973D02*
Y896398D01*
G01X41535Y883071D02*
Y881299D01*
G01Y888071D02*
Y886299D01*
G01Y893071D02*
Y891299D01*
G01Y898071D02*
Y896299D01*
G01X41026Y896398D02*
Y897973D01*
G01Y891398D02*
Y892973D01*
G01Y886398D02*
Y887973D01*
G01Y881398D02*
Y882973D01*
G01X40344D02*
Y881398D01*
G01Y887973D02*
Y886398D01*
G01Y892973D02*
Y891398D01*
G01Y897973D02*
Y896398D01*
G01Y917973D02*
X70866D01*
G01X40344Y916398D02*
X70866D01*
G01X40344Y912973D02*
X70866D01*
G01X40344Y911398D02*
X70866D01*
G01X40344Y907973D02*
X69685D01*
G01X40344Y906398D02*
X69685D01*
G01X40344Y902973D02*
X70866D01*
G01X40344Y901398D02*
X70866D01*
G01X46553Y902973D02*
Y901398D01*
G01Y907973D02*
Y906398D01*
G01Y912973D02*
Y911398D01*
G01Y917973D02*
Y916398D01*
G01X45447Y902973D02*
Y901398D01*
G01Y907973D02*
Y906398D01*
G01Y912973D02*
Y911398D01*
G01Y917973D02*
Y916398D01*
G01X45201Y902973D02*
Y901398D01*
G01Y907973D02*
Y906398D01*
G01Y912973D02*
Y911398D01*
G01Y917973D02*
Y916398D01*
G01X41535Y903071D02*
Y901299D01*
G01Y908071D02*
Y906299D01*
G01Y913071D02*
Y911299D01*
G01Y918071D02*
Y916299D01*
G01X41026Y916398D02*
Y917973D01*
G01Y911398D02*
Y912973D01*
G01Y906398D02*
Y907973D01*
G01Y901398D02*
Y902973D01*
G01X40344D02*
Y901398D01*
G01Y907973D02*
Y906398D01*
G01Y912973D02*
Y911398D01*
G01Y917973D02*
Y916398D01*
G01X68110Y940394D02*
X42006D01*
G01Y938425D02*
X68110D01*
G01Y937244D02*
X42006D01*
G01Y935276D02*
X68110D01*
G01Y934095D02*
X42006D01*
G01Y932126D02*
X68110D01*
G01Y930945D02*
X42006D01*
G01Y928977D02*
X68110D01*
G01Y927795D02*
X42006D01*
G01Y925827D02*
X68110D01*
G01X59055Y924921D02*
X40551D01*
G01X68110Y924646D02*
X42006D01*
G01X70866Y923071D02*
X41535D01*
G01X40465Y922973D02*
X70866D01*
G01X40465Y921398D02*
X70866D01*
G01X41535Y921299D02*
X70866D01*
G01X51039Y940394D02*
Y941575D01*
G01Y937244D02*
Y938425D01*
G01Y934095D02*
Y935276D01*
G01Y930945D02*
Y932126D01*
G01Y927795D02*
Y928977D01*
G01Y924646D02*
Y925827D01*
G01X48800D02*
Y924646D01*
G01Y928977D02*
Y927795D01*
G01Y932126D02*
Y930945D01*
G01Y935276D02*
Y934095D01*
G01Y938425D02*
Y937244D01*
G01Y941575D02*
Y940394D01*
G01X48302Y937244D02*
Y938425D01*
G01Y940394D02*
Y941575D01*
G01Y934095D02*
Y935276D01*
G01Y930945D02*
Y932126D01*
G01Y927795D02*
Y928977D01*
G01Y924646D02*
Y925827D01*
G01X47559Y924547D02*
Y925925D01*
G01Y932225D02*
Y930847D01*
G01Y929075D02*
Y927697D01*
G01Y935374D02*
Y933996D01*
G01Y941673D02*
Y940295D01*
G01Y938524D02*
Y937146D01*
G01X46553Y922973D02*
Y921398D01*
G01X45447Y922973D02*
Y921398D01*
G01X45201D02*
Y922973D01*
G01X42743Y925827D02*
Y924646D01*
G01Y932126D02*
Y930945D01*
G01Y928977D02*
Y927795D01*
G01Y935276D02*
Y934095D01*
G01Y938425D02*
Y937244D01*
G01Y941575D02*
Y940394D01*
G01X42006D02*
Y941575D01*
G01Y937244D02*
Y938425D01*
G01Y934095D02*
Y935276D01*
G01Y930945D02*
Y932126D01*
G01Y927795D02*
Y928977D01*
G01Y924646D02*
Y925827D01*
G01X41535Y923071D02*
Y921299D01*
G01X41453Y921398D02*
Y922973D01*
G01X40551Y922480D02*
Y946890D01*
G01X40465Y922973D02*
Y921398D01*
G01X40344Y961398D02*
X70866D01*
G01X40344Y957973D02*
X70866D01*
G01X40344Y956398D02*
X70866D01*
G01X40344Y952973D02*
X70866D01*
G01X40344Y951398D02*
X70866D01*
G01X41535Y948071D02*
X70866D01*
G01X40465Y947973D02*
X70866D01*
G01X40465Y946398D02*
X70866D01*
G01X41535Y946299D02*
X70866D01*
G01X42006Y944725D02*
X68110D01*
G01X40551Y944449D02*
X59055D01*
G01X68110Y943543D02*
X42006D01*
G01Y941575D02*
X68110D01*
G01X51039Y943543D02*
Y944725D01*
G01X48800D02*
Y943543D01*
G01X48302D02*
Y944725D01*
G01X47559Y943445D02*
Y944823D01*
G01X46553Y947973D02*
Y946398D01*
G01Y952973D02*
Y951398D01*
G01Y957973D02*
Y956398D01*
G01Y962973D02*
Y961398D01*
G01X45447Y947973D02*
Y946398D01*
G01Y952973D02*
Y951398D01*
G01Y957973D02*
Y956398D01*
G01Y962973D02*
Y961398D01*
G01X45201Y946398D02*
Y947973D01*
G01Y952973D02*
Y951398D01*
G01Y957973D02*
Y956398D01*
G01Y962973D02*
Y961398D01*
G01X42743Y944725D02*
Y943543D01*
G01X42006D02*
Y944725D01*
G01X41535Y948071D02*
Y946299D01*
G01Y953071D02*
Y951299D01*
G01Y958071D02*
Y956299D01*
G01Y963071D02*
Y961299D01*
G01X41453Y946398D02*
Y947973D01*
G01X41026Y961398D02*
Y962973D01*
G01Y956398D02*
Y957973D01*
G01Y951398D02*
Y952973D01*
G01X40465Y947973D02*
Y946398D01*
G01X40344Y952973D02*
Y951398D01*
G01Y957973D02*
Y956398D01*
G01Y962973D02*
Y961398D01*
G01X68208Y981004D02*
X39764D01*
G01X40344Y977973D02*
X70866D01*
G01X40344Y976398D02*
X70866D01*
G01X40344Y972973D02*
X70866D01*
G01X40344Y971398D02*
X70866D01*
G01X40344Y967973D02*
X70866D01*
G01X40344Y966398D02*
X70866D01*
G01X40344Y962973D02*
X70866D01*
G01X46553Y967973D02*
Y966398D01*
G01Y972973D02*
Y971398D01*
G01Y977973D02*
Y976398D01*
G01X45447Y967973D02*
Y966398D01*
G01Y972973D02*
Y971398D01*
G01Y977973D02*
Y976398D01*
G01X45201Y967973D02*
Y966398D01*
G01Y972973D02*
Y971398D01*
G01Y977973D02*
Y976398D01*
G01X41535Y968071D02*
Y966299D01*
G01Y973071D02*
Y971299D01*
G01Y978071D02*
Y976299D01*
G01X41026Y976398D02*
Y977973D01*
G01Y971398D02*
Y972973D01*
G01Y966398D02*
Y967973D01*
G01X40344D02*
Y966398D01*
G01Y972973D02*
Y971398D01*
G01Y977973D02*
Y976398D01*
G01X78740Y1003268D02*
X59055D01*
G01Y1002284D02*
X78740D01*
G01X59252Y1002087D02*
X78543D01*
G01X59252Y1000512D02*
X78543D01*
G01X78740Y1000315D02*
X59055D01*
G01Y999331D02*
X78740D01*
G01Y996240D02*
X59055D01*
G01X70079Y988878D02*
X59055D01*
G01X90551Y985925D02*
X40551D01*
G01X59252Y1002087D02*
Y1000512D01*
G01X59055Y994272D02*
Y1007225D01*
G01X55118Y998209D02*
Y1011162D01*
G01D02*
X82677D01*
G01X78740Y1007225D02*
X59055D01*
G01X78740Y1005256D02*
X59055D01*
G01X78740Y1235551D02*
X59055D01*
G01Y1234567D02*
X78740D01*
G01X59252Y1234370D02*
X78543D01*
G01X59252Y1232795D02*
X78543D01*
G01X78740Y1232599D02*
X59055D01*
G01Y1231614D02*
X78740D01*
G01X59055Y1229626D02*
X78740D01*
G01X59055Y1227658D02*
X78740D01*
G01X82677Y1223721D02*
X55118D01*
G01X59252Y1234370D02*
Y1232795D01*
G01X59055Y1227658D02*
Y1240610D01*
G01X55118Y1223721D02*
Y1236673D01*
G01X40344Y1256910D02*
X70866D01*
G01X39764Y1253878D02*
X68208D01*
G01X40551Y1248957D02*
X90551D01*
G01X59055Y1246004D02*
X70079D01*
G01X59055Y1238642D02*
X78740D01*
G01X59055Y1240610D02*
Y1399784D01*
G01X46553Y1258484D02*
Y1256910D01*
G01X45447Y1258484D02*
Y1256910D01*
G01X45201Y1258484D02*
Y1256910D01*
G01X41535Y1258583D02*
Y1256811D01*
G01X41026Y1256910D02*
Y1258484D01*
G01X40344D02*
Y1256910D01*
G01X39764Y1253878D02*
Y1386516D01*
G01X40344Y1278484D02*
X70866D01*
G01X40344Y1276910D02*
X70866D01*
G01X40344Y1273484D02*
X69685D01*
G01X40344Y1271910D02*
X69685D01*
G01X40344Y1268484D02*
X70866D01*
G01X40344Y1266910D02*
X70866D01*
G01X40344Y1263484D02*
X70866D01*
G01X40344Y1261910D02*
X70866D01*
G01X40344Y1258484D02*
X70866D01*
G01X46553Y1263484D02*
Y1261910D01*
G01Y1268484D02*
Y1266910D01*
G01Y1273484D02*
Y1271910D01*
G01Y1278484D02*
Y1276910D01*
G01X45447Y1263484D02*
Y1261910D01*
G01Y1268484D02*
Y1266910D01*
G01Y1273484D02*
Y1271910D01*
G01Y1278484D02*
Y1276910D01*
G01X45201Y1263484D02*
Y1261910D01*
G01Y1268484D02*
Y1266910D01*
G01Y1273484D02*
Y1271910D01*
G01Y1278484D02*
Y1276910D01*
G01X41535Y1263583D02*
Y1261811D01*
G01Y1268583D02*
Y1266811D01*
G01Y1273583D02*
Y1271811D01*
G01Y1278583D02*
Y1276811D01*
G01X41026Y1276910D02*
Y1278484D01*
G01Y1271910D02*
Y1273484D01*
G01Y1266910D02*
Y1268484D01*
G01Y1261910D02*
Y1263484D01*
G01X40344D02*
Y1261910D01*
G01Y1268484D02*
Y1266910D01*
G01Y1273484D02*
Y1271910D01*
G01Y1278484D02*
Y1276910D01*
G01Y1298484D02*
X70866D01*
G01X40344Y1296910D02*
X70866D01*
G01X40344Y1293484D02*
X70866D01*
G01X40344Y1291910D02*
X70866D01*
G01X40344Y1288484D02*
X70866D01*
G01X40344Y1286910D02*
X70866D01*
G01X40344Y1283484D02*
X70866D01*
G01X40344Y1281910D02*
X70866D01*
G01X46553Y1283484D02*
Y1281910D01*
G01Y1288484D02*
Y1286910D01*
G01Y1293484D02*
Y1291910D01*
G01Y1298484D02*
Y1296910D01*
G01X45447Y1283484D02*
Y1281910D01*
G01Y1288484D02*
Y1286910D01*
G01Y1293484D02*
Y1291910D01*
G01Y1298484D02*
Y1296910D01*
G01X45201Y1283484D02*
Y1281910D01*
G01Y1288484D02*
Y1286910D01*
G01Y1293484D02*
Y1291910D01*
G01Y1298484D02*
Y1296910D01*
G01X41535Y1283583D02*
Y1281811D01*
G01Y1288583D02*
Y1286811D01*
G01Y1293583D02*
Y1291811D01*
G01Y1298583D02*
Y1296811D01*
G01X41026Y1296910D02*
Y1298484D01*
G01Y1291910D02*
Y1293484D01*
G01Y1286910D02*
Y1288484D01*
G01Y1281910D02*
Y1283484D01*
G01X40344D02*
Y1281910D01*
G01Y1288484D02*
Y1286910D01*
G01Y1293484D02*
Y1291910D01*
G01Y1298484D02*
Y1296910D01*
G01Y1318484D02*
X70866D01*
G01X40344Y1316910D02*
X70866D01*
G01X40344Y1313484D02*
X69685D01*
G01X40344Y1311910D02*
X69685D01*
G01X40344Y1308484D02*
X70866D01*
G01X40344Y1306910D02*
X70866D01*
G01X40344Y1303484D02*
X70866D01*
G01X40344Y1301910D02*
X70866D01*
G01X46553Y1303484D02*
Y1301910D01*
G01Y1308484D02*
Y1306910D01*
G01Y1313484D02*
Y1311910D01*
G01Y1318484D02*
Y1316910D01*
G01X45447Y1303484D02*
Y1301910D01*
G01Y1308484D02*
Y1306910D01*
G01Y1313484D02*
Y1311910D01*
G01Y1318484D02*
Y1316910D01*
G01X45201Y1303484D02*
Y1301910D01*
G01Y1308484D02*
Y1306910D01*
G01Y1313484D02*
Y1311910D01*
G01Y1318484D02*
Y1316910D01*
G01X41535Y1303583D02*
Y1301811D01*
G01Y1308583D02*
Y1306811D01*
G01Y1313583D02*
Y1311811D01*
G01Y1318583D02*
Y1316811D01*
G01X41026Y1316910D02*
Y1318484D01*
G01Y1311910D02*
Y1313484D01*
G01Y1306910D02*
Y1308484D01*
G01Y1301910D02*
Y1303484D01*
G01X40344D02*
Y1301910D01*
G01Y1308484D02*
Y1306910D01*
G01Y1313484D02*
Y1311910D01*
G01Y1318484D02*
Y1316910D01*
G01X42006Y1340788D02*
X68110D01*
G01Y1339606D02*
X42006D01*
G01Y1337638D02*
X68110D01*
G01Y1336457D02*
X42006D01*
G01Y1334488D02*
X68110D01*
G01Y1333307D02*
X42006D01*
G01Y1331339D02*
X68110D01*
G01X59055Y1330433D02*
X40551D01*
G01X68110Y1330158D02*
X42006D01*
G01X70866Y1328583D02*
X41535D01*
G01X40465Y1328484D02*
X70866D01*
G01X40465Y1326910D02*
X70866D01*
G01X41535Y1326811D02*
X70866D01*
G01X40344Y1323484D02*
X70866D01*
G01X40344Y1321910D02*
X70866D01*
G01X51039Y1339606D02*
Y1340788D01*
G01Y1336457D02*
Y1337638D01*
G01Y1333307D02*
Y1334488D01*
G01Y1330158D02*
Y1331339D01*
G01X48800D02*
Y1330158D01*
G01Y1334488D02*
Y1333307D01*
G01Y1337638D02*
Y1336457D01*
G01Y1340788D02*
Y1339606D01*
G01X48302D02*
Y1340788D01*
G01Y1336457D02*
Y1337638D01*
G01Y1330158D02*
Y1331339D01*
G01Y1333307D02*
Y1334488D01*
G01X47559Y1330059D02*
Y1331437D01*
G01Y1334587D02*
Y1333209D01*
G01Y1337736D02*
Y1336358D01*
G01Y1340886D02*
Y1339508D01*
G01X46553Y1323484D02*
Y1321910D01*
G01Y1328484D02*
Y1326910D01*
G01X45447Y1323484D02*
Y1321910D01*
G01Y1328484D02*
Y1326910D01*
G01X45201D02*
Y1328484D01*
G01Y1323484D02*
Y1321910D01*
G01X42743Y1331339D02*
Y1330158D01*
G01Y1334488D02*
Y1333307D01*
G01Y1337638D02*
Y1336457D01*
G01Y1340788D02*
Y1339606D01*
G01X42006D02*
Y1340788D01*
G01Y1336457D02*
Y1337638D01*
G01Y1333307D02*
Y1334488D01*
G01Y1330158D02*
Y1331339D01*
G01X41535Y1323583D02*
Y1321811D01*
G01Y1328583D02*
Y1326811D01*
G01X41453Y1326910D02*
Y1328484D01*
G01X41026Y1321910D02*
Y1323484D01*
G01X40551Y1327992D02*
Y1352402D01*
G01X40465Y1328484D02*
Y1326910D01*
G01X40344Y1323484D02*
Y1321910D01*
G01Y1361910D02*
X70866D01*
G01X40344Y1358484D02*
X70866D01*
G01X40344Y1356910D02*
X70866D01*
G01X41535Y1353583D02*
X70866D01*
G01X40465Y1353484D02*
X70866D01*
G01X40465Y1351910D02*
X70866D01*
G01X41535Y1351811D02*
X70866D01*
G01X42006Y1350236D02*
X68110D01*
G01X40551Y1349961D02*
X59055D01*
G01X68110Y1349055D02*
X42006D01*
G01Y1347087D02*
X68110D01*
G01Y1345906D02*
X42006D01*
G01Y1343937D02*
X68110D01*
G01Y1342756D02*
X42006D01*
G01X51039Y1349055D02*
Y1350236D01*
G01Y1345906D02*
Y1347087D01*
G01Y1342756D02*
Y1343937D01*
G01X48800D02*
Y1342756D01*
G01Y1347087D02*
Y1345906D01*
G01Y1350236D02*
Y1349055D01*
G01X48302D02*
Y1350236D01*
G01Y1345906D02*
Y1347087D01*
G01Y1342756D02*
Y1343937D01*
G01X47559Y1348957D02*
Y1350335D01*
G01Y1344036D02*
Y1342658D01*
G01Y1347185D02*
Y1345807D01*
G01X46553Y1353484D02*
Y1351910D01*
G01Y1358484D02*
Y1356910D01*
G01Y1363484D02*
Y1361910D01*
G01X45447Y1353484D02*
Y1351910D01*
G01Y1358484D02*
Y1356910D01*
G01Y1363484D02*
Y1361910D01*
G01X45201Y1351910D02*
Y1353484D01*
G01Y1358484D02*
Y1356910D01*
G01Y1363484D02*
Y1361910D01*
G01X42743Y1343937D02*
Y1342756D01*
G01Y1347087D02*
Y1345906D01*
G01Y1350236D02*
Y1349055D01*
G01X42006D02*
Y1350236D01*
G01Y1345906D02*
Y1347087D01*
G01Y1342756D02*
Y1343937D01*
G01X41535Y1353583D02*
Y1351811D01*
G01Y1358583D02*
Y1356811D01*
G01Y1363583D02*
Y1361811D01*
G01X41453Y1351910D02*
Y1353484D01*
G01X41026Y1361910D02*
Y1363484D01*
G01Y1356910D02*
Y1358484D01*
G01X40465Y1353484D02*
Y1351910D01*
G01X40344Y1358484D02*
Y1356910D01*
G01Y1363484D02*
Y1361910D01*
G01Y1383484D02*
X70866D01*
G01X40344Y1381910D02*
X70866D01*
G01X40344Y1378484D02*
X70866D01*
G01X40344Y1376910D02*
X70866D01*
G01X40344Y1373484D02*
X70866D01*
G01X40344Y1371910D02*
X70866D01*
G01X40344Y1368484D02*
X70866D01*
G01X40344Y1366910D02*
X70866D01*
G01X40344Y1363484D02*
X70866D01*
G01X46553Y1368484D02*
Y1366910D01*
G01Y1373484D02*
Y1371910D01*
G01Y1378484D02*
Y1376910D01*
G01Y1383484D02*
Y1381910D01*
G01X45447Y1368484D02*
Y1366910D01*
G01Y1373484D02*
Y1371910D01*
G01Y1378484D02*
Y1376910D01*
G01Y1383484D02*
Y1381910D01*
G01X45201Y1368484D02*
Y1366910D01*
G01Y1373484D02*
Y1371910D01*
G01Y1378484D02*
Y1376910D01*
G01Y1383484D02*
Y1381910D01*
G01X41535Y1368583D02*
Y1366811D01*
G01Y1373583D02*
Y1371811D01*
G01Y1378583D02*
Y1376811D01*
G01Y1383583D02*
Y1381811D01*
G01X41026Y1381910D02*
Y1383484D01*
G01Y1376910D02*
Y1378484D01*
G01Y1371910D02*
Y1373484D01*
G01Y1366910D02*
Y1368484D01*
G01X40344D02*
Y1366910D01*
G01Y1373484D02*
Y1371910D01*
G01Y1378484D02*
Y1376910D01*
G01Y1383484D02*
Y1381910D01*
G01X59055Y1404843D02*
X78740D01*
G01Y1401752D02*
X59055D01*
G01X70079Y1394390D02*
X59055D01*
G01X90551Y1391437D02*
X40551D01*
G01X68208Y1386516D02*
X39764D01*
G01X59055Y1399784D02*
Y1412736D01*
G01X55118Y1403721D02*
Y1416673D01*
G01D02*
X82677D01*
G01X78740Y1412736D02*
X59055D01*
G01X78740Y1410768D02*
X59055D01*
G01X78740Y1408780D02*
X59055D01*
G01Y1407795D02*
X78740D01*
G01X59252Y1407599D02*
X78543D01*
G01X59252Y1406024D02*
X78543D01*
G01X78740Y1405827D02*
X59055D01*
G01X59252Y1407599D02*
Y1406024D01*
G01Y1638307D02*
X78543D01*
G01X78740Y1638110D02*
X59055D01*
G01Y1637126D02*
X78740D01*
G01X59055Y1635138D02*
X78740D01*
G01X59055Y1633169D02*
X78740D01*
G01X82677Y1629232D02*
X55118D01*
G01X59252Y1639882D02*
Y1638307D01*
G01X59055Y1633169D02*
Y1646122D01*
G01X55118Y1629232D02*
Y1642185D01*
G01X39764Y1659390D02*
X68208D01*
G01X40551Y1654469D02*
X90551D01*
G01X59055Y1651516D02*
X70079D01*
G01X59055Y1644154D02*
X78740D01*
G01Y1641063D02*
X59055D01*
G01Y1640079D02*
X78740D01*
G01X59252Y1639882D02*
X78543D01*
G01X59055Y1646122D02*
Y1805295D01*
G01X39764Y1659390D02*
Y1792028D01*
G01X40344Y1678996D02*
X69685D01*
G01X40344Y1677421D02*
X69685D01*
G01X40344Y1673996D02*
X70866D01*
G01X40344Y1672421D02*
X70866D01*
G01X40344Y1668996D02*
X70866D01*
G01X40344Y1667421D02*
X70866D01*
G01X40344Y1663996D02*
X70866D01*
G01X40344Y1662421D02*
X70866D01*
G01X46553Y1663996D02*
Y1662421D01*
G01Y1668996D02*
Y1667421D01*
G01Y1673996D02*
Y1672421D01*
G01Y1678996D02*
Y1677421D01*
G01X45447Y1663996D02*
Y1662421D01*
G01Y1668996D02*
Y1667421D01*
G01Y1673996D02*
Y1672421D01*
G01Y1678996D02*
Y1677421D01*
G01X45201Y1663996D02*
Y1662421D01*
G01Y1668996D02*
Y1667421D01*
G01Y1673996D02*
Y1672421D01*
G01Y1678996D02*
Y1677421D01*
G01X41535Y1664095D02*
Y1662323D01*
G01Y1669095D02*
Y1667323D01*
G01Y1674095D02*
Y1672323D01*
G01Y1679095D02*
Y1677323D01*
G01X41026Y1677421D02*
Y1678996D01*
G01Y1672421D02*
Y1673996D01*
G01Y1667421D02*
Y1668996D01*
G01Y1662421D02*
Y1663996D01*
G01X40344D02*
Y1662421D01*
G01Y1668996D02*
Y1667421D01*
G01Y1673996D02*
Y1672421D01*
G01Y1678996D02*
Y1677421D01*
G01Y1698996D02*
X70866D01*
G01X40344Y1697421D02*
X70866D01*
G01X40344Y1693996D02*
X70866D01*
G01X40344Y1692421D02*
X70866D01*
G01X40344Y1688996D02*
X70866D01*
G01X40344Y1687421D02*
X70866D01*
G01X40344Y1683996D02*
X70866D01*
G01X40344Y1682421D02*
X70866D01*
G01X46553Y1683996D02*
Y1682421D01*
G01Y1688996D02*
Y1687421D01*
G01Y1693996D02*
Y1692421D01*
G01Y1698996D02*
Y1697421D01*
G01X45447Y1683996D02*
Y1682421D01*
G01Y1688996D02*
Y1687421D01*
G01Y1693996D02*
Y1692421D01*
G01Y1698996D02*
Y1697421D01*
G01X45201Y1683996D02*
Y1682421D01*
G01Y1688996D02*
Y1687421D01*
G01Y1693996D02*
Y1692421D01*
G01Y1698996D02*
Y1697421D01*
G01X41535Y1684095D02*
Y1682323D01*
G01Y1689095D02*
Y1687323D01*
G01Y1694095D02*
Y1692323D01*
G01Y1699095D02*
Y1697323D01*
G01X41026Y1697421D02*
Y1698996D01*
G01Y1692421D02*
Y1693996D01*
G01Y1687421D02*
Y1688996D01*
G01Y1682421D02*
Y1683996D01*
G01X40344D02*
Y1682421D01*
G01Y1688996D02*
Y1687421D01*
G01Y1693996D02*
Y1692421D01*
G01Y1698996D02*
Y1697421D01*
G01Y1722421D02*
X70866D01*
G01X40344Y1718996D02*
X69685D01*
G01X40344Y1717421D02*
X69685D01*
G01X40344Y1713996D02*
X70866D01*
G01X40344Y1712421D02*
X70866D01*
G01X40344Y1708996D02*
X70866D01*
G01X40344Y1707421D02*
X70866D01*
G01X40344Y1703996D02*
X70866D01*
G01X40344Y1702421D02*
X70866D01*
G01X46553Y1703996D02*
Y1702421D01*
G01Y1708996D02*
Y1707421D01*
G01Y1713996D02*
Y1712421D01*
G01Y1718996D02*
Y1717421D01*
G01Y1723996D02*
Y1722421D01*
G01X45447Y1703996D02*
Y1702421D01*
G01Y1708996D02*
Y1707421D01*
G01Y1713996D02*
Y1712421D01*
G01Y1718996D02*
Y1717421D01*
G01Y1723996D02*
Y1722421D01*
G01X45201Y1703996D02*
Y1702421D01*
G01Y1708996D02*
Y1707421D01*
G01Y1713996D02*
Y1712421D01*
G01Y1718996D02*
Y1717421D01*
G01Y1723996D02*
Y1722421D01*
G01X41535Y1704095D02*
Y1702323D01*
G01Y1709095D02*
Y1707323D01*
G01Y1714095D02*
Y1712323D01*
G01Y1719095D02*
Y1717323D01*
G01Y1724095D02*
Y1722323D01*
G01X41026Y1722421D02*
Y1723996D01*
G01Y1717421D02*
Y1718996D01*
G01Y1712421D02*
Y1713996D01*
G01Y1707421D02*
Y1708996D01*
G01Y1702421D02*
Y1703996D01*
G01X40344D02*
Y1702421D01*
G01Y1708996D02*
Y1707421D01*
G01Y1713996D02*
Y1712421D01*
G01Y1718996D02*
Y1717421D01*
G01Y1723996D02*
Y1722421D01*
G01X42006Y1743150D02*
X68110D01*
G01Y1741969D02*
X42006D01*
G01Y1740000D02*
X68110D01*
G01Y1738819D02*
X42006D01*
G01Y1736851D02*
X68110D01*
G01X59055Y1735945D02*
X40551D01*
G01X68110Y1735669D02*
X42006D01*
G01X70866Y1734095D02*
X41535D01*
G01X40465Y1733996D02*
X70866D01*
G01X40465Y1732421D02*
X70866D01*
G01X41535Y1732323D02*
X70866D01*
G01X40344Y1728996D02*
X70866D01*
G01X40344Y1727421D02*
X70866D01*
G01X40344Y1723996D02*
X70866D01*
G01X51039Y1741969D02*
Y1743150D01*
G01Y1738819D02*
Y1740000D01*
G01Y1735669D02*
Y1736851D01*
G01X48800D02*
Y1735669D01*
G01Y1740000D02*
Y1738819D01*
G01Y1743150D02*
Y1741969D01*
G01X48302D02*
Y1743150D01*
G01Y1738819D02*
Y1740000D01*
G01Y1735669D02*
Y1736851D01*
G01X47559Y1735571D02*
Y1736949D01*
G01Y1740099D02*
Y1738721D01*
G01Y1743248D02*
Y1741870D01*
G01X46553Y1728996D02*
Y1727421D01*
G01Y1733996D02*
Y1732421D01*
G01X45447Y1728996D02*
Y1727421D01*
G01Y1733996D02*
Y1732421D01*
G01X45201D02*
Y1733996D01*
G01Y1728996D02*
Y1727421D01*
G01X42743Y1736851D02*
Y1735669D01*
G01Y1740000D02*
Y1738819D01*
G01Y1743150D02*
Y1741969D01*
G01X42006D02*
Y1743150D01*
G01Y1738819D02*
Y1740000D01*
G01Y1735669D02*
Y1736851D01*
G01X41535Y1729095D02*
Y1727323D01*
G01Y1734095D02*
Y1732323D01*
G01X41453Y1732421D02*
Y1733996D01*
G01X41026Y1727421D02*
Y1728996D01*
G01X40551Y1733504D02*
Y1757914D01*
G01X40465Y1733996D02*
Y1732421D01*
G01X40344Y1728996D02*
Y1727421D01*
G01Y1763996D02*
X70866D01*
G01X40344Y1762421D02*
X70866D01*
G01X41535Y1759095D02*
X70866D01*
G01X40465Y1758996D02*
X70866D01*
G01X40465Y1757421D02*
X70866D01*
G01X41535Y1757323D02*
X70866D01*
G01X42006Y1755748D02*
X68110D01*
G01X40551Y1755473D02*
X59055D01*
G01X68110Y1754567D02*
X42006D01*
G01Y1752599D02*
X68110D01*
G01Y1751417D02*
X42006D01*
G01Y1749449D02*
X68110D01*
G01Y1748268D02*
X42006D01*
G01Y1746299D02*
X68110D01*
G01Y1745118D02*
X42006D01*
G01X51039Y1751417D02*
Y1752599D01*
G01Y1754567D02*
Y1755748D01*
G01Y1748268D02*
Y1749449D01*
G01Y1745118D02*
Y1746299D01*
G01X48800D02*
Y1745118D01*
G01Y1749449D02*
Y1748268D01*
G01Y1755748D02*
Y1754567D01*
G01Y1752599D02*
Y1751417D01*
G01X48302Y1754567D02*
Y1755748D01*
G01Y1751417D02*
Y1752599D01*
G01Y1748268D02*
Y1749449D01*
G01Y1745118D02*
Y1746299D01*
G01X47559Y1754469D02*
Y1755847D01*
G01Y1746398D02*
Y1745020D01*
G01Y1749547D02*
Y1748169D01*
G01Y1752697D02*
Y1751319D01*
G01X46553Y1758996D02*
Y1757421D01*
G01Y1763996D02*
Y1762421D01*
G01X45447Y1758996D02*
Y1757421D01*
G01Y1763996D02*
Y1762421D01*
G01X45201Y1757421D02*
Y1758996D01*
G01Y1763996D02*
Y1762421D01*
G01X42743Y1746299D02*
Y1745118D01*
G01Y1749449D02*
Y1748268D01*
G01Y1755748D02*
Y1754567D01*
G01Y1752599D02*
Y1751417D01*
G01X42006D02*
Y1752599D01*
G01Y1754567D02*
Y1755748D01*
G01Y1748268D02*
Y1749449D01*
G01Y1745118D02*
Y1746299D01*
G01X41535Y1759095D02*
Y1757323D01*
G01Y1764095D02*
Y1762323D01*
G01X41453Y1757421D02*
Y1758996D01*
G01X41026Y1762421D02*
Y1763996D01*
G01X40465Y1758996D02*
Y1757421D01*
G01X40344Y1763996D02*
Y1762421D01*
G01Y1783996D02*
X70866D01*
G01X40344Y1782421D02*
X70866D01*
G01X40344Y1778996D02*
X70866D01*
G01X40344Y1777421D02*
X70866D01*
G01X40344Y1773996D02*
X70866D01*
G01X40344Y1772421D02*
X70866D01*
G01X40344Y1768996D02*
X70866D01*
G01X40344Y1767421D02*
X70866D01*
G01X46553Y1768996D02*
Y1767421D01*
G01Y1773996D02*
Y1772421D01*
G01Y1778996D02*
Y1777421D01*
G01Y1783996D02*
Y1782421D01*
G01X45447Y1768996D02*
Y1767421D01*
G01Y1773996D02*
Y1772421D01*
G01Y1778996D02*
Y1777421D01*
G01Y1783996D02*
Y1782421D01*
G01X45201Y1768996D02*
Y1767421D01*
G01Y1773996D02*
Y1772421D01*
G01Y1778996D02*
Y1777421D01*
G01Y1783996D02*
Y1782421D01*
G01X41535Y1769095D02*
Y1767323D01*
G01Y1774095D02*
Y1772323D01*
G01Y1779095D02*
Y1777323D01*
G01Y1784095D02*
Y1782323D01*
G01X41026Y1782421D02*
Y1783996D01*
G01Y1777421D02*
Y1778996D01*
G01Y1772421D02*
Y1773996D01*
G01Y1767421D02*
Y1768996D01*
G01X40344D02*
Y1767421D01*
G01Y1773996D02*
Y1772421D01*
G01Y1778996D02*
Y1777421D01*
G01Y1783996D02*
Y1782421D01*
G01X78740Y1807264D02*
X59055D01*
G01X70079Y1799902D02*
X59055D01*
G01X90551Y1796949D02*
X40551D01*
G01X68208Y1792028D02*
X39764D01*
G01X40344Y1788996D02*
X70866D01*
G01X40344Y1787421D02*
X70866D01*
G01X59055Y1805295D02*
Y1818248D01*
G01X46553Y1788996D02*
Y1787421D01*
G01X45447Y1788996D02*
Y1787421D01*
G01X45201Y1788996D02*
Y1787421D01*
G01X41535Y1789095D02*
Y1787323D01*
G01X41026Y1787421D02*
Y1788996D01*
G01X40344D02*
Y1787421D01*
G01X55118Y1822185D02*
X82677D01*
G01X78740Y1818248D02*
X59055D01*
G01X78740Y1816280D02*
X59055D01*
G01X78740Y1814291D02*
X59055D01*
G01Y1813307D02*
X78740D01*
G01X59252Y1813110D02*
X78543D01*
G01X59252Y1811536D02*
X78543D01*
G01X78740Y1811339D02*
X59055D01*
G01Y1810354D02*
X78740D01*
G01X59252Y1813110D02*
Y1811536D01*
G01X55118Y1809232D02*
Y1822185D01*
G01X76013Y30686D02*
X75895Y30948D01*
G01X76132Y30433D02*
X76013Y30686D01*
G01X80281Y27042D02*
X80167Y27284D01*
G01X80399Y26779D02*
X80281Y27042D01*
G01X80520Y26496D02*
X80399Y26779D01*
G01X80736Y25953D02*
X80754Y25905D01*
G01X80701Y26044D02*
X80736Y25953D01*
G01X75779Y26495D02*
Y26496D01*
G01X75777Y26491D02*
X75779Y26495D01*
G01X75753Y26432D02*
X75777Y26491D01*
G01X80286Y30685D02*
X80167Y30433D01*
G01X80404Y30948D02*
X80286Y30685D01*
G01X75899Y26778D02*
X75779Y26496D01*
G01X76017Y27041D02*
X75899Y26778D01*
G01X76132Y27284D02*
X76017Y27041D01*
G01X80167Y27284D02*
G03Y30433I-2018J1575D01*
G01X76132D02*
G03Y27284I2017J-1575D01*
G01X80520Y26496D02*
G03Y31221I-2370J2363D01*
G01X75779D02*
G03Y26496I2370J-2363D01*
G01X81653Y28858D02*
G03I-3504J0D01*
G01X75472Y32008D02*
G03Y25709I2677J-3149D01*
G01X80827D02*
G03Y32008I-2678J3149D01*
G01X72638Y17047D02*
G03I-3741J0D01*
G01X75714Y26339D02*
X75753Y26432D01*
G01X75631Y26130D02*
X75714Y26339D01*
G01X75597Y26044D02*
X75631Y26130D01*
G01X75562Y25953D02*
X75597Y26044D01*
G01X75527Y25857D02*
X75562Y25953D01*
G01X75472Y25709D02*
X75527Y25857D01*
G01X78740Y11122D02*
Y24075D01*
G01X78543Y16260D02*
Y17835D01*
G01X73189D02*
Y16260D01*
G01X71850Y17835D02*
Y18032D01*
G01Y16260D02*
Y16063D01*
G01Y17835D02*
Y16260D01*
G01X71653Y17835D02*
Y16260D01*
G01X70079Y24075D02*
Y32421D01*
G01Y16260D02*
Y17835D01*
G01X67716Y16260D02*
Y17835D01*
G01X66142Y16260D02*
Y17835D01*
G01X65945Y16260D02*
Y17835D01*
G01Y18032D02*
Y17835D01*
G01Y16260D02*
Y16063D01*
G01X64606Y16260D02*
Y17835D01*
G01X80790Y25808D02*
X80827Y25709D01*
G01X80754Y25905D02*
X80790Y25808D01*
G01X80668Y26130D02*
X80701Y26044D01*
G01X80596Y26309D02*
X80668Y26130D01*
G01X80563Y26390D02*
X80596Y26309D01*
G01X80520Y26496D02*
X80563Y26390D01*
G01X80167Y30433D02*
X76132D01*
G01X70079Y29469D02*
X90551D01*
G01X80167Y27284D02*
X76132D01*
G01X75779Y26496D02*
X80520D01*
G01X80827Y25709D02*
X75472D01*
G01X75895Y30948D02*
X75779Y31221D01*
G01X75527Y31860D02*
X75508Y31909D01*
G01X75562Y31764D02*
X75527Y31860D01*
G01X80736Y31764D02*
X80719Y31717D01*
G01X80772Y31860D02*
X80736Y31764D01*
G01X80520Y31222D02*
Y31221D01*
G01X80533Y31253D02*
X80520Y31222D01*
G01Y31221D02*
X80404Y30948D01*
G01X79527Y42047D02*
X82677Y43228D01*
G01X79527Y47047D02*
X82677Y48228D01*
G01X79527Y52047D02*
X82677Y53228D01*
G01X80573Y31351D02*
X80533Y31253D01*
G01X80652Y31546D02*
X80573Y31351D01*
G01X80684Y31628D02*
X80652Y31546D01*
G01X80719Y31717D02*
X80684Y31628D01*
G01X80827Y32008D02*
X80772Y31860D01*
G01X82008Y41949D02*
Y40374D01*
G01Y46949D02*
Y45374D01*
G01Y51949D02*
Y50374D01*
G01X80433Y41949D02*
Y40374D01*
G01Y46949D02*
Y45374D01*
G01Y51949D02*
Y50374D01*
G01X74803Y40374D02*
Y40276D01*
G01Y42047D02*
Y41949D01*
G01D02*
Y40374D01*
G01Y45374D02*
Y45276D01*
G01Y47047D02*
Y46949D01*
G01D02*
Y45374D01*
G01Y50374D02*
Y50276D01*
G01Y52047D02*
Y51949D01*
G01D02*
Y50374D01*
G01X70866Y35571D02*
Y55374D01*
G01X69586Y37343D02*
Y169980D01*
G01X68208D02*
Y37343D01*
G01X66929D02*
Y169980D01*
G01X75508Y31909D02*
X75472Y32008D01*
G01X75597Y31673D02*
X75562Y31764D01*
G01X75631Y31586D02*
X75597Y31673D01*
G01X75703Y31407D02*
X75631Y31586D01*
G01X75736Y31326D02*
X75703Y31407D01*
G01X75779Y31221D02*
X75736Y31326D01*
G01X79527Y52047D02*
X74803D01*
G01X70866Y51949D02*
X88110D01*
G01X70866Y50374D02*
X88110D01*
G01X74803Y50276D02*
X79527D01*
G01Y47047D02*
X74803D01*
G01X70866Y46949D02*
X88110D01*
G01X70866Y45374D02*
X88110D01*
G01X74803Y45276D02*
X79527D01*
G01Y42047D02*
X74803D01*
G01X70866Y41949D02*
X88110D01*
G01X70866Y40374D02*
X88110D01*
G01X74803Y40276D02*
X79527D01*
G01X69586Y37343D02*
X70866D01*
G01X90551D02*
X70866D01*
G01Y35571D02*
X90551D01*
G01X75472Y32008D02*
X80827D01*
G01X80520Y31221D02*
X75779D01*
G01X82677Y49095D02*
X79527Y50276D01*
G01X82677Y44095D02*
X79527Y45276D01*
G01X82677Y39095D02*
X79527Y40276D01*
G01Y62047D02*
X82677Y63228D01*
G01X79527Y67047D02*
X82677Y68228D01*
G01X79527Y72047D02*
X82677Y73228D01*
G01X82008Y56949D02*
Y55374D01*
G01Y61949D02*
Y60374D01*
G01Y66949D02*
Y65374D01*
G01Y71949D02*
Y70374D01*
G01X80433Y56949D02*
Y55374D01*
G01Y61949D02*
Y60374D01*
G01Y66949D02*
Y65374D01*
G01Y71949D02*
Y70374D01*
G01X77756Y57284D02*
Y60040D01*
G01X74803Y60374D02*
Y60276D01*
G01Y62047D02*
Y61949D01*
G01D02*
Y60374D01*
G01Y65374D02*
Y65276D01*
G01Y67047D02*
Y66949D01*
G01Y70374D02*
Y70276D01*
G01Y66949D02*
Y65374D01*
G01Y72047D02*
Y71949D01*
G01D02*
Y70374D01*
G01X72834Y55374D02*
Y55276D01*
G01Y57047D02*
Y56949D01*
G01D02*
Y55374D01*
G01X70866D02*
Y56949D01*
G01D02*
Y95374D01*
G01X69685Y58524D02*
Y53799D01*
G01X77559Y57047D02*
X82677Y58228D01*
G01X79527Y72047D02*
X74803D01*
G01X70866Y71949D02*
X88110D01*
G01X70866Y70374D02*
X88110D01*
G01X74803Y70276D02*
X79527D01*
G01Y67047D02*
X74803D01*
G01X70866Y66949D02*
X88110D01*
G01X70866Y65374D02*
X88110D01*
G01X74803Y65276D02*
X79527D01*
G01Y62047D02*
X74803D01*
G01X70866Y61949D02*
X88110D01*
G01X70866Y60374D02*
X88110D01*
G01X74803Y60276D02*
X79527D01*
G01X70866Y60040D02*
X77756D01*
G01X70866Y58524D02*
X69685D01*
G01X77756Y57284D02*
X70866D01*
G01X77559Y57047D02*
X72834D01*
G01X69685Y56949D02*
X89567D01*
G01X69685Y55374D02*
X89567D01*
G01X72834Y55276D02*
X77559D01*
G01X69685Y53799D02*
X70866D01*
G01X82677Y69095D02*
X79527Y70276D01*
G01X82677Y64095D02*
X79527Y65276D01*
G01X82677Y59095D02*
X79527Y60276D01*
G01X82677Y54095D02*
X77559Y55276D01*
G01X79527Y77047D02*
X82677Y78228D01*
G01X79527Y82047D02*
X82677Y83228D01*
G01X79527Y87047D02*
X82677Y88228D01*
G01X79527Y92047D02*
X82677Y93228D01*
G01X82008Y76949D02*
Y75374D01*
G01Y81949D02*
Y80374D01*
G01Y86949D02*
Y85374D01*
G01Y91949D02*
Y90374D01*
G01X80433Y76949D02*
Y75374D01*
G01Y81949D02*
Y80374D01*
G01Y86949D02*
Y85374D01*
G01Y91949D02*
Y90374D01*
G01X77756Y82284D02*
Y85040D01*
G01X74803Y75374D02*
Y75276D01*
G01Y77047D02*
Y76949D01*
G01Y80374D02*
Y80276D01*
G01Y76949D02*
Y75374D01*
G01Y82047D02*
Y81949D01*
G01Y85374D02*
Y85276D01*
G01Y81949D02*
Y80374D01*
G01Y87047D02*
Y86949D01*
G01D02*
Y85374D01*
G01Y90374D02*
Y90276D01*
G01Y92047D02*
Y91949D01*
G01D02*
Y90374D01*
G01X69685Y98524D02*
Y93799D01*
G01D02*
X70866D01*
G01X82677Y94095D02*
X77559Y95276D01*
G01X79527Y92047D02*
X74803D01*
G01X70866Y91949D02*
X88110D01*
G01X70866Y90374D02*
X88110D01*
G01X74803Y90276D02*
X79527D01*
G01Y87047D02*
X74803D01*
G01X70866Y86949D02*
X88110D01*
G01X70866Y85374D02*
X88110D01*
G01X74803Y85276D02*
X79527D01*
G01X70866Y85040D02*
X77756D01*
G01Y82284D02*
X70866D01*
G01X79527Y82047D02*
X74803D01*
G01X70866Y81949D02*
X88110D01*
G01X70866Y80374D02*
X88110D01*
G01X74803Y80276D02*
X79527D01*
G01Y77047D02*
X74803D01*
G01X70866Y76949D02*
X88110D01*
G01X70866Y75374D02*
X88110D01*
G01X74803Y75276D02*
X79527D01*
G01X82677Y89095D02*
X79527Y90276D01*
G01X82677Y84095D02*
X79527Y85276D01*
G01X82677Y79095D02*
X79527Y80276D01*
G01X82677Y74095D02*
X79527Y75276D01*
G01X73228Y114902D02*
X75590Y115591D01*
G01X79527Y102047D02*
X82677Y103228D01*
G01X79527Y107047D02*
X82677Y108228D01*
G01X82008Y96949D02*
Y95374D01*
G01Y101949D02*
Y100374D01*
G01Y106949D02*
Y105374D01*
G01Y111949D02*
Y110374D01*
G01X80433Y96949D02*
Y95374D01*
G01Y101949D02*
Y100374D01*
G01Y106949D02*
Y105374D01*
G01Y111949D02*
Y110374D01*
G01X80118Y114803D02*
Y113622D01*
G01X78937Y112638D02*
Y112047D01*
G01X77756Y107284D02*
Y110040D01*
G01X75590Y112835D02*
Y112638D01*
G01X75512Y113622D02*
Y114803D01*
G01X75118D02*
Y113622D01*
G01X74803Y100374D02*
Y100276D01*
G01Y102047D02*
Y101949D01*
G01D02*
Y100374D01*
G01Y105374D02*
Y105276D01*
G01Y107047D02*
Y106949D01*
G01D02*
Y105374D01*
G01Y110374D02*
Y110276D01*
G01Y112047D02*
Y111949D01*
G01D02*
Y110374D01*
G01X74330Y114803D02*
Y113622D01*
G01X72834Y95374D02*
Y95276D01*
G01Y97047D02*
Y96949D01*
G01D02*
Y95374D01*
G01X72756Y114803D02*
Y113622D01*
G01X70866Y114803D02*
Y116772D01*
G01Y113622D02*
Y114803D01*
G01Y95374D02*
Y96949D01*
G01D02*
Y113622D01*
G01X68110Y135866D02*
Y111457D01*
G01X77559Y97047D02*
X82677Y98228D01*
G01X73228Y114902D02*
X70866D01*
G01X68110Y114803D02*
X80118D01*
G01X68110Y113622D02*
X80118D01*
G01X73228Y113524D02*
X70866D01*
G01X75590Y112638D02*
X78937D01*
G01Y112047D02*
X74803D01*
G01X70866Y111949D02*
X89567D01*
G01X70866Y110374D02*
X89567D01*
G01X74803Y110276D02*
X79527D01*
G01X70866Y110040D02*
X77756D01*
G01Y107284D02*
X70866D01*
G01X79527Y107047D02*
X74803D01*
G01X70866Y106949D02*
X88110D01*
G01X70866Y105374D02*
X88110D01*
G01X74803Y105276D02*
X79527D01*
G01Y102047D02*
X74803D01*
G01X70866Y101949D02*
X88110D01*
G01X70866Y100374D02*
X88110D01*
G01X74803Y100276D02*
X79527D01*
G01X70866Y98524D02*
X69685D01*
G01X77559Y97047D02*
X72834D01*
G01X69685Y96949D02*
X89567D01*
G01X69685Y95374D02*
X89567D01*
G01X72834Y95276D02*
X77559D01*
G01X75590Y112835D02*
X73228Y113524D01*
G01X82677Y109095D02*
X79527Y110276D01*
G01X82677Y104095D02*
X79527Y105276D01*
G01X82677Y99095D02*
X79527Y100276D01*
G01X73228Y118051D02*
X75590Y118740D01*
G01X73228Y121201D02*
X75590Y121890D01*
G01X73228Y124351D02*
X75590Y125040D01*
G01X73228Y127500D02*
X75590Y128189D01*
G01X73228Y130650D02*
X75590Y131339D01*
G01X73228Y133799D02*
X75590Y134488D01*
G01X78473Y134114D02*
X78372Y134081D01*
G01X79411Y131817D02*
X79243Y131752D01*
G01X78975Y132867D02*
X79143Y132933D01*
G01X78305Y132835D02*
X78473Y132900D01*
G01X78707Y131851D02*
X78573Y131785D01*
G01X79411Y133261D02*
X79277Y133195D01*
G01X78640Y132014D02*
X78540Y131949D01*
G01X78372Y132671D02*
X78473Y132736D01*
G01X79243Y133392D02*
X79344Y133458D01*
G01X79377Y132014D02*
X79243Y131916D01*
G01X79009Y132671D02*
X79143Y132769D01*
G01X79512Y131916D02*
X79411Y131817D01*
G01X78808Y131949D02*
X78707Y131851D01*
G01X79545Y133392D02*
X79411Y133261D01*
G01X78205Y132736D02*
X78305Y132835D01*
G01X78171Y134147D02*
X78305Y134278D01*
G01X78741Y132146D02*
X78640Y132014D01*
G01X78875Y132736D02*
X78975Y132867D01*
G01X78272Y132540D02*
X78372Y132671D01*
G01X79344Y133458D02*
X79411Y133556D01*
G01X78372Y134081D02*
X78305Y133983D01*
G01X79612Y132080D02*
X79512Y131916D01*
G01X78104Y132572D02*
X78205Y132736D01*
G01X79444Y132146D02*
X79377Y132014D01*
G01X78842D02*
X78808Y131949D01*
G01X79612Y133524D02*
X79545Y133392D01*
G01X78942Y132540D02*
X79009Y132671D01*
G01X78842D02*
X78875Y132736D01*
G01X78104Y134016D02*
X78171Y134147D01*
G01X78305Y133983D02*
X78272Y133884D01*
G01X79478Y132277D02*
X79444Y132146D01*
G01X79411Y133556D02*
X79444Y133688D01*
G01X78908Y132408D02*
X78937Y132520D01*
G01D02*
X78942Y132540D01*
G01X78774Y132277D02*
X78741Y132146D01*
G01X78238Y132408D02*
X78267Y132520D01*
G01D02*
X78272Y132540D01*
G01X78071Y133884D02*
X78104Y134016D01*
G01X79645Y132244D02*
X79612Y132080D01*
G01X79645Y133688D02*
X79612Y133524D01*
G01X78071Y132408D02*
X78093Y132520D01*
G01D02*
X78104Y132572D01*
G01X82008Y136949D02*
Y135374D01*
G01X80433Y136949D02*
Y135374D01*
G01X80118Y117953D02*
Y116772D01*
G01Y121103D02*
Y119921D01*
G01Y127402D02*
Y126221D01*
G01Y124252D02*
Y123071D01*
G01Y130551D02*
Y129370D01*
G01Y133701D02*
Y132520D01*
G01X79645Y132441D02*
Y132244D01*
G01Y133950D02*
Y133701D01*
G01D02*
Y133688D01*
G01X79478Y132408D02*
Y132277D01*
G01X79444Y133701D02*
Y133950D01*
G01Y133688D02*
Y133701D01*
G01X79210Y134213D02*
Y134410D01*
G01X78942Y133884D02*
Y133701D01*
G01D02*
Y133688D01*
G01X78937Y135276D02*
Y134685D01*
G01X78908Y132277D02*
Y132408D01*
G01X78774D02*
Y132277D01*
G01X78741Y133701D02*
Y133884D01*
G01Y133688D02*
Y133701D01*
G01X78439Y133491D02*
Y133294D01*
G01X78272Y133884D02*
Y133701D01*
G01D02*
Y133688D01*
G01X78238Y132277D02*
Y132408D01*
G01X78071Y133721D02*
Y133884D01*
G01Y132277D02*
Y132408D01*
G01X75590Y115984D02*
Y115591D01*
G01Y122284D02*
Y121890D01*
G01Y119134D02*
Y118740D01*
G01Y125433D02*
Y125040D01*
G01Y131732D02*
Y131339D01*
G01Y128583D02*
Y128189D01*
G01Y134685D02*
Y134488D01*
G01X75512Y132520D02*
Y133701D01*
G01Y129370D02*
Y130551D01*
G01Y126221D02*
Y127402D01*
G01Y123071D02*
Y124252D01*
G01Y119921D02*
Y121103D01*
G01Y116772D02*
Y117953D01*
G01X75118D02*
Y116772D01*
G01Y121103D02*
Y119921D01*
G01Y127402D02*
Y126221D01*
G01Y124252D02*
Y123071D01*
G01Y130551D02*
Y129370D01*
G01Y133701D02*
Y132520D01*
G01X74803Y135374D02*
Y135276D01*
G01Y136949D02*
Y135374D01*
G01X74330Y117953D02*
Y116772D01*
G01Y121103D02*
Y119921D01*
G01Y124252D02*
Y123071D01*
G01Y127402D02*
Y126221D01*
G01Y130551D02*
Y129370D01*
G01Y133701D02*
Y132520D01*
G01X72756Y117953D02*
Y116772D01*
G01Y121103D02*
Y119921D01*
G01Y127402D02*
Y126221D01*
G01Y124252D02*
Y123071D01*
G01Y130551D02*
Y129370D01*
G01Y133701D02*
Y132520D01*
G01X70866Y133701D02*
Y171752D01*
G01Y130551D02*
Y132520D01*
G01D02*
Y133701D01*
G01Y127402D02*
Y129370D01*
G01D02*
Y130551D01*
G01Y124252D02*
Y126221D01*
G01D02*
Y127402D01*
G01Y123071D02*
Y124252D01*
G01Y121103D02*
Y123071D01*
G01Y117953D02*
Y119921D01*
G01D02*
Y121103D01*
G01Y116772D02*
Y117953D01*
G01X79612Y134114D02*
X79645Y133950D01*
G01X79629Y132520D02*
X79645Y132441D01*
G01X79612Y132605D02*
X79629Y132520D01*
G01X78774Y133524D02*
X78741Y133688D01*
G01X78075Y133701D02*
X78071Y133721D01*
G01X78104Y133556D02*
X78075Y133701D01*
G01X78104Y132113D02*
X78071Y132277D01*
G01X79444Y133950D02*
X79411Y134081D01*
G01X79449Y132520D02*
X79478Y132408D01*
G01X79444Y132540D02*
X79449Y132520D01*
G01X78908Y134016D02*
X78942Y133884D01*
G01Y133688D02*
X78975Y133556D01*
G01X78942Y132146D02*
X78908Y132277D01*
G01X78746Y132520D02*
X78774Y132408D01*
G01X78741Y132540D02*
X78746Y132520D01*
G01X78272Y132146D02*
X78238Y132277D01*
G01X78741Y133884D02*
X78707Y133983D01*
G01X78272Y133688D02*
X78305Y133589D01*
G01Y134278D02*
X78439Y134311D01*
G01X78842Y134147D02*
X78908Y134016D01*
G01X79377Y132671D02*
X79444Y132540D01*
G01X78842Y133392D02*
X78774Y133524D01*
G01X78808Y132736D02*
X78842Y132671D01*
G01X79009Y132014D02*
X78942Y132146D01*
G01X78875Y131949D02*
X78842Y132014D01*
G01X79512Y134278D02*
X79612Y134114D01*
G01X79512Y132769D02*
X79612Y132605D01*
G01X78205Y131949D02*
X78104Y132113D01*
G01X78707Y133983D02*
X78640Y134081D01*
G01X78975Y133556D02*
X79042Y133458D01*
G01X78205Y133425D02*
X78104Y133556D01*
G01X78640Y132671D02*
X78741Y132540D01*
G01X78975Y131817D02*
X78875Y131949D01*
G01X78372Y132014D02*
X78272Y132146D01*
G01X70866Y135374D02*
X88110D01*
G01X74803Y135276D02*
X78937D01*
G01Y134685D02*
X75590D01*
G01X78439Y134311D02*
X78573D01*
G01X78540Y134114D02*
X78473D01*
G01X73228Y133799D02*
X70866D01*
G01X68110Y133701D02*
X80118D01*
G01X79143Y133392D02*
X79243D01*
G01X79277Y133195D02*
X79109D01*
G01X79143Y132933D02*
X79243D01*
G01X78473Y132900D02*
X78573D01*
G01X79143Y132769D02*
X79243D01*
G01X78473Y132736D02*
X78540D01*
G01X68110Y132520D02*
X80118D01*
G01X73228Y132421D02*
X70866D01*
G01X78540Y131949D02*
X78473D01*
G01X79243Y131916D02*
X79143D01*
G01X78573Y131785D02*
X78473D01*
G01X79243Y131752D02*
X79143D01*
G01X73228Y130650D02*
X70866D01*
G01X68110Y130551D02*
X80118D01*
G01X68110Y129370D02*
X80118D01*
G01X73228Y129272D02*
X70866D01*
G01X73228Y127500D02*
X70866D01*
G01X68110Y127402D02*
X80118D01*
G01X68110Y126221D02*
X80118D01*
G01X73228Y126122D02*
X70866D01*
G01X73228Y124351D02*
X70866D01*
G01X68110Y124252D02*
X80118D01*
G01X68110Y123071D02*
X80118D01*
G01X73228Y122973D02*
X70866D01*
G01X73228Y121201D02*
X70866D01*
G01X68110Y121103D02*
X80118D01*
G01X68110Y119921D02*
X80118D01*
G01X73228Y119823D02*
X70866D01*
G01X73228Y118051D02*
X70866D01*
G01X68110Y117953D02*
X80118D01*
G01X68110Y116772D02*
X80118D01*
G01X73228Y116673D02*
X70866D01*
G01X79411Y134081D02*
X79310Y134180D01*
G01X78707Y134278D02*
X78842Y134147D01*
G01X79411Y132867D02*
X79512Y132769D01*
G01X78975Y133261D02*
X78842Y133392D01*
G01X78305Y133589D02*
X78372Y133524D01*
G01X78707Y132835D02*
X78808Y132736D01*
G01X78305Y131851D02*
X78205Y131949D01*
G01X79243Y132769D02*
X79377Y132671D01*
G01X78339Y133327D02*
X78205Y133425D01*
G01X79143Y131916D02*
X79009Y132014D01*
G01X79042Y133458D02*
X79143Y133392D01*
G01X78540Y132736D02*
X78640Y132671D01*
G01X78473Y131949D02*
X78372Y132014D01*
G01X79344Y134377D02*
X79512Y134278D01*
G01X79109Y133195D02*
X78975Y133261D01*
G01X78372Y133524D02*
X78439Y133491D01*
G01X78573Y132900D02*
X78707Y132835D01*
G01X79243Y132933D02*
X79411Y132867D01*
G01X79143Y131752D02*
X78975Y131817D01*
G01X78473Y131785D02*
X78305Y131851D01*
G01X79310Y134180D02*
X79210Y134213D01*
G01X78640Y134081D02*
X78540Y134114D01*
G01X78439Y133294D02*
X78339Y133327D01*
G01X75590Y131732D02*
X73228Y132421D01*
G01X75590Y128583D02*
X73228Y129272D01*
G01X75590Y125433D02*
X73228Y126122D01*
G01X75590Y122284D02*
X73228Y122973D01*
G01X75590Y119134D02*
X73228Y119823D01*
G01X75590Y115984D02*
X73228Y116673D01*
G01X79210Y134410D02*
X79344Y134377D01*
G01X78573Y134311D02*
X78707Y134278D01*
G01X79527Y137047D02*
X82677Y138228D01*
G01X79527Y142047D02*
X82677Y143228D01*
G01X79527Y147047D02*
X82677Y148228D01*
G01X79527Y152047D02*
X82677Y153228D01*
G01X79527Y157047D02*
X82677Y158228D01*
G01X82008Y141949D02*
Y140374D01*
G01Y146949D02*
Y145374D01*
G01Y151949D02*
Y150374D01*
G01Y156949D02*
Y155374D01*
G01X80433Y141949D02*
Y140374D01*
G01Y146949D02*
Y145374D01*
G01Y151949D02*
Y150374D01*
G01Y156949D02*
Y155374D01*
G01X77756Y142284D02*
Y145040D01*
G01X74803Y137047D02*
Y136949D01*
G01Y140374D02*
Y140276D01*
G01Y142047D02*
Y141949D01*
G01Y145374D02*
Y145276D01*
G01Y141949D02*
Y140374D01*
G01Y147047D02*
Y146949D01*
G01Y150374D02*
Y150276D01*
G01Y146949D02*
Y145374D01*
G01Y152047D02*
Y151949D01*
G01Y155374D02*
Y155276D01*
G01Y151949D02*
Y150374D01*
G01Y157047D02*
Y156949D01*
G01D02*
Y155374D01*
G01X79527Y157047D02*
X74803D01*
G01X70866Y156949D02*
X88110D01*
G01X70866Y155374D02*
X88110D01*
G01X74803Y155276D02*
X79527D01*
G01Y152047D02*
X74803D01*
G01X70866Y151949D02*
X88110D01*
G01X70866Y150374D02*
X88110D01*
G01X74803Y150276D02*
X79527D01*
G01Y147047D02*
X74803D01*
G01X70866Y146949D02*
X88110D01*
G01X70866Y145374D02*
X88110D01*
G01X74803Y145276D02*
X79527D01*
G01X70866Y145040D02*
X77756D01*
G01Y142284D02*
X70866D01*
G01X79527Y142047D02*
X74803D01*
G01X70866Y141949D02*
X88110D01*
G01X70866Y140374D02*
X88110D01*
G01X74803Y140276D02*
X79527D01*
G01Y137047D02*
X74803D01*
G01X70866Y136949D02*
X88110D01*
G01X82677Y154095D02*
X79527Y155276D01*
G01X82677Y149095D02*
X79527Y150276D01*
G01X82677Y144095D02*
X79527Y145276D01*
G01X82677Y139095D02*
X79527Y140276D01*
G01X80708Y178465D02*
G03I-2559J0D01*
G01X81496D02*
G03I-3347J0D01*
G01X81653D02*
G03I-3504J0D01*
G01X78075Y182598D02*
G03X78149Y174331I73J-4133D01*
G01X78224D02*
G03X78149Y182599I-75J4134D01*
G01X79527Y162047D02*
X82677Y163228D01*
G01X79527Y167047D02*
X82677Y168228D01*
G01X82008Y161949D02*
Y160374D01*
G01Y166949D02*
Y165374D01*
G01X80433Y161949D02*
Y160374D01*
G01Y166949D02*
Y165374D01*
G01X74803Y160374D02*
Y160276D01*
G01Y162047D02*
Y161949D01*
G01D02*
Y160374D01*
G01Y165374D02*
Y165276D01*
G01Y167047D02*
Y166949D01*
G01D02*
Y165374D01*
G01X70079Y183248D02*
Y174902D01*
G01X90551Y177854D02*
X70079D01*
G01X90551Y171752D02*
X70866D01*
G01Y169980D02*
X90551D01*
G01X69586D02*
X70866D01*
G01X78224Y174331D02*
X78149D01*
G01X79527Y167047D02*
X74803D01*
G01X70866Y166949D02*
X88110D01*
G01X70866Y165374D02*
X88110D01*
G01X74803Y165276D02*
X79527D01*
G01Y162047D02*
X74803D01*
G01X70866Y161949D02*
X88110D01*
G01X70866Y160374D02*
X88110D01*
G01X74803Y160276D02*
X79527D01*
G01X82677Y164095D02*
X79527Y165276D01*
G01X82677Y159095D02*
X79527Y160276D01*
G01X72638Y190276D02*
G03I-3741J0D01*
G01X78740Y183248D02*
Y196201D01*
G01X78543Y189488D02*
Y191063D01*
G01X73189D02*
Y189488D01*
G01X71850Y191063D02*
Y191260D01*
G01Y189488D02*
Y189291D01*
G01Y191063D02*
Y189488D01*
G01X71653Y191063D02*
Y189488D01*
G01X70079D02*
Y191063D01*
G01X67716Y189488D02*
Y191063D01*
G01X66142Y189488D02*
Y191063D01*
G01X65945Y189488D02*
Y191063D01*
G01Y189488D02*
Y189291D01*
G01Y191260D02*
Y191063D01*
G01X64606Y189488D02*
Y191063D01*
G01X78075Y182598D02*
X78149D01*
G01X72047Y207244D02*
G03Y206063I0J-591D01*
G01Y210000D02*
G03Y208819I0J-591D01*
G01X65748Y206063D02*
G03Y207244I0J590D01*
G01Y208819D02*
G03Y210000I0J590D01*
G01X65759Y206865D02*
X65665Y206753D01*
G01Y206881D02*
X65759Y206992D01*
G01X73622Y205768D02*
Y207736D01*
G01Y210295D02*
Y208327D01*
G01X72047Y207244D02*
Y208819D01*
G01Y210000D02*
Y210591D01*
G01Y205473D02*
Y206063D01*
G01X71063Y205473D02*
Y210591D01*
G01X70866D02*
Y205473D01*
G01X70472Y208327D02*
Y210295D01*
G01Y207736D02*
Y205768D01*
G01X67323Y208327D02*
Y210295D01*
G01Y207736D02*
Y205768D01*
G01X66929Y210591D02*
Y205473D01*
G01X66732D02*
Y210591D01*
G01X65852Y206992D02*
Y206244D01*
G01X65759D02*
Y206865D01*
G01X65748Y206063D02*
Y205473D01*
G01Y208819D02*
Y207244D01*
G01Y210591D02*
Y210000D01*
G01X65665Y206753D02*
Y206881D01*
G01X64173Y205768D02*
Y207736D01*
G01Y210295D02*
Y208327D01*
G01X65748Y210591D02*
X72047D01*
G01Y210295D02*
X73622D01*
G01X70472D02*
X72047D01*
G01X65748D02*
X64173D01*
G01X67323D02*
X65748D01*
G01X64173Y208327D02*
X65748D01*
G01D02*
X67323D01*
G01X73622D02*
X72047D01*
G01D02*
X70472D01*
G01X64173Y207736D02*
X65748D01*
G01D02*
X67323D01*
G01X73622D02*
X72047D01*
G01D02*
X70472D01*
G01X65759Y206992D02*
X65852D01*
G01Y206244D02*
X65759D01*
G01X72047Y205768D02*
X73622D01*
G01X70472D02*
X72047D01*
G01X65748D02*
X64173D01*
G01X67323D02*
X65748D01*
G01Y205473D02*
X72047D01*
G01X80281Y432554D02*
X80167Y432795D01*
G01X80399Y432291D02*
X80281Y432554D01*
G01X80520Y432008D02*
X80399Y432291D01*
G01X75527Y431369D02*
X75545Y431417D01*
G01X75472Y431221D02*
X75527Y431369D01*
G01X75779Y432006D02*
Y432008D01*
G01X75766Y431975D02*
X75779Y432006D01*
G01X75899Y432290D02*
X75779Y432008D01*
G01X76017Y432553D02*
X75899Y432290D01*
G01X76132Y432795D02*
X76017Y432553D01*
G01X80167Y432795D02*
G03Y435945I-2017J1575D01*
G01X76132D02*
G03Y432795I2017J-1575D01*
G01X80520Y432008D02*
G03Y436732I-2371J2362D01*
G01X75779D02*
G03Y432008I2370J-2362D01*
G01X81653Y434370D02*
G03I-3504J0D01*
G01X72638Y422559D02*
G03I-3741J0D01*
G01X75472Y437520D02*
G03Y431221I2677J-3149D01*
G01X80827D02*
G03Y437520I-2678J3149D01*
G01X75725Y431878D02*
X75766Y431975D01*
G01X75647Y431683D02*
X75725Y431878D01*
G01X75615Y431600D02*
X75647Y431683D01*
G01X75580Y431511D02*
X75615Y431600D01*
G01X75545Y431417D02*
X75580Y431511D01*
G01X78740Y416634D02*
Y429587D01*
G01X78543Y421772D02*
Y423347D01*
G01X73189D02*
Y421772D01*
G01X71850Y423347D02*
Y423543D01*
G01Y421772D02*
Y421575D01*
G01Y423347D02*
Y421772D01*
G01X71653Y423347D02*
Y421772D01*
G01X70079Y429587D02*
Y437933D01*
G01Y421772D02*
Y423347D01*
G01X67716Y421772D02*
Y423347D01*
G01X66142Y421772D02*
Y423347D01*
G01X65945Y421772D02*
Y423347D01*
G01Y421772D02*
Y421575D01*
G01Y423543D02*
Y423347D01*
G01X64606Y421772D02*
Y423347D01*
G01X80167Y432795D02*
X76132D01*
G01X75779Y432008D02*
X80520D01*
G01X80827Y431221D02*
X75472D01*
G01X80772Y431369D02*
X80827Y431221D01*
G01X80736Y431464D02*
X80772Y431369D01*
G01X80701Y431556D02*
X80736Y431464D01*
G01X80668Y431642D02*
X80701Y431556D01*
G01X80596Y431821D02*
X80668Y431642D01*
G01X80563Y431902D02*
X80596Y431821D01*
G01X80520Y432008D02*
X80563Y431902D01*
G01X75895Y436460D02*
X75779Y436732D01*
G01X76013Y436197D02*
X75895Y436460D01*
G01X76132Y435945D02*
X76013Y436197D01*
G01X80520Y436734D02*
Y436732D01*
G01X80533Y436765D02*
X80520Y436734D01*
G01X80286Y436197D02*
X80167Y435945D01*
G01X80404Y436460D02*
X80286Y436197D01*
G01X80520Y436732D02*
X80404Y436460D01*
G01X79527Y447559D02*
X82677Y448740D01*
G01X79527Y452559D02*
X82677Y453740D01*
G01X80573Y436863D02*
X80533Y436765D01*
G01X80652Y437058D02*
X80573Y436863D01*
G01X80684Y437140D02*
X80652Y437058D01*
G01X80719Y437229D02*
X80684Y437140D01*
G01X80754Y437323D02*
X80719Y437229D01*
G01X80790Y437421D02*
X80754Y437323D01*
G01X80827Y437520D02*
X80790Y437421D01*
G01X82008Y447461D02*
Y445886D01*
G01Y452461D02*
Y450886D01*
G01X80433Y447461D02*
Y445886D01*
G01Y452461D02*
Y450886D01*
G01X74803Y445886D02*
Y445788D01*
G01Y447559D02*
Y447461D01*
G01D02*
Y445886D01*
G01Y450886D02*
Y450788D01*
G01Y452559D02*
Y452461D01*
G01D02*
Y450886D01*
G01X70866Y441083D02*
Y460886D01*
G01X69586Y442854D02*
Y575492D01*
G01X68208D02*
Y442854D01*
G01X66929D02*
Y575492D01*
G01X79527Y452559D02*
X74803D01*
G01X70866Y452461D02*
X88110D01*
G01X70866Y450886D02*
X88110D01*
G01X74803Y450788D02*
X79527D01*
G01Y447559D02*
X74803D01*
G01X70866Y447461D02*
X88110D01*
G01X70866Y445886D02*
X88110D01*
G01X74803Y445788D02*
X79527D01*
G01X69586Y442854D02*
X70866D01*
G01X90551D02*
X70866D01*
G01Y441083D02*
X90551D01*
G01X75472Y437520D02*
X80827D01*
G01X80520Y436732D02*
X75779D01*
G01X80167Y435945D02*
X76132D01*
G01X70079Y434980D02*
X90551D01*
G01X75527Y437372D02*
X75472Y437520D01*
G01X75562Y437276D02*
X75527Y437372D01*
G01X75597Y437184D02*
X75562Y437276D01*
G01X75631Y437098D02*
X75597Y437184D01*
G01X75703Y436919D02*
X75631Y437098D01*
G01X75736Y436838D02*
X75703Y436919D01*
G01X75779Y436732D02*
X75736Y436838D01*
G01X82677Y449606D02*
X79527Y450788D01*
G01X82677Y444606D02*
X79527Y445788D01*
G01Y457559D02*
X82677Y458740D01*
G01X79527Y467559D02*
X82677Y468740D01*
G01X79527Y472559D02*
X82677Y473740D01*
G01X77559Y462559D02*
X82677Y463740D01*
G01X82008Y457461D02*
Y455886D01*
G01Y462461D02*
Y460886D01*
G01Y467461D02*
Y465886D01*
G01Y472461D02*
Y470886D01*
G01X80433Y457461D02*
Y455886D01*
G01Y462461D02*
Y460886D01*
G01Y467461D02*
Y465886D01*
G01Y472461D02*
Y470886D01*
G01X77756Y462795D02*
Y465551D01*
G01X74803Y455886D02*
Y455788D01*
G01Y457559D02*
Y457461D01*
G01D02*
Y455886D01*
G01Y465886D02*
Y465788D01*
G01Y467559D02*
Y467461D01*
G01D02*
Y465886D01*
G01Y470886D02*
Y470788D01*
G01Y472559D02*
Y472461D01*
G01D02*
Y470886D01*
G01X72834Y460886D02*
Y460788D01*
G01Y462559D02*
Y462461D01*
G01D02*
Y460886D01*
G01X70866D02*
Y462461D01*
G01D02*
Y500886D01*
G01X69685Y464036D02*
Y459311D01*
G01X79527Y472559D02*
X74803D01*
G01X70866Y472461D02*
X88110D01*
G01X70866Y470886D02*
X88110D01*
G01X74803Y470788D02*
X79527D01*
G01Y467559D02*
X74803D01*
G01X70866Y467461D02*
X88110D01*
G01X70866Y465886D02*
X88110D01*
G01X74803Y465788D02*
X79527D01*
G01X70866Y465551D02*
X77756D01*
G01X70866Y464036D02*
X69685D01*
G01X77756Y462795D02*
X70866D01*
G01X77559Y462559D02*
X72834D01*
G01X69685Y462461D02*
X89567D01*
G01X69685Y460886D02*
X89567D01*
G01X72834Y460788D02*
X77559D01*
G01X69685Y459311D02*
X70866D01*
G01X79527Y457559D02*
X74803D01*
G01X70866Y457461D02*
X88110D01*
G01X70866Y455886D02*
X88110D01*
G01X74803Y455788D02*
X79527D01*
G01X82677Y474606D02*
X79527Y475788D01*
G01X82677Y469606D02*
X79527Y470788D01*
G01X82677Y464606D02*
X79527Y465788D01*
G01X82677Y454606D02*
X79527Y455788D01*
G01X82677Y459606D02*
X77559Y460788D01*
G01X79527Y477559D02*
X82677Y478740D01*
G01X79527Y482559D02*
X82677Y483740D01*
G01X79527Y487559D02*
X82677Y488740D01*
G01X79527Y492559D02*
X82677Y493740D01*
G01X82008Y477461D02*
Y475886D01*
G01Y482461D02*
Y480886D01*
G01Y487461D02*
Y485886D01*
G01Y492461D02*
Y490886D01*
G01Y497461D02*
Y495886D01*
G01X80433Y477461D02*
Y475886D01*
G01Y482461D02*
Y480886D01*
G01Y487461D02*
Y485886D01*
G01Y492461D02*
Y490886D01*
G01Y497461D02*
Y495886D01*
G01X77756Y487795D02*
Y490551D01*
G01X74803Y475886D02*
Y475788D01*
G01Y477559D02*
Y477461D01*
G01D02*
Y475886D01*
G01Y480886D02*
Y480788D01*
G01Y482559D02*
Y482461D01*
G01D02*
Y480886D01*
G01Y485886D02*
Y485788D01*
G01Y487559D02*
Y487461D01*
G01D02*
Y485886D01*
G01Y490886D02*
Y490788D01*
G01Y492559D02*
Y492461D01*
G01D02*
Y490886D01*
G01Y495886D02*
Y495788D01*
G01Y497461D02*
Y495886D01*
G01X70866D02*
X88110D01*
G01X74803Y495788D02*
X79527D01*
G01Y492559D02*
X74803D01*
G01X70866Y492461D02*
X88110D01*
G01X70866Y490886D02*
X88110D01*
G01X74803Y490788D02*
X79527D01*
G01X70866Y490551D02*
X77756D01*
G01Y487795D02*
X70866D01*
G01X79527Y487559D02*
X74803D01*
G01X70866Y487461D02*
X88110D01*
G01X70866Y485886D02*
X88110D01*
G01X74803Y485788D02*
X79527D01*
G01Y482559D02*
X74803D01*
G01X70866Y482461D02*
X88110D01*
G01X70866Y480886D02*
X88110D01*
G01X74803Y480788D02*
X79527D01*
G01Y477559D02*
X74803D01*
G01X70866Y477461D02*
X88110D01*
G01X70866Y475886D02*
X88110D01*
G01X74803Y475788D02*
X79527D01*
G01X82677Y494606D02*
X79527Y495788D01*
G01X82677Y489606D02*
X79527Y490788D01*
G01X82677Y484606D02*
X79527Y485788D01*
G01X82677Y479606D02*
X79527Y480788D01*
G01Y497559D02*
X82677Y498740D01*
G01X79527Y507559D02*
X82677Y508740D01*
G01X79527Y512559D02*
X82677Y513740D01*
G01X77559Y502559D02*
X82677Y503740D01*
G01X82008Y502461D02*
Y500886D01*
G01Y507461D02*
Y505886D01*
G01Y512461D02*
Y510886D01*
G01Y517461D02*
Y515886D01*
G01X80433Y502461D02*
Y500886D01*
G01Y507461D02*
Y505886D01*
G01Y512461D02*
Y510886D01*
G01Y517461D02*
Y515886D01*
G01X77756Y512795D02*
Y515551D01*
G01X74803Y497559D02*
Y497461D01*
G01Y505886D02*
Y505788D01*
G01Y507559D02*
Y507461D01*
G01Y510886D02*
Y510788D01*
G01Y507461D02*
Y505886D01*
G01Y512559D02*
Y512461D01*
G01Y515886D02*
Y515788D01*
G01Y512461D02*
Y510886D01*
G01Y517461D02*
Y515886D01*
G01X70866D02*
X89567D01*
G01X74803Y515788D02*
X79527D01*
G01X70866Y515551D02*
X77756D01*
G01Y512795D02*
X70866D01*
G01X79527Y512559D02*
X74803D01*
G01X70866Y512461D02*
X88110D01*
G01X70866Y510886D02*
X88110D01*
G01X74803Y510788D02*
X79527D01*
G01Y507559D02*
X74803D01*
G01X70866Y507461D02*
X88110D01*
G01X70866Y505886D02*
X88110D01*
G01X74803Y505788D02*
X79527D01*
G01X70866Y504036D02*
X69685D01*
G01X77559Y502559D02*
X72834D01*
G01X69685Y502461D02*
X89567D01*
G01X69685Y500886D02*
X89567D01*
G01X72834Y500788D02*
X77559D01*
G01X69685Y499311D02*
X70866D01*
G01X79527Y497559D02*
X74803D01*
G01X70866Y497461D02*
X88110D01*
G01X72834Y500886D02*
Y500788D01*
G01Y502559D02*
Y502461D01*
G01D02*
Y500886D01*
G01X70866D02*
Y502461D01*
G01D02*
Y519134D01*
G01X69685Y504036D02*
Y499311D01*
G01X68110Y541378D02*
Y516969D01*
G01X82677Y499606D02*
X77559Y500788D01*
G01X82677Y514606D02*
X79527Y515788D01*
G01X82677Y509606D02*
X79527Y510788D01*
G01X82677Y504606D02*
X79527Y505788D01*
G01X73228Y520414D02*
X75590Y521103D01*
G01X73228Y523563D02*
X75590Y524252D01*
G01X73228Y526713D02*
X75590Y527402D01*
G01X73228Y529862D02*
X75590Y530551D01*
G01X73228Y533012D02*
X75590Y533701D01*
G01X73228Y536162D02*
X75590Y536851D01*
G01X79411Y537329D02*
X79243Y537264D01*
G01X78975Y538379D02*
X79143Y538445D01*
G01X78305Y538347D02*
X78473Y538412D01*
G01X78707Y537362D02*
X78573Y537297D01*
G01X78640Y537526D02*
X78540Y537461D01*
G01X78372Y538182D02*
X78473Y538248D01*
G01X79377Y537526D02*
X79243Y537428D01*
G01X79009Y538182D02*
X79143Y538281D01*
G01X79512Y537428D02*
X79411Y537329D01*
G01X78808Y537461D02*
X78707Y537362D01*
G01X78205Y538248D02*
X78305Y538347D01*
G01X78741Y537658D02*
X78640Y537526D01*
G01X78875Y538248D02*
X78975Y538379D01*
G01X78272Y538051D02*
X78372Y538182D01*
G01X79612Y537592D02*
X79512Y537428D01*
G01X78104Y538084D02*
X78205Y538248D01*
G01X79444Y537658D02*
X79377Y537526D01*
G01X78842D02*
X78808Y537461D01*
G01X78942Y538051D02*
X79009Y538182D01*
G01X78842D02*
X78875Y538248D01*
G01X79478Y537789D02*
X79444Y537658D01*
G01X78908Y537920D02*
X78937Y538032D01*
G01D02*
X78942Y538051D01*
G01X78774Y537789D02*
X78741Y537658D01*
G01X78267Y538032D02*
X78272Y538051D01*
G01X78238Y537920D02*
X78267Y538032D01*
G01X79645Y537756D02*
X79612Y537592D01*
G01X78071Y537920D02*
X78093Y538032D01*
G01D02*
X78104Y538084D01*
G01X80118Y520315D02*
Y519134D01*
G01Y523465D02*
Y522284D01*
G01Y529764D02*
Y528583D01*
G01Y526614D02*
Y525433D01*
G01Y532914D02*
Y531732D01*
G01Y536063D02*
Y534882D01*
G01Y539213D02*
Y538032D01*
G01X79645Y537953D02*
Y537756D01*
G01X79478Y537920D02*
Y537789D01*
G01X78937Y518150D02*
Y517559D01*
G01X78908Y537789D02*
Y537920D01*
G01X78774D02*
Y537789D01*
G01X78238D02*
Y537920D01*
G01X78071Y537789D02*
Y537920D01*
G01X75590Y518347D02*
Y518150D01*
G01Y524646D02*
Y524252D01*
G01Y521496D02*
Y521103D01*
G01Y527795D02*
Y527402D01*
G01Y534095D02*
Y533701D01*
G01Y530945D02*
Y530551D01*
G01Y537244D02*
Y536851D01*
G01X75512Y538032D02*
Y539213D01*
G01Y534882D02*
Y536063D01*
G01Y531732D02*
Y532914D01*
G01Y525433D02*
Y526614D01*
G01Y528583D02*
Y529764D01*
G01Y522284D02*
Y523465D01*
G01Y519134D02*
Y520315D01*
G01X75118D02*
Y519134D01*
G01Y523465D02*
Y522284D01*
G01Y529764D02*
Y528583D01*
G01Y526614D02*
Y525433D01*
G01Y532914D02*
Y531732D01*
G01Y536063D02*
Y534882D01*
G01Y539213D02*
Y538032D01*
G01X74803Y517559D02*
Y517461D01*
G01X74330Y520315D02*
Y519134D01*
G01Y523465D02*
Y522284D01*
G01Y526614D02*
Y525433D01*
G01Y529764D02*
Y528583D01*
G01Y532914D02*
Y531732D01*
G01Y539213D02*
Y538032D01*
G01Y536063D02*
Y534882D01*
G01X79143Y538445D02*
X79243D01*
G01X78473Y538412D02*
X78573D01*
G01X79143Y538281D02*
X79243D01*
G01X78473Y538248D02*
X78540D01*
G01X68110Y538032D02*
X80118D01*
G01X73228Y537933D02*
X70866D01*
G01X78540Y537461D02*
X78473D01*
G01X79243Y537428D02*
X79143D01*
G01X78573Y537297D02*
X78473D01*
G01X79243Y537264D02*
X79143D01*
G01X73228Y536162D02*
X70866D01*
G01X68110Y536063D02*
X80118D01*
G01X68110Y534882D02*
X80118D01*
G01X73228Y534784D02*
X70866D01*
G01X73228Y533012D02*
X70866D01*
G01X68110Y532914D02*
X80118D01*
G01X68110Y531732D02*
X80118D01*
G01X73228Y531634D02*
X70866D01*
G01X73228Y529862D02*
X70866D01*
G01X68110Y529764D02*
X80118D01*
G01X68110Y528583D02*
X80118D01*
G01X73228Y528484D02*
X70866D01*
G01X73228Y526713D02*
X70866D01*
G01X68110Y526614D02*
X80118D01*
G01X68110Y525433D02*
X80118D01*
G01X73228Y525335D02*
X70866D01*
G01X73228Y523563D02*
X70866D01*
G01X68110Y523465D02*
X80118D01*
G01X68110Y522284D02*
X80118D01*
G01X73228Y522185D02*
X70866D01*
G01X73228Y520414D02*
X70866D01*
G01X68110Y520315D02*
X80118D01*
G01X68110Y519134D02*
X80118D01*
G01X73228Y519036D02*
X70866D01*
G01X75590Y518150D02*
X78937D01*
G01Y517559D02*
X74803D01*
G01X70866Y517461D02*
X89567D01*
G01X72756Y520315D02*
Y519134D01*
G01Y523465D02*
Y522284D01*
G01Y526614D02*
Y525433D01*
G01Y529764D02*
Y528583D01*
G01Y532914D02*
Y531732D01*
G01Y539213D02*
Y538032D01*
G01Y536063D02*
Y534882D01*
G01X70866Y536063D02*
Y538032D01*
G01D02*
Y539213D01*
G01Y534882D02*
Y536063D01*
G01Y532914D02*
Y534882D01*
G01Y529764D02*
Y531732D01*
G01D02*
Y532914D01*
G01Y526614D02*
Y528583D01*
G01D02*
Y529764D01*
G01Y525433D02*
Y526614D01*
G01Y523465D02*
Y525433D01*
G01Y520315D02*
Y522284D01*
G01D02*
Y523465D01*
G01Y519134D02*
Y520315D01*
G01X79629Y538032D02*
X79645Y537953D01*
G01X79612Y538117D02*
X79629Y538032D01*
G01X78104Y537625D02*
X78071Y537789D01*
G01X79449Y538032D02*
X79478Y537920D01*
G01X79444Y538051D02*
X79449Y538032D01*
G01X78942Y537658D02*
X78908Y537789D01*
G01X78746Y538032D02*
X78774Y537920D01*
G01X78741Y538051D02*
X78746Y538032D01*
G01X78272Y537658D02*
X78238Y537789D01*
G01X79243Y538445D02*
X79411Y538379D01*
G01X79143Y537264D02*
X78975Y537329D01*
G01X78473Y537297D02*
X78305Y537362D01*
G01X75590Y537244D02*
X73228Y537933D01*
G01X75590Y534095D02*
X73228Y534784D01*
G01X75590Y530945D02*
X73228Y531634D01*
G01X75590Y527795D02*
X73228Y528484D01*
G01X75590Y524646D02*
X73228Y525335D01*
G01X75590Y521496D02*
X73228Y522185D01*
G01X75590Y518347D02*
X73228Y519036D01*
G01X79377Y538182D02*
X79444Y538051D01*
G01X78808Y538248D02*
X78842Y538182D01*
G01X79009Y537526D02*
X78942Y537658D01*
G01X78875Y537461D02*
X78842Y537526D01*
G01X79512Y538281D02*
X79612Y538117D01*
G01X78205Y537461D02*
X78104Y537625D01*
G01X78640Y538182D02*
X78741Y538051D01*
G01X78975Y537329D02*
X78875Y537461D01*
G01X78372Y537526D02*
X78272Y537658D01*
G01X79411Y538379D02*
X79512Y538281D01*
G01X78707Y538347D02*
X78808Y538248D01*
G01X78305Y537362D02*
X78205Y537461D01*
G01X79243Y538281D02*
X79377Y538182D01*
G01X79143Y537428D02*
X79009Y537526D01*
G01X78540Y538248D02*
X78640Y538182D01*
G01X78473Y537461D02*
X78372Y537526D01*
G01X78573Y538412D02*
X78707Y538347D01*
G01X73228Y539311D02*
X75590Y540000D01*
G01X78473Y539626D02*
X78372Y539593D01*
G01X79527Y542559D02*
X82677Y543740D01*
G01X79527Y547559D02*
X82677Y548740D01*
G01X79527Y552559D02*
X82677Y553740D01*
G01X79527Y557559D02*
X82677Y558740D01*
G01X79411Y538773D02*
X79277Y538707D01*
G01X79243Y538904D02*
X79344Y538970D01*
G01X79545Y538904D02*
X79411Y538773D01*
G01X78171Y539659D02*
X78305Y539790D01*
G01X79344Y538970D02*
X79411Y539068D01*
G01X78372Y539593D02*
X78305Y539495D01*
G01X79612Y539036D02*
X79545Y538904D01*
G01X78104Y539528D02*
X78171Y539659D01*
G01X78305Y539495D02*
X78272Y539396D01*
G01X78305Y539790D02*
X78439Y539823D01*
G01X79411Y539068D02*
X79444Y539199D01*
G01X78071Y539396D02*
X78104Y539528D01*
G01X79645Y539199D02*
X79612Y539036D01*
G01X79527Y557559D02*
X74803D01*
G01X70866Y557461D02*
X88110D01*
G01X70866Y555886D02*
X88110D01*
G01X74803Y555788D02*
X79527D01*
G01Y552559D02*
X74803D01*
G01X70866Y552461D02*
X88110D01*
G01X70866Y550886D02*
X88110D01*
G01X74803Y550788D02*
X79527D01*
G01X70866Y550551D02*
X77756D01*
G01X82008Y542461D02*
Y540886D01*
G01Y547461D02*
Y545886D01*
G01Y552461D02*
Y550886D01*
G01Y557461D02*
Y555886D01*
G01X80433Y542461D02*
Y540886D01*
G01Y547461D02*
Y545886D01*
G01Y552461D02*
Y550886D01*
G01Y557461D02*
Y555886D01*
G01X79645Y539462D02*
Y539213D01*
G01D02*
Y539199D01*
G01X79444Y539213D02*
Y539462D01*
G01Y539199D02*
Y539213D01*
G01X79210Y539725D02*
Y539921D01*
G01X78942Y539396D02*
Y539213D01*
G01D02*
Y539199D01*
G01X78937Y540788D02*
Y540197D01*
G01X78741Y539213D02*
Y539396D01*
G01Y539199D02*
Y539213D01*
G01X78439Y539003D02*
Y538806D01*
G01X78272Y539396D02*
Y539213D01*
G01D02*
Y539199D01*
G01X78071Y539232D02*
Y539396D01*
G01X77756Y547795D02*
Y550551D01*
G01X75590Y540197D02*
Y540000D01*
G01X74803Y540886D02*
Y540788D01*
G01Y542559D02*
Y542461D01*
G01D02*
Y540886D01*
G01Y545886D02*
Y545788D01*
G01Y547559D02*
Y547461D01*
G01D02*
Y545886D01*
G01Y550886D02*
Y550788D01*
G01Y552559D02*
Y552461D01*
G01D02*
Y550886D01*
G01Y555886D02*
Y555788D01*
G01Y557559D02*
Y557461D01*
G01D02*
Y555886D01*
G01X79612Y539626D02*
X79645Y539462D01*
G01X77756Y547795D02*
X70866D01*
G01X79527Y547559D02*
X74803D01*
G01X70866Y547461D02*
X88110D01*
G01X70866Y545886D02*
X88110D01*
G01X74803Y545788D02*
X79527D01*
G01Y542559D02*
X74803D01*
G01X70866Y542461D02*
X88110D01*
G01X70866Y540886D02*
X88110D01*
G01X74803Y540788D02*
X78937D01*
G01Y540197D02*
X75590D01*
G01X78439Y539823D02*
X78573D01*
G01X78540Y539626D02*
X78473D01*
G01X73228Y539311D02*
X70866D01*
G01X68110Y539213D02*
X80118D01*
G01X79143Y538904D02*
X79243D01*
G01X79277Y538707D02*
X79109D01*
G01X70866Y539213D02*
Y577264D01*
G01X78774Y539036D02*
X78741Y539199D01*
G01X78075Y539213D02*
X78071Y539232D01*
G01X78104Y539068D02*
X78075Y539213D01*
G01X79444Y539462D02*
X79411Y539593D01*
G01X78908Y539528D02*
X78942Y539396D01*
G01Y539199D02*
X78975Y539068D01*
G01X78741Y539396D02*
X78707Y539495D01*
G01X78272Y539199D02*
X78305Y539101D01*
G01X82677Y554606D02*
X79527Y555788D01*
G01X82677Y549606D02*
X79527Y550788D01*
G01X82677Y544606D02*
X79527Y545788D01*
G01X79310Y539691D02*
X79210Y539725D01*
G01X78640Y539593D02*
X78540Y539626D01*
G01X78439Y538806D02*
X78339Y538839D01*
G01X79210Y539921D02*
X79344Y539888D01*
G01X78573Y539823D02*
X78707Y539790D01*
G01X78842Y539659D02*
X78908Y539528D01*
G01X78842Y538904D02*
X78774Y539036D01*
G01X79512Y539790D02*
X79612Y539626D01*
G01X78707Y539495D02*
X78640Y539593D01*
G01X78975Y539068D02*
X79042Y538970D01*
G01X78205Y538937D02*
X78104Y539068D01*
G01X79411Y539593D02*
X79310Y539691D01*
G01X78707Y539790D02*
X78842Y539659D01*
G01X78975Y538773D02*
X78842Y538904D01*
G01X78305Y539101D02*
X78372Y539036D01*
G01X78339Y538839D02*
X78205Y538937D01*
G01X79042Y538970D02*
X79143Y538904D01*
G01X79344Y539888D02*
X79512Y539790D01*
G01X79109Y538707D02*
X78975Y538773D01*
G01X78372Y539036D02*
X78439Y539003D01*
G01X81496Y583977D02*
G03I-3347J0D01*
G01X81653D02*
G03I-3504J0D01*
G01X78075Y588110D02*
G03X78149Y579843I73J-4133D01*
G01X78224D02*
G03X78149Y588110I-75J4133D01*
G01X79527Y562559D02*
X82677Y563740D01*
G01X79527Y567559D02*
X82677Y568740D01*
G01X79527Y572559D02*
X82677Y573740D01*
G01X90551Y577264D02*
X70866D01*
G01Y575492D02*
X90551D01*
G01X69586D02*
X70866D01*
G01X79527Y572559D02*
X74803D01*
G01X70866Y572461D02*
X88110D01*
G01X70866Y570886D02*
X88110D01*
G01X74803Y570788D02*
X79527D01*
G01Y567559D02*
X74803D01*
G01X70866Y567461D02*
X88110D01*
G01X70866Y565886D02*
X88110D01*
G01X74803Y565788D02*
X79527D01*
G01Y562559D02*
X74803D01*
G01X70866Y562461D02*
X88110D01*
G01X70866Y560886D02*
X88110D01*
G01X74803Y560788D02*
X79527D01*
G01X78224Y579843D02*
X78149D01*
G01X82008Y562461D02*
Y560886D01*
G01Y567461D02*
Y565886D01*
G01Y572461D02*
Y570886D01*
G01X80433Y562461D02*
Y560886D01*
G01Y567461D02*
Y565886D01*
G01Y572461D02*
Y570886D01*
G01X74803Y560886D02*
Y560788D01*
G01Y562559D02*
Y562461D01*
G01D02*
Y560886D01*
G01Y565886D02*
Y565788D01*
G01Y567559D02*
Y567461D01*
G01D02*
Y565886D01*
G01Y570886D02*
Y570788D01*
G01Y572559D02*
Y572461D01*
G01D02*
Y570886D01*
G01X70079Y588760D02*
Y580414D01*
G01X82677Y569606D02*
X79527Y570788D01*
G01X82677Y564606D02*
X79527Y565788D01*
G01X82677Y559606D02*
X79527Y560788D01*
G01X80708Y583977D02*
G03I-2559J0D01*
G01X72638Y595788D02*
G03I-3741J0D01*
G01X90551Y583366D02*
X70079D01*
G01X78075Y588110D02*
X78149D01*
G01X78740Y588760D02*
Y601713D01*
G01X78543Y595000D02*
Y596575D01*
G01X73189D02*
Y595000D01*
G01X71850Y596575D02*
Y596772D01*
G01Y595000D02*
Y594803D01*
G01Y596575D02*
Y595000D01*
G01X71653Y596575D02*
Y595000D01*
G01X70079D02*
Y596575D01*
G01X67716Y595000D02*
Y596575D01*
G01X66142Y595000D02*
Y596575D01*
G01X65945Y595000D02*
Y596575D01*
G01Y595000D02*
Y594803D01*
G01Y596772D02*
Y596575D01*
G01X64606Y595000D02*
Y596575D01*
G01X72047Y612756D02*
G03Y611575I0J-591D01*
G01X65748D02*
G03Y612756I0J590D01*
G01Y614331D02*
G03Y615512I0J590D01*
G01X72047D02*
G03Y614331I0J-591D01*
G01X65759Y612377D02*
X65665Y612265D01*
G01Y612393D02*
X65759Y612504D01*
G01X65748Y616103D02*
X72047D01*
G01Y615807D02*
X73622D01*
G01X70472D02*
X72047D01*
G01X65748D02*
X64173D01*
G01X67323D02*
X65748D01*
G01X64173Y613839D02*
X65748D01*
G01D02*
X67323D01*
G01X73622D02*
X72047D01*
G01D02*
X70472D01*
G01X64173Y613248D02*
X65748D01*
G01D02*
X67323D01*
G01X73622D02*
X72047D01*
G01D02*
X70472D01*
G01X65759Y612504D02*
X65852D01*
G01Y611756D02*
X65759D01*
G01X72047Y611280D02*
X73622D01*
G01X70472D02*
X72047D01*
G01X65748D02*
X64173D01*
G01X67323D02*
X65748D01*
G01Y610984D02*
X72047D01*
G01X73622Y611280D02*
Y613248D01*
G01Y615807D02*
Y613839D01*
G01X72047Y615512D02*
Y616103D01*
G01Y612756D02*
Y614331D01*
G01Y610984D02*
Y611575D01*
G01X71063Y610984D02*
Y616103D01*
G01X70866D02*
Y610984D01*
G01X70472Y613839D02*
Y615807D01*
G01Y613248D02*
Y611280D01*
G01X67323Y613839D02*
Y615807D01*
G01Y613248D02*
Y611280D01*
G01X66929Y616103D02*
Y610984D01*
G01X66732D02*
Y616103D01*
G01X65852Y612504D02*
Y611756D01*
G01X65759D02*
Y612377D01*
G01X65748Y611575D02*
Y610984D01*
G01Y614331D02*
Y612756D01*
G01Y616103D02*
Y615512D01*
G01X65665Y612265D02*
Y612393D01*
G01X64173Y611280D02*
Y613248D01*
G01Y615807D02*
Y613839D01*
G01X72638Y828071D02*
G03I-3741J0D01*
G01X78740Y822146D02*
Y835099D01*
G01X78543Y827284D02*
Y828858D01*
G01X73189D02*
Y827284D01*
G01X71850Y828858D02*
Y829055D01*
G01Y827284D02*
Y827087D01*
G01Y828858D02*
Y827284D01*
G01X71653Y828858D02*
Y827284D01*
G01X70079D02*
Y828858D01*
G01X67716Y827284D02*
Y828858D01*
G01X66142Y827284D02*
Y828858D01*
G01X65945Y827284D02*
Y828858D01*
G01Y829055D02*
Y828858D01*
G01Y827284D02*
Y827087D01*
G01X64606Y827284D02*
Y828858D01*
G01X75895Y841971D02*
X75779Y842244D01*
G01X76013Y841709D02*
X75895Y841971D01*
G01X76132Y841457D02*
X76013Y841709D01*
G01X80281Y838066D02*
X80167Y838307D01*
G01X80399Y837803D02*
X80281Y838066D01*
G01X80520Y837520D02*
X80399Y837803D01*
G01X75779Y837518D02*
Y837520D01*
G01X75777Y837515D02*
X75779Y837518D01*
G01X75753Y837456D02*
X75777Y837515D01*
G01X80520Y842245D02*
Y842244D01*
G01X80522Y842249D02*
X80520Y842245D01*
G01X80546Y842308D02*
X80522Y842249D01*
G01X80286Y841709D02*
X80167Y841457D01*
G01X80404Y841971D02*
X80286Y841709D01*
G01X80520Y842244D02*
X80404Y841971D01*
G01X75899Y837802D02*
X75779Y837520D01*
G01X76017Y838065D02*
X75899Y837802D01*
G01X76132Y838307D02*
X76017Y838065D01*
G01X80167Y838307D02*
G03Y841457I-2017J1575D01*
G01X76132D02*
G03Y838307I2017J-1575D01*
G01X80520Y837520D02*
G03Y842244I-2371J2362D01*
G01X75779D02*
G03Y837520I2370J-2362D01*
G01X81653Y839882D02*
G03I-3504J0D01*
G01X75472Y843032D02*
G03Y836732I2677J-3150D01*
G01X80827D02*
G03Y843032I-2677J3150D01*
G01X79527Y853071D02*
X82677Y854252D01*
G01X79527Y853071D02*
X74803D01*
G01X70866Y852973D02*
X88110D01*
G01X70866Y851398D02*
X88110D01*
G01X74803Y851299D02*
X79527D01*
G01X69586Y848366D02*
X70866D01*
G01X90551D02*
X70866D01*
G01Y846595D02*
X90551D01*
G01X75472Y843032D02*
X80827D01*
G01X80520Y842244D02*
X75779D01*
G01X80167Y841457D02*
X76132D01*
G01X70079Y840492D02*
X90551D01*
G01X80167Y838307D02*
X76132D01*
G01X75779Y837520D02*
X80520D01*
G01X80827Y836732D02*
X75472D01*
G01X82677Y855118D02*
X79527Y856299D01*
G01X82677Y850118D02*
X79527Y851299D01*
G01X80584Y842402D02*
X80546Y842308D01*
G01X75714Y837362D02*
X75753Y837456D01*
G01X80668Y842610D02*
X80584Y842402D01*
G01X75631Y837154D02*
X75714Y837362D01*
G01X80701Y842696D02*
X80668Y842610D01*
G01X75597Y837068D02*
X75631Y837154D01*
G01X80736Y842788D02*
X80701Y842696D01*
G01X75562Y836976D02*
X75597Y837068D01*
G01X80772Y842884D02*
X80736Y842788D01*
G01X75527Y836880D02*
X75562Y836976D01*
G01X80827Y843032D02*
X80772Y842884D01*
G01X75472Y836732D02*
X75527Y836880D01*
G01X82008Y852973D02*
Y851398D01*
G01X80433Y852973D02*
Y851398D01*
G01X74803D02*
Y851299D01*
G01Y853071D02*
Y852973D01*
G01D02*
Y851398D01*
G01X80772Y836880D02*
X80827Y836732D01*
G01X75527Y842884D02*
X75472Y843032D01*
G01X80736Y836976D02*
X80772Y836880D01*
G01X75562Y842788D02*
X75527Y842884D01*
G01X80701Y837068D02*
X80736Y836976D01*
G01X75597Y842696D02*
X75562Y842788D01*
G01X80668Y837154D02*
X80701Y837068D01*
G01X75631Y842610D02*
X75597Y842696D01*
G01X80596Y837333D02*
X80668Y837154D01*
G01X75703Y842431D02*
X75631Y842610D01*
G01X80563Y837414D02*
X80596Y837333D01*
G01X75736Y842350D02*
X75703Y842431D01*
G01X80520Y837520D02*
X80563Y837414D01*
G01X75779Y842244D02*
X75736Y842350D01*
G01X70866Y846595D02*
Y866398D01*
G01X70079Y835099D02*
Y843445D01*
G01X69586Y848366D02*
Y981004D01*
G01X68208D02*
Y848366D01*
G01X66929D02*
Y981004D01*
G01X77559Y868071D02*
X82677Y869252D01*
G01X79527Y858071D02*
X82677Y859252D01*
G01X79527Y863071D02*
X82677Y864252D01*
G01X79527Y873071D02*
X82677Y874252D01*
G01X70866Y876398D02*
X88110D01*
G01X74803Y876299D02*
X79527D01*
G01Y873071D02*
X74803D01*
G01X70866Y872973D02*
X88110D01*
G01X70866Y871398D02*
X88110D01*
G01X74803Y871299D02*
X79527D01*
G01X70866Y871063D02*
X77756D01*
G01X70866Y869547D02*
X69685D01*
G01X77756Y868307D02*
X70866D01*
G01X77559Y868071D02*
X72834D01*
G01X69685Y867973D02*
X89567D01*
G01X69685Y866398D02*
X89567D01*
G01X72834Y866299D02*
X77559D01*
G01X69685Y864823D02*
X70866D01*
G01X79527Y863071D02*
X74803D01*
G01X70866Y862973D02*
X88110D01*
G01X70866Y861398D02*
X88110D01*
G01X74803Y861299D02*
X79527D01*
G01Y858071D02*
X74803D01*
G01X70866Y857973D02*
X88110D01*
G01X70866Y856398D02*
X88110D01*
G01X74803Y856299D02*
X79527D01*
G01X82677Y875118D02*
X79527Y876299D01*
G01X82677Y870118D02*
X79527Y871299D01*
G01X82677Y860118D02*
X79527Y861299D01*
G01X82677Y865118D02*
X77559Y866299D01*
G01X82008Y857973D02*
Y856398D01*
G01Y862973D02*
Y861398D01*
G01Y867973D02*
Y866398D01*
G01Y872973D02*
Y871398D01*
G01Y877973D02*
Y876398D01*
G01X80433Y857973D02*
Y856398D01*
G01Y862973D02*
Y861398D01*
G01Y867973D02*
Y866398D01*
G01Y872973D02*
Y871398D01*
G01Y877973D02*
Y876398D01*
G01X77756Y868307D02*
Y871063D01*
G01X74803Y856398D02*
Y856299D01*
G01Y857973D02*
Y856398D01*
G01Y858071D02*
Y857973D01*
G01Y861398D02*
Y861299D01*
G01Y863071D02*
Y862973D01*
G01D02*
Y861398D01*
G01Y871398D02*
Y871299D01*
G01Y873071D02*
Y872973D01*
G01Y876398D02*
Y876299D01*
G01Y872973D02*
Y871398D01*
G01Y877973D02*
Y876398D01*
G01X72834Y866398D02*
Y866299D01*
G01Y868071D02*
Y867973D01*
G01D02*
Y866398D01*
G01X70866D02*
Y867973D01*
G01D02*
Y906398D01*
G01X69685Y869547D02*
Y864823D01*
G01X79527Y878071D02*
X82677Y879252D01*
G01X79527Y883071D02*
X82677Y884252D01*
G01X79527Y888071D02*
X82677Y889252D01*
G01X79527Y893071D02*
X82677Y894252D01*
G01X79527Y898071D02*
X82677Y899252D01*
G01X79527Y898071D02*
X74803D01*
G01X70866Y897973D02*
X88110D01*
G01X70866Y896398D02*
X88110D01*
G01X74803Y896299D02*
X79527D01*
G01X70866Y896063D02*
X77756D01*
G01Y893307D02*
X70866D01*
G01X79527Y893071D02*
X74803D01*
G01X70866Y892973D02*
X88110D01*
G01X70866Y891398D02*
X88110D01*
G01X74803Y891299D02*
X79527D01*
G01Y888071D02*
X74803D01*
G01X70866Y887973D02*
X88110D01*
G01X70866Y886398D02*
X88110D01*
G01X74803Y886299D02*
X79527D01*
G01Y883071D02*
X74803D01*
G01X70866Y882973D02*
X88110D01*
G01X70866Y881398D02*
X88110D01*
G01X74803Y881299D02*
X79527D01*
G01Y878071D02*
X74803D01*
G01X70866Y877973D02*
X88110D01*
G01X82677Y895118D02*
X79527Y896299D01*
G01X82677Y890118D02*
X79527Y891299D01*
G01X82677Y885118D02*
X79527Y886299D01*
G01X82677Y880118D02*
X79527Y881299D01*
G01X82008Y882973D02*
Y881398D01*
G01Y887973D02*
Y886398D01*
G01Y892973D02*
Y891398D01*
G01Y897973D02*
Y896398D01*
G01X80433Y882973D02*
Y881398D01*
G01Y887973D02*
Y886398D01*
G01Y892973D02*
Y891398D01*
G01Y897973D02*
Y896398D01*
G01X77756Y893307D02*
Y896063D01*
G01X74803Y878071D02*
Y877973D01*
G01Y881398D02*
Y881299D01*
G01Y883071D02*
Y882973D01*
G01D02*
Y881398D01*
G01Y886398D02*
Y886299D01*
G01Y888071D02*
Y887973D01*
G01D02*
Y886398D01*
G01Y891398D02*
Y891299D01*
G01Y893071D02*
Y892973D01*
G01D02*
Y891398D01*
G01Y896398D02*
Y896299D01*
G01Y898071D02*
Y897973D01*
G01D02*
Y896398D01*
G01X77559Y908071D02*
X82677Y909252D01*
G01X77756Y918307D02*
X70866D01*
G01X79527Y918071D02*
X74803D01*
G01X70866Y917973D02*
X88110D01*
G01X70866Y916398D02*
X88110D01*
G01X74803Y916299D02*
X79527D01*
G01Y913071D02*
X74803D01*
G01X70866Y912973D02*
X88110D01*
G01X70866Y911398D02*
X88110D01*
G01X74803Y911299D02*
X79527D01*
G01X70866Y909547D02*
X69685D01*
G01X77559Y908071D02*
X72834D01*
G01X69685Y907973D02*
X89567D01*
G01X69685Y906398D02*
X89567D01*
G01X72834Y906299D02*
X77559D01*
G01X69685Y904823D02*
X70866D01*
G01X79527Y903071D02*
X74803D01*
G01X70866Y902973D02*
X88110D01*
G01X70866Y901398D02*
X88110D01*
G01X74803Y901299D02*
X79527D01*
G01Y903071D02*
X82677Y904252D01*
G01X79527Y913071D02*
X82677Y914252D01*
G01X79527Y918071D02*
X82677Y919252D01*
G01Y905118D02*
X77559Y906299D01*
G01X82677Y915118D02*
X79527Y916299D01*
G01X82677Y910118D02*
X79527Y911299D01*
G01X82677Y900118D02*
X79527Y901299D01*
G01X82008Y902973D02*
Y901398D01*
G01Y907973D02*
Y906398D01*
G01Y912973D02*
Y911398D01*
G01Y917973D02*
Y916398D01*
G01X80433Y902973D02*
Y901398D01*
G01Y907973D02*
Y906398D01*
G01Y912973D02*
Y911398D01*
G01Y917973D02*
Y916398D01*
G01X77756Y918307D02*
Y921063D01*
G01X74803Y901398D02*
Y901299D01*
G01Y903071D02*
Y902973D01*
G01D02*
Y901398D01*
G01Y911398D02*
Y911299D01*
G01Y913071D02*
Y912973D01*
G01D02*
Y911398D01*
G01Y916398D02*
Y916299D01*
G01Y918071D02*
Y917973D01*
G01D02*
Y916398D01*
G01X72834Y906398D02*
Y906299D01*
G01Y908071D02*
Y907973D01*
G01D02*
Y906398D01*
G01X70866D02*
Y907973D01*
G01D02*
Y924646D01*
G01X69685Y909547D02*
Y904823D01*
G01X68110Y940394D02*
X80118D01*
G01X73228Y940295D02*
X70866D01*
G01X73228Y938524D02*
X70866D01*
G01X68110Y938425D02*
X80118D01*
G01X68110Y937244D02*
X80118D01*
G01X73228Y937146D02*
X70866D01*
G01X73228Y935374D02*
X70866D01*
G01X68110Y935276D02*
X80118D01*
G01X68110Y934095D02*
X80118D01*
G01X73228Y933996D02*
X70866D01*
G01X73228Y932225D02*
X70866D01*
G01X68110Y932126D02*
X80118D01*
G01X68110Y930945D02*
X80118D01*
G01X73228Y930847D02*
X70866D01*
G01X73228Y925925D02*
X75590Y926614D01*
G01X73228Y929075D02*
X75590Y929764D01*
G01X73228Y932225D02*
X75590Y932914D01*
G01X73228Y929075D02*
X70866D01*
G01X68110Y928977D02*
X80118D01*
G01X68110Y927795D02*
X80118D01*
G01X73228Y927697D02*
X70866D01*
G01X73228Y925925D02*
X70866D01*
G01X68110Y925827D02*
X80118D01*
G01X68110Y924646D02*
X80118D01*
G01X73228Y924547D02*
X70866D01*
G01X75590Y923662D02*
X78937D01*
G01Y923071D02*
X74803D01*
G01X70866Y922973D02*
X89567D01*
G01X70866Y921398D02*
X89567D01*
G01X74803Y921299D02*
X79527D01*
G01X70866Y921063D02*
X77756D01*
G01X73228Y935374D02*
X75590Y936063D01*
G01X73228Y938524D02*
X75590Y939213D01*
G01Y939606D02*
X73228Y940295D01*
G01X75590Y936457D02*
X73228Y937146D01*
G01X75590Y933307D02*
X73228Y933996D01*
G01X75590Y930158D02*
X73228Y930847D01*
G01X75590Y927008D02*
X73228Y927697D01*
G01X75590Y923858D02*
X73228Y924547D01*
G01X82677Y920118D02*
X79527Y921299D01*
G01X82008Y922973D02*
Y921398D01*
G01X80433Y922973D02*
Y921398D01*
G01X80118Y925827D02*
Y924646D01*
G01Y932126D02*
Y930945D01*
G01Y928977D02*
Y927795D01*
G01Y935276D02*
Y934095D01*
G01Y941575D02*
Y940394D01*
G01Y938425D02*
Y937244D01*
G01X78937Y923662D02*
Y923071D01*
G01X75590Y927008D02*
Y926614D01*
G01Y923858D02*
Y923662D01*
G01Y930158D02*
Y929764D01*
G01Y936457D02*
Y936063D01*
G01Y933307D02*
Y932914D01*
G01Y939606D02*
Y939213D01*
G01X75512Y937244D02*
Y938425D01*
G01Y940394D02*
Y941575D01*
G01Y934095D02*
Y935276D01*
G01Y930945D02*
Y932126D01*
G01Y927795D02*
Y928977D01*
G01Y924646D02*
Y925827D01*
G01X75118D02*
Y924646D01*
G01Y932126D02*
Y930945D01*
G01Y928977D02*
Y927795D01*
G01Y935276D02*
Y934095D01*
G01Y941575D02*
Y940394D01*
G01Y938425D02*
Y937244D01*
G01X74803Y921398D02*
Y921299D01*
G01Y923071D02*
Y922973D01*
G01D02*
Y921398D01*
G01X74330Y925827D02*
Y924646D01*
G01Y928977D02*
Y927795D01*
G01Y932126D02*
Y930945D01*
G01Y935276D02*
Y934095D01*
G01Y938425D02*
Y937244D01*
G01Y941575D02*
Y940394D01*
G01X72756Y925827D02*
Y924646D01*
G01Y932126D02*
Y930945D01*
G01Y928977D02*
Y927795D01*
G01Y935276D02*
Y934095D01*
G01Y938425D02*
Y937244D01*
G01Y941575D02*
Y940394D01*
G01X70866Y938425D02*
Y940394D01*
G01D02*
Y941575D01*
G01Y937244D02*
Y938425D01*
G01Y935276D02*
Y937244D01*
G01Y932126D02*
Y934095D01*
G01D02*
Y935276D01*
G01Y928977D02*
Y930945D01*
G01D02*
Y932126D01*
G01Y927795D02*
Y928977D01*
G01Y925827D02*
Y927795D01*
G01Y924646D02*
Y925827D01*
G01X68110Y946890D02*
Y922480D01*
G01X78305Y945302D02*
X78439Y945335D01*
G01X70866Y961398D02*
X88110D01*
G01X74803Y961299D02*
X79527D01*
G01Y958071D02*
X74803D01*
G01X70866Y957973D02*
X88110D01*
G01X70866Y956398D02*
X88110D01*
G01X74803Y956299D02*
X79527D01*
G01X70866Y956063D02*
X77756D01*
G01Y953307D02*
X70866D01*
G01X79527Y953071D02*
X74803D01*
G01X70866Y952973D02*
X88110D01*
G01X70866Y951398D02*
X88110D01*
G01X74803Y951299D02*
X79527D01*
G01Y948071D02*
X74803D01*
G01X70866Y947973D02*
X88110D01*
G01X70866Y946398D02*
X88110D01*
G01X74803Y946299D02*
X78937D01*
G01Y945709D02*
X75590D01*
G01X78439Y945335D02*
X78573D01*
G01X78540Y945138D02*
X78473D01*
G01X73228Y944823D02*
X70866D01*
G01X68110Y944725D02*
X80118D01*
G01X79143Y944416D02*
X79243D01*
G01X79277Y944219D02*
X79109D01*
G01X79143Y943957D02*
X79243D01*
G01X78473Y943924D02*
X78573D01*
G01X79143Y943793D02*
X79243D01*
G01X78473Y943760D02*
X78540D01*
G01X68110Y943543D02*
X80118D01*
G01X73228Y943445D02*
X70866D01*
G01X78540Y942973D02*
X78473D01*
G01X79243Y942940D02*
X79143D01*
G01X78573Y942808D02*
X78473D01*
G01X79243Y942776D02*
X79143D01*
G01X73228Y941673D02*
X70866D01*
G01X68110Y941575D02*
X80118D01*
G01X73228Y941673D02*
X75590Y942362D01*
G01X73228Y944823D02*
X75590Y945512D01*
G01X78473Y945138D02*
X78372Y945105D01*
G01X79527Y948071D02*
X82677Y949252D01*
G01X79527Y953071D02*
X82677Y954252D01*
G01X79527Y958071D02*
X82677Y959252D01*
G01X79411Y942841D02*
X79243Y942776D01*
G01X78975Y943891D02*
X79143Y943957D01*
G01X78305Y943858D02*
X78473Y943924D01*
G01X79243Y943957D02*
X79411Y943891D01*
G01X79143Y942776D02*
X78975Y942841D01*
G01X78473Y942808D02*
X78305Y942874D01*
G01X82677Y960118D02*
X79527Y961299D01*
G01X82677Y955118D02*
X79527Y956299D01*
G01X82677Y950118D02*
X79527Y951299D01*
G01X79310Y945203D02*
X79210Y945236D01*
G01X78640Y945105D02*
X78540Y945138D01*
G01X78439Y944317D02*
X78339Y944351D01*
G01X75590Y942756D02*
X73228Y943445D01*
G01X79210Y945433D02*
X79344Y945400D01*
G01X78573Y945335D02*
X78707Y945302D01*
G01Y942874D02*
X78573Y942808D01*
G01X79411Y944285D02*
X79277Y944219D01*
G01X78640Y943038D02*
X78540Y942973D01*
G01X78372Y943694D02*
X78473Y943760D01*
G01X79243Y944416D02*
X79344Y944482D01*
G01X79377Y943038D02*
X79243Y942940D01*
G01X79042Y944482D02*
X79143Y944416D01*
G01X78540Y943760D02*
X78640Y943694D01*
G01X78473Y942973D02*
X78372Y943038D01*
G01X79344Y945400D02*
X79512Y945302D01*
G01X79109Y944219D02*
X78975Y944285D01*
G01X78372Y944547D02*
X78439Y944514D01*
G01X78573Y943924D02*
X78707Y943858D01*
G01X79009Y943694D02*
X79143Y943793D01*
G01X79512Y942940D02*
X79411Y942841D01*
G01X78808Y942973D02*
X78707Y942874D01*
G01X79545Y944416D02*
X79411Y944285D01*
G01X78205Y943760D02*
X78305Y943858D01*
G01X78171Y945171D02*
X78305Y945302D01*
G01X79411Y945105D02*
X79310Y945203D01*
G01X78707Y945302D02*
X78842Y945171D01*
G01X79411Y943891D02*
X79512Y943793D01*
G01X78975Y944285D02*
X78842Y944416D01*
G01X78305Y944613D02*
X78372Y944547D01*
G01X78707Y943858D02*
X78808Y943760D01*
G01X78305Y942874D02*
X78205Y942973D01*
G01X79243Y943793D02*
X79377Y943694D01*
G01X78339Y944351D02*
X78205Y944449D01*
G01X79143Y942940D02*
X79009Y943038D01*
G01X78741Y943169D02*
X78640Y943038D01*
G01X78875Y943760D02*
X78975Y943891D01*
G01X78272Y943563D02*
X78372Y943694D01*
G01X79344Y944482D02*
X79411Y944580D01*
G01X78372Y945105D02*
X78305Y945006D01*
G01X79612Y943104D02*
X79512Y942940D01*
G01X78104Y943596D02*
X78205Y943760D01*
G01X79444Y943169D02*
X79377Y943038D01*
G01X78842D02*
X78808Y942973D01*
G01X79612Y944547D02*
X79545Y944416D01*
G01X78942Y943563D02*
X79009Y943694D01*
G01X78842D02*
X78875Y943760D01*
G01X78104Y945040D02*
X78171Y945171D01*
G01X79612Y945138D02*
X79645Y944974D01*
G01X79629Y943543D02*
X79645Y943465D01*
G01X79612Y943628D02*
X79629Y943543D01*
G01X78774Y944547D02*
X78741Y944711D01*
G01X78075Y944725D02*
X78071Y944744D01*
G01X78104Y944580D02*
X78075Y944725D01*
G01X78104Y943136D02*
X78071Y943301D01*
G01X79444Y944974D02*
X79411Y945105D01*
G01X79449Y943543D02*
X79478Y943432D01*
G01X79444Y943563D02*
X79449Y943543D01*
G01X78908Y945040D02*
X78942Y944908D01*
G01Y944711D02*
X78975Y944580D01*
G01X78942Y943169D02*
X78908Y943301D01*
G01X78746Y943543D02*
X78774Y943432D01*
G01X78741Y943563D02*
X78746Y943543D01*
G01X78272Y943169D02*
X78238Y943301D01*
G01X78741Y944908D02*
X78707Y945006D01*
G01X78272Y944711D02*
X78305Y944613D01*
G01X78842Y945171D02*
X78908Y945040D01*
G01X79377Y943694D02*
X79444Y943563D01*
G01X78842Y944416D02*
X78774Y944547D01*
G01X78808Y943760D02*
X78842Y943694D01*
G01X79009Y943038D02*
X78942Y943169D01*
G01X78875Y942973D02*
X78842Y943038D01*
G01X79512Y945302D02*
X79612Y945138D01*
G01X79512Y943793D02*
X79612Y943628D01*
G01X78205Y942973D02*
X78104Y943136D01*
G01X78707Y945006D02*
X78640Y945105D01*
G01X78975Y944580D02*
X79042Y944482D01*
G01X78205Y944449D02*
X78104Y944580D01*
G01X78640Y943694D02*
X78741Y943563D01*
G01X78975Y942841D02*
X78875Y942973D01*
G01X78372Y943038D02*
X78272Y943169D01*
G01X78305Y945006D02*
X78272Y944908D01*
G01X79478Y943301D02*
X79444Y943169D01*
G01X79411Y944580D02*
X79444Y944711D01*
G01X78908Y943432D02*
X78937Y943543D01*
G01D02*
X78942Y943563D01*
G01X78774Y943301D02*
X78741Y943169D01*
G01X78238Y943432D02*
X78267Y943543D01*
G01D02*
X78272Y943563D01*
G01X78071Y944908D02*
X78104Y945040D01*
G01X79645Y943268D02*
X79612Y943104D01*
G01X79645Y944711D02*
X79612Y944547D01*
G01X78071Y943432D02*
X78093Y943543D01*
G01D02*
X78104Y943596D01*
G01X82008Y947973D02*
Y946398D01*
G01Y952973D02*
Y951398D01*
G01Y957973D02*
Y956398D01*
G01Y962973D02*
Y961398D01*
G01X80433Y947973D02*
Y946398D01*
G01Y952973D02*
Y951398D01*
G01Y957973D02*
Y956398D01*
G01Y962973D02*
Y961398D01*
G01X80118Y944725D02*
Y943543D01*
G01X79645Y943465D02*
Y943268D01*
G01Y944974D02*
Y944725D01*
G01D02*
Y944711D01*
G01X79478Y943432D02*
Y943301D01*
G01X79444Y944725D02*
Y944974D01*
G01Y944711D02*
Y944725D01*
G01X79210Y945236D02*
Y945433D01*
G01X78942Y944908D02*
Y944725D01*
G01D02*
Y944711D01*
G01X78937Y946299D02*
Y945709D01*
G01X78908Y943301D02*
Y943432D01*
G01X78774D02*
Y943301D01*
G01X78741Y944725D02*
Y944908D01*
G01Y944711D02*
Y944725D01*
G01X78439Y944514D02*
Y944317D01*
G01X78272Y944908D02*
Y944725D01*
G01D02*
Y944711D01*
G01X78238Y943301D02*
Y943432D01*
G01X78071Y943301D02*
Y943432D01*
G01Y944744D02*
Y944908D01*
G01X77756Y953307D02*
Y956063D01*
G01X75590Y945709D02*
Y945512D01*
G01Y942756D02*
Y942362D01*
G01X75512Y943543D02*
Y944725D01*
G01X75118D02*
Y943543D01*
G01X74803Y946398D02*
Y946299D01*
G01Y948071D02*
Y947973D01*
G01Y951398D02*
Y951299D01*
G01Y947973D02*
Y946398D01*
G01Y953071D02*
Y952973D01*
G01D02*
Y951398D01*
G01Y956398D02*
Y956299D01*
G01Y958071D02*
Y957973D01*
G01D02*
Y956398D01*
G01Y961398D02*
Y961299D01*
G01Y962973D02*
Y961398D01*
G01X74330Y944725D02*
Y943543D01*
G01X72756Y944725D02*
Y943543D01*
G01X70866Y944725D02*
Y982776D01*
G01Y941575D02*
Y943543D01*
G01D02*
Y944725D01*
G01Y981004D02*
X90551D01*
G01X69586D02*
X70866D01*
G01X79527Y978071D02*
X74803D01*
G01X70866Y977973D02*
X88110D01*
G01X70866Y976398D02*
X88110D01*
G01X74803Y976299D02*
X79527D01*
G01Y973071D02*
X74803D01*
G01X70866Y972973D02*
X88110D01*
G01X70866Y971398D02*
X88110D01*
G01X74803Y971299D02*
X79527D01*
G01Y968071D02*
X74803D01*
G01X70866Y967973D02*
X88110D01*
G01X70866Y966398D02*
X88110D01*
G01X74803Y966299D02*
X79527D01*
G01Y963071D02*
X74803D01*
G01X70866Y962973D02*
X88110D01*
G01X79527Y963071D02*
X82677Y964252D01*
G01X79527Y968071D02*
X82677Y969252D01*
G01X79527Y973071D02*
X82677Y974252D01*
G01X79527Y978071D02*
X82677Y979252D01*
G01Y975118D02*
X79527Y976299D01*
G01X82677Y970118D02*
X79527Y971299D01*
G01X82677Y965118D02*
X79527Y966299D01*
G01X82008Y967973D02*
Y966398D01*
G01Y972973D02*
Y971398D01*
G01Y977973D02*
Y976398D01*
G01X80433Y967973D02*
Y966398D01*
G01Y972973D02*
Y971398D01*
G01Y977973D02*
Y976398D01*
G01X74803Y963071D02*
Y962973D01*
G01Y966398D02*
Y966299D01*
G01Y968071D02*
Y967973D01*
G01D02*
Y966398D01*
G01Y971398D02*
Y971299D01*
G01Y973071D02*
Y972973D01*
G01D02*
Y971398D01*
G01Y976398D02*
Y976299D01*
G01Y978071D02*
Y977973D01*
G01D02*
Y976398D01*
G01X72638Y1001299D02*
G03I-3741J0D01*
G01X80708Y989488D02*
G03I-2559J0D01*
G01X81496D02*
G03I-3347J0D01*
G01X81653D02*
G03I-3504J0D01*
G01X78075Y993621D02*
G03X78149Y985354I73J-4133D01*
G01X78224Y985355D02*
G03X78149Y993622I-75J4133D01*
G01X90551Y988878D02*
X70079D01*
G01X90551Y982776D02*
X70866D01*
G01X78075Y993622D02*
X78149D01*
G01X78224Y985355D02*
X78149Y985354D01*
G01X78740Y994272D02*
Y1007225D01*
G01X78543Y1000512D02*
Y1002087D01*
G01X73189D02*
Y1000512D01*
G01X71850Y1002087D02*
Y1002284D01*
G01Y1000512D02*
Y1000315D01*
G01Y1002087D02*
Y1000512D01*
G01X71653Y1002087D02*
Y1000512D01*
G01X70079D02*
Y1002087D01*
G01Y994272D02*
Y985925D01*
G01X67716Y1000512D02*
Y1002087D01*
G01X66142Y1000512D02*
Y1002087D01*
G01X65945Y1000512D02*
Y1002087D01*
G01Y1000512D02*
Y1000315D01*
G01Y1002284D02*
Y1002087D01*
G01X64606Y1000512D02*
Y1002087D01*
G01X72047Y1018268D02*
G03Y1017087I0J-591D01*
G01X65748D02*
G03Y1018268I0J590D01*
G01Y1019843D02*
G03Y1021024I0J590D01*
G01X72047D02*
G03Y1019843I0J-591D01*
G01X65748Y1021614D02*
X72047D01*
G01Y1021319D02*
X73622D01*
G01X70472D02*
X72047D01*
G01X65748D02*
X64173D01*
G01X67323D02*
X65748D01*
G01X64173Y1019351D02*
X65748D01*
G01D02*
X67323D01*
G01X73622D02*
X72047D01*
G01D02*
X70472D01*
G01X64173Y1018760D02*
X65748D01*
G01D02*
X67323D01*
G01X73622D02*
X72047D01*
G01D02*
X70472D01*
G01X65759Y1018016D02*
X65852D01*
G01Y1017268D02*
X65759D01*
G01X72047Y1016791D02*
X73622D01*
G01X70472D02*
X72047D01*
G01X65748D02*
X64173D01*
G01X67323D02*
X65748D01*
G01Y1016496D02*
X72047D01*
G01X65759Y1017888D02*
X65665Y1017777D01*
G01Y1017904D02*
X65759Y1018016D01*
G01X73622Y1016791D02*
Y1018760D01*
G01Y1021319D02*
Y1019351D01*
G01X72047Y1018268D02*
Y1019843D01*
G01Y1021024D02*
Y1021614D01*
G01Y1016496D02*
Y1017087D01*
G01X71063Y1016496D02*
Y1021614D01*
G01X70866D02*
Y1016496D01*
G01X70472Y1019351D02*
Y1021319D01*
G01Y1018760D02*
Y1016791D01*
G01X67323Y1019351D02*
Y1021319D01*
G01Y1018760D02*
Y1016791D01*
G01X66929Y1021614D02*
Y1016496D01*
G01X66732D02*
Y1021614D01*
G01X65852Y1018016D02*
Y1017268D01*
G01X65759D02*
Y1017888D01*
G01X65748Y1017087D02*
Y1016496D01*
G01Y1019843D02*
Y1018268D01*
G01Y1021614D02*
Y1021024D01*
G01X65665Y1017777D02*
Y1017904D01*
G01X64173Y1016791D02*
Y1018760D01*
G01Y1021319D02*
Y1019351D01*
G01X72638Y1233583D02*
G03I-3741J0D01*
G01X78740Y1227658D02*
Y1240610D01*
G01X78543Y1232795D02*
Y1234370D01*
G01X73189D02*
Y1232795D01*
G01X71850Y1234370D02*
Y1234567D01*
G01Y1232795D02*
Y1232599D01*
G01Y1234370D02*
Y1232795D01*
G01X71653Y1234370D02*
Y1232795D01*
G01X70079D02*
Y1234370D01*
G01X67716Y1232795D02*
Y1234370D01*
G01X66142Y1232795D02*
Y1234370D01*
G01X65945Y1232795D02*
Y1234370D01*
G01Y1234567D02*
Y1234370D01*
G01Y1232795D02*
Y1232599D01*
G01X64606Y1232795D02*
Y1234370D01*
G01X75779Y1243030D02*
Y1243032D01*
G01X75766Y1242999D02*
X75779Y1243030D01*
G01X80520Y1247757D02*
Y1247756D01*
G01X80533Y1247788D02*
X80520Y1247757D01*
G01X80286Y1247221D02*
X80167Y1246969D01*
G01X80404Y1247483D02*
X80286Y1247221D01*
G01X80520Y1247756D02*
X80404Y1247483D01*
G01X75899Y1243314D02*
X75779Y1243032D01*
G01X76017Y1243577D02*
X75899Y1243314D01*
G01X76132Y1243819D02*
X76017Y1243577D01*
G01X80281D02*
X80167Y1243819D01*
G01X80399Y1243315D02*
X80281Y1243577D01*
G01X80520Y1243032D02*
X80399Y1243315D01*
G01X75895Y1247483D02*
X75779Y1247756D01*
G01X76013Y1247221D02*
X75895Y1247483D01*
G01X76132Y1246969D02*
X76013Y1247221D01*
G01X80167Y1243819D02*
G03Y1246969I-2017J1575D01*
G01X76132D02*
G03Y1243819I2017J-1575D01*
G01X80520Y1243032D02*
G03Y1247756I-2371J2362D01*
G01X75779D02*
G03Y1243032I2370J-2362D01*
G01X81653Y1245394D02*
G03I-3504J0D01*
G01X75472Y1248543D02*
G03Y1242244I2677J-3150D01*
G01X80827D02*
G03Y1248543I-2678J3149D01*
G01X70866Y1256910D02*
X88110D01*
G01X74803Y1256811D02*
X79527D01*
G01X69586Y1253878D02*
X70866D01*
G01X90551D02*
X70866D01*
G01Y1252106D02*
X90551D01*
G01X75472Y1248543D02*
X80827D01*
G01X80520Y1247756D02*
X75779D01*
G01X80167Y1246969D02*
X76132D01*
G01X70079Y1246004D02*
X90551D01*
G01X80167Y1243819D02*
X76132D01*
G01X75779Y1243032D02*
X80520D01*
G01X80827Y1242244D02*
X75472D01*
G01X82677Y1255630D02*
X79527Y1256811D01*
G01X80772Y1242392D02*
X80827Y1242244D01*
G01X75527Y1248395D02*
X75472Y1248543D01*
G01X80736Y1242488D02*
X80772Y1242392D01*
G01X75562Y1248299D02*
X75527Y1248395D01*
G01X80701Y1242580D02*
X80736Y1242488D01*
G01X75597Y1248208D02*
X75562Y1248299D01*
G01X80668Y1242666D02*
X80701Y1242580D01*
G01X75631Y1248122D02*
X75597Y1248208D01*
G01X80596Y1242845D02*
X80668Y1242666D01*
G01X75703Y1247943D02*
X75631Y1248122D01*
G01X80563Y1242926D02*
X80596Y1242845D01*
G01X75736Y1247862D02*
X75703Y1247943D01*
G01X80520Y1243032D02*
X80563Y1242926D01*
G01X75779Y1247756D02*
X75736Y1247862D01*
G01X82008Y1258484D02*
Y1256910D01*
G01X80433Y1258484D02*
Y1256910D01*
G01X74803D02*
Y1256811D01*
G01Y1258484D02*
Y1256910D01*
G01X80573Y1247886D02*
X80533Y1247788D01*
G01X75725Y1242901D02*
X75766Y1242999D01*
G01X80609Y1247975D02*
X80573Y1247886D01*
G01X75690Y1242813D02*
X75725Y1242901D01*
G01X80668Y1248122D02*
X80609Y1247975D01*
G01X75631Y1242666D02*
X75690Y1242813D01*
G01X80701Y1248208D02*
X80668Y1248122D01*
G01X75597Y1242580D02*
X75631Y1242666D01*
G01X80736Y1248299D02*
X80701Y1248208D01*
G01X75562Y1242488D02*
X75597Y1242580D01*
G01X80772Y1248395D02*
X80736Y1248299D01*
G01X75527Y1242392D02*
X75562Y1242488D01*
G01X80827Y1248543D02*
X80772Y1248395D01*
G01X75472Y1242244D02*
X75527Y1242392D01*
G01X70866Y1252106D02*
Y1271910D01*
G01X70079Y1240610D02*
Y1248957D01*
G01X69586Y1253878D02*
Y1386516D01*
G01X68208D02*
Y1253878D01*
G01X66929D02*
Y1386516D01*
G01X77559Y1273583D02*
X82677Y1274764D01*
G01X79527Y1278583D02*
X74803D01*
G01X70866Y1278484D02*
X88110D01*
G01X70866Y1276910D02*
X88110D01*
G01X74803Y1276811D02*
X79527D01*
G01X70866Y1276575D02*
X77756D01*
G01X70866Y1275059D02*
X69685D01*
G01X77756Y1273819D02*
X70866D01*
G01X77559Y1273583D02*
X72834D01*
G01X69685Y1273484D02*
X89567D01*
G01X69685Y1271910D02*
X89567D01*
G01X72834Y1271811D02*
X77559D01*
G01X69685Y1270335D02*
X70866D01*
G01X79527Y1268583D02*
X74803D01*
G01X70866Y1268484D02*
X88110D01*
G01X70866Y1266910D02*
X88110D01*
G01X74803Y1266811D02*
X79527D01*
G01Y1263583D02*
X74803D01*
G01X70866Y1263484D02*
X88110D01*
G01X70866Y1261910D02*
X88110D01*
G01X74803Y1261811D02*
X79527D01*
G01Y1258583D02*
X74803D01*
G01X70866Y1258484D02*
X88110D01*
G01X82677Y1270630D02*
X77559Y1271811D01*
G01X82677Y1275630D02*
X79527Y1276811D01*
G01X82677Y1265630D02*
X79527Y1266811D01*
G01X82677Y1260630D02*
X79527Y1261811D01*
G01Y1258583D02*
X82677Y1259764D01*
G01X79527Y1263583D02*
X82677Y1264764D01*
G01X79527Y1268583D02*
X82677Y1269764D01*
G01X79527Y1278583D02*
X82677Y1279764D01*
G01X82008Y1263484D02*
Y1261910D01*
G01Y1268484D02*
Y1266910D01*
G01Y1273484D02*
Y1271910D01*
G01Y1278484D02*
Y1276910D01*
G01X80433Y1263484D02*
Y1261910D01*
G01Y1268484D02*
Y1266910D01*
G01Y1273484D02*
Y1271910D01*
G01Y1278484D02*
Y1276910D01*
G01X77756Y1273819D02*
Y1276575D01*
G01X74803Y1258583D02*
Y1258484D01*
G01Y1261910D02*
Y1261811D01*
G01Y1263583D02*
Y1263484D01*
G01D02*
Y1261910D01*
G01Y1266910D02*
Y1266811D01*
G01Y1268583D02*
Y1268484D01*
G01D02*
Y1266910D01*
G01Y1276910D02*
Y1276811D01*
G01Y1278583D02*
Y1278484D01*
G01D02*
Y1276910D01*
G01X72834Y1271910D02*
Y1271811D01*
G01Y1273583D02*
Y1273484D01*
G01D02*
Y1271910D01*
G01X70866D02*
Y1273484D01*
G01D02*
Y1311910D01*
G01X69685Y1275059D02*
Y1270335D01*
G01X77756Y1298819D02*
X70866D01*
G01X79527Y1298583D02*
X74803D01*
G01X70866Y1298484D02*
X88110D01*
G01X70866Y1296910D02*
X88110D01*
G01X74803Y1296811D02*
X79527D01*
G01Y1293583D02*
X74803D01*
G01X70866Y1293484D02*
X88110D01*
G01X70866Y1291910D02*
X88110D01*
G01X74803Y1291811D02*
X79527D01*
G01Y1288583D02*
X74803D01*
G01X70866Y1288484D02*
X88110D01*
G01X70866Y1286910D02*
X88110D01*
G01X74803Y1286811D02*
X79527D01*
G01Y1283583D02*
X74803D01*
G01X70866Y1283484D02*
X88110D01*
G01X70866Y1281910D02*
X88110D01*
G01X74803Y1281811D02*
X79527D01*
G01X82677Y1295630D02*
X79527Y1296811D01*
G01X82677Y1290630D02*
X79527Y1291811D01*
G01X82677Y1285630D02*
X79527Y1286811D01*
G01X82677Y1280630D02*
X79527Y1281811D01*
G01Y1283583D02*
X82677Y1284764D01*
G01X79527Y1288583D02*
X82677Y1289764D01*
G01X79527Y1293583D02*
X82677Y1294764D01*
G01X79527Y1298583D02*
X82677Y1299764D01*
G01X82008Y1283484D02*
Y1281910D01*
G01Y1288484D02*
Y1286910D01*
G01Y1293484D02*
Y1291910D01*
G01Y1298484D02*
Y1296910D01*
G01X80433Y1283484D02*
Y1281910D01*
G01Y1288484D02*
Y1286910D01*
G01Y1293484D02*
Y1291910D01*
G01Y1298484D02*
Y1296910D01*
G01X77756Y1298819D02*
Y1301575D01*
G01X74803Y1281910D02*
Y1281811D01*
G01Y1283583D02*
Y1283484D01*
G01D02*
Y1281910D01*
G01Y1286910D02*
Y1286811D01*
G01Y1288583D02*
Y1288484D01*
G01D02*
Y1286910D01*
G01Y1291910D02*
Y1291811D01*
G01Y1293583D02*
Y1293484D01*
G01Y1296910D02*
Y1296811D01*
G01Y1293484D02*
Y1291910D01*
G01Y1298583D02*
Y1298484D01*
G01D02*
Y1296910D01*
G01X77559Y1313583D02*
X82677Y1314764D01*
G01X79527Y1318583D02*
X74803D01*
G01X70866Y1318484D02*
X88110D01*
G01X70866Y1316910D02*
X88110D01*
G01X74803Y1316811D02*
X79527D01*
G01X70866Y1315059D02*
X69685D01*
G01X77559Y1313583D02*
X72834D01*
G01X69685Y1313484D02*
X89567D01*
G01X69685Y1311910D02*
X89567D01*
G01X72834Y1311811D02*
X77559D01*
G01X69685Y1310335D02*
X70866D01*
G01X79527Y1308583D02*
X74803D01*
G01X70866Y1308484D02*
X88110D01*
G01X70866Y1306910D02*
X88110D01*
G01X74803Y1306811D02*
X79527D01*
G01Y1303583D02*
X74803D01*
G01X70866Y1303484D02*
X88110D01*
G01X70866Y1301910D02*
X88110D01*
G01X74803Y1301811D02*
X79527D01*
G01X70866Y1301575D02*
X77756D01*
G01X82677Y1310630D02*
X77559Y1311811D01*
G01X82677Y1320630D02*
X79527Y1321811D01*
G01X82677Y1315630D02*
X79527Y1316811D01*
G01X82677Y1305630D02*
X79527Y1306811D01*
G01X82677Y1300630D02*
X79527Y1301811D01*
G01Y1303583D02*
X82677Y1304764D01*
G01X82008Y1303484D02*
Y1301910D01*
G01Y1308484D02*
Y1306910D01*
G01Y1313484D02*
Y1311910D01*
G01Y1318484D02*
Y1316910D01*
G01X80433Y1303484D02*
Y1301910D01*
G01Y1308484D02*
Y1306910D01*
G01Y1313484D02*
Y1311910D01*
G01Y1318484D02*
Y1316910D01*
G01X74803Y1301910D02*
Y1301811D01*
G01Y1303583D02*
Y1303484D01*
G01Y1306910D02*
Y1306811D01*
G01Y1303484D02*
Y1301910D01*
G01Y1308583D02*
Y1308484D01*
G01D02*
Y1306910D01*
G01Y1316910D02*
Y1316811D01*
G01Y1318583D02*
Y1318484D01*
G01D02*
Y1316910D01*
G01X79527Y1308583D02*
X82677Y1309764D01*
G01X79527Y1318583D02*
X82677Y1319764D01*
G01X72834Y1311910D02*
Y1311811D01*
G01Y1313583D02*
Y1313484D01*
G01D02*
Y1311910D01*
G01X70866D02*
Y1313484D01*
G01D02*
Y1330158D01*
G01X69685Y1315059D02*
Y1310335D01*
G01X73228Y1340886D02*
X70866D01*
G01X68110Y1340788D02*
X80118D01*
G01X68110Y1339606D02*
X80118D01*
G01X73228Y1339508D02*
X70866D01*
G01X73228Y1337736D02*
X70866D01*
G01X68110Y1337638D02*
X80118D01*
G01X68110Y1336457D02*
X80118D01*
G01X73228Y1336358D02*
X70866D01*
G01X73228Y1334587D02*
X70866D01*
G01X68110Y1334488D02*
X80118D01*
G01X68110Y1333307D02*
X80118D01*
G01X73228Y1333209D02*
X70866D01*
G01X73228Y1331437D02*
X70866D01*
G01X68110Y1331339D02*
X80118D01*
G01X68110Y1330158D02*
X80118D01*
G01X73228Y1330059D02*
X70866D01*
G01X75590Y1329173D02*
X78937D01*
G01Y1328583D02*
X74803D01*
G01X70866Y1328484D02*
X89567D01*
G01X70866Y1326910D02*
X89567D01*
G01X74803Y1326811D02*
X79527D01*
G01X70866Y1326575D02*
X77756D01*
G01Y1323819D02*
X70866D01*
G01X79527Y1323583D02*
X74803D01*
G01X70866Y1323484D02*
X88110D01*
G01X70866Y1321910D02*
X88110D01*
G01X74803Y1321811D02*
X79527D01*
G01X75590Y1341969D02*
X73228Y1342658D01*
G01X75590Y1338819D02*
X73228Y1339508D01*
G01X75590Y1335669D02*
X73228Y1336358D01*
G01X75590Y1332520D02*
X73228Y1333209D01*
G01X75590Y1329370D02*
X73228Y1330059D01*
G01X82677Y1325630D02*
X79527Y1326811D01*
G01X82008Y1323484D02*
Y1321910D01*
G01Y1328484D02*
Y1326910D01*
G01X80433Y1323484D02*
Y1321910D01*
G01Y1328484D02*
Y1326910D01*
G01X80118Y1334488D02*
Y1333307D01*
G01Y1331339D02*
Y1330158D01*
G01Y1337638D02*
Y1336457D01*
G01Y1340788D02*
Y1339606D01*
G01X78937Y1329173D02*
Y1328583D01*
G01X77756Y1323819D02*
Y1326575D01*
G01X75590Y1329370D02*
Y1329173D01*
G01Y1332520D02*
Y1332126D01*
G01Y1338819D02*
Y1338425D01*
G01Y1335669D02*
Y1335276D01*
G01Y1341969D02*
Y1341575D01*
G01X75512Y1339606D02*
Y1340788D01*
G01Y1336457D02*
Y1337638D01*
G01Y1330158D02*
Y1331339D01*
G01Y1333307D02*
Y1334488D01*
G01X75118D02*
Y1333307D01*
G01Y1331339D02*
Y1330158D01*
G01Y1337638D02*
Y1336457D01*
G01Y1340788D02*
Y1339606D01*
G01X74803Y1321910D02*
Y1321811D01*
G01Y1323583D02*
Y1323484D01*
G01D02*
Y1321910D01*
G01Y1326910D02*
Y1326811D01*
G01Y1328583D02*
Y1328484D01*
G01D02*
Y1326910D01*
G01X74330Y1331339D02*
Y1330158D01*
G01Y1334488D02*
Y1333307D01*
G01Y1337638D02*
Y1336457D01*
G01Y1340788D02*
Y1339606D01*
G01X73228Y1331437D02*
X75590Y1332126D01*
G01X73228Y1334587D02*
X75590Y1335276D01*
G01X73228Y1337736D02*
X75590Y1338425D01*
G01X73228Y1340886D02*
X75590Y1341575D01*
G01X79527Y1323583D02*
X82677Y1324764D01*
G01X72756Y1331339D02*
Y1330158D01*
G01Y1334488D02*
Y1333307D01*
G01Y1337638D02*
Y1336457D01*
G01Y1340788D02*
Y1339606D01*
G01X70866Y1340788D02*
Y1342756D01*
G01Y1339606D02*
Y1340788D01*
G01Y1337638D02*
Y1339606D01*
G01Y1334488D02*
Y1336457D01*
G01D02*
Y1337638D01*
G01Y1331339D02*
Y1333307D01*
G01D02*
Y1334488D01*
G01Y1330158D02*
Y1331339D01*
G01X68110Y1352402D02*
Y1327992D01*
G01X78305Y1350814D02*
X78439Y1350847D01*
G01X70866Y1361910D02*
X88110D01*
G01X74803Y1361811D02*
X79527D01*
G01X70866Y1361575D02*
X77756D01*
G01Y1358819D02*
X70866D01*
G01X79527Y1358583D02*
X74803D01*
G01X70866Y1358484D02*
X88110D01*
G01X70866Y1356910D02*
X88110D01*
G01X74803Y1356811D02*
X79527D01*
G01Y1353583D02*
X74803D01*
G01X70866Y1353484D02*
X88110D01*
G01X70866Y1351910D02*
X88110D01*
G01X74803Y1351811D02*
X78937D01*
G01Y1351221D02*
X75590D01*
G01X78439Y1350847D02*
X78573D01*
G01X78540Y1350650D02*
X78473D01*
G01X73228Y1350335D02*
X70866D01*
G01X68110Y1350236D02*
X80118D01*
G01X79143Y1349928D02*
X79243D01*
G01X79277Y1349731D02*
X79109D01*
G01X79143Y1349469D02*
X79243D01*
G01X78473Y1349436D02*
X78573D01*
G01X79143Y1349304D02*
X79243D01*
G01X78473Y1349272D02*
X78540D01*
G01X68110Y1349055D02*
X80118D01*
G01X73228Y1348957D02*
X70866D01*
G01X78540Y1348484D02*
X78473D01*
G01X79243Y1348451D02*
X79143D01*
G01X78573Y1348320D02*
X78473D01*
G01X79243Y1348288D02*
X79143D01*
G01X73228Y1347185D02*
X70866D01*
G01X68110Y1347087D02*
X80118D01*
G01X68110Y1345906D02*
X80118D01*
G01X73228Y1345807D02*
X70866D01*
G01X73228Y1344036D02*
X70866D01*
G01X68110Y1343937D02*
X80118D01*
G01X68110Y1342756D02*
X80118D01*
G01X73228Y1342658D02*
X70866D01*
G01X79210Y1350945D02*
X79344Y1350912D01*
G01X78573Y1350847D02*
X78707Y1350814D01*
G01X79243Y1349469D02*
X79411Y1349403D01*
G01X79143Y1348288D02*
X78975Y1348353D01*
G01X78473Y1348320D02*
X78305Y1348386D01*
G01X82677Y1360630D02*
X79527Y1361811D01*
G01X82677Y1355630D02*
X79527Y1356811D01*
G01X79310Y1350715D02*
X79210Y1350748D01*
G01X78640Y1350617D02*
X78540Y1350650D01*
G01X78439Y1349829D02*
X78339Y1349862D01*
G01X75590Y1348268D02*
X73228Y1348957D01*
G01X75590Y1345118D02*
X73228Y1345807D01*
G01X79109Y1349731D02*
X78975Y1349797D01*
G01X78372Y1350059D02*
X78439Y1350026D01*
G01X78573Y1349436D02*
X78707Y1349370D01*
G01X79243Y1349304D02*
X79377Y1349206D01*
G01X78339Y1349862D02*
X78205Y1349961D01*
G01X79143Y1348451D02*
X79009Y1348550D01*
G01X79042Y1349993D02*
X79143Y1349928D01*
G01X78540Y1349272D02*
X78640Y1349206D01*
G01X78473Y1348484D02*
X78372Y1348550D01*
G01X79344Y1350912D02*
X79512Y1350814D01*
G01X79411Y1350617D02*
X79310Y1350715D01*
G01X78707Y1350814D02*
X78842Y1350682D01*
G01X79411Y1349403D02*
X79512Y1349304D01*
G01X78975Y1349797D02*
X78842Y1349928D01*
G01X78305Y1350125D02*
X78372Y1350059D01*
G01X78707Y1349370D02*
X78808Y1349272D01*
G01X78305Y1348386D02*
X78205Y1348484D01*
G01Y1349961D02*
X78104Y1350092D01*
G01X78640Y1349206D02*
X78741Y1349075D01*
G01X78975Y1348353D02*
X78875Y1348484D01*
G01X78372Y1348550D02*
X78272Y1348681D01*
G01X79512Y1350814D02*
X79612Y1350650D01*
G01X79512Y1349304D02*
X79612Y1349140D01*
G01X78205Y1348484D02*
X78104Y1348648D01*
G01X78707Y1350518D02*
X78640Y1350617D01*
G01X78975Y1350092D02*
X79042Y1349993D01*
G01X78842Y1350682D02*
X78908Y1350551D01*
G01X79377Y1349206D02*
X79444Y1349075D01*
G01X78842Y1349928D02*
X78774Y1350059D01*
G01X78808Y1349272D02*
X78842Y1349206D01*
G01X79009Y1348550D02*
X78942Y1348681D01*
G01X78875Y1348484D02*
X78842Y1348550D01*
G01X79612Y1350650D02*
X79645Y1350486D01*
G01X79629Y1349055D02*
X79645Y1348977D01*
G01X79612Y1349140D02*
X79629Y1349055D01*
G01X78774Y1350059D02*
X78741Y1350223D01*
G01X78075Y1350236D02*
X78071Y1350256D01*
G01X78104Y1350092D02*
X78075Y1350236D01*
G01X78104Y1348648D02*
X78071Y1348812D01*
G01X79444Y1350486D02*
X79411Y1350617D01*
G01X79449Y1349055D02*
X79478Y1348943D01*
G01X79444Y1349075D02*
X79449Y1349055D01*
G01X78908Y1350551D02*
X78942Y1350420D01*
G01Y1350223D02*
X78975Y1350092D01*
G01X78942Y1348681D02*
X78908Y1348812D01*
G01X78746Y1349055D02*
X78774Y1348943D01*
G01X78741Y1349075D02*
X78746Y1349055D01*
G01X78272Y1348681D02*
X78238Y1348812D01*
G01X78741Y1350420D02*
X78707Y1350518D01*
G01X78272Y1350223D02*
X78305Y1350125D01*
G01X82008Y1353484D02*
Y1351910D01*
G01Y1358484D02*
Y1356910D01*
G01Y1363484D02*
Y1361910D01*
G01X80433Y1353484D02*
Y1351910D01*
G01Y1358484D02*
Y1356910D01*
G01Y1363484D02*
Y1361910D01*
G01X80118Y1343937D02*
Y1342756D01*
G01Y1347087D02*
Y1345906D01*
G01Y1350236D02*
Y1349055D01*
G01X79645Y1348977D02*
Y1348780D01*
G01Y1350486D02*
Y1350236D01*
G01D02*
Y1350223D01*
G01X79478Y1348943D02*
Y1348812D01*
G01X79444Y1350236D02*
Y1350486D01*
G01Y1350223D02*
Y1350236D01*
G01X79210Y1350748D02*
Y1350945D01*
G01X78942Y1350420D02*
Y1350236D01*
G01D02*
Y1350223D01*
G01X78937Y1351811D02*
Y1351221D01*
G01X78908Y1348812D02*
Y1348943D01*
G01X78774D02*
Y1348812D01*
G01X78741Y1350236D02*
Y1350420D01*
G01Y1350223D02*
Y1350236D01*
G01X78439Y1350026D02*
Y1349829D01*
G01X78272Y1350420D02*
Y1350236D01*
G01D02*
Y1350223D01*
G01X78238Y1348812D02*
Y1348943D01*
G01X78071Y1350256D02*
Y1350420D01*
G01Y1348812D02*
Y1348943D01*
G01X77756Y1358819D02*
Y1361575D01*
G01X75590Y1348268D02*
Y1347874D01*
G01Y1345118D02*
Y1344725D01*
G01Y1351221D02*
Y1351024D01*
G01X75512Y1349055D02*
Y1350236D01*
G01Y1345906D02*
Y1347087D01*
G01Y1342756D02*
Y1343937D01*
G01X75118D02*
Y1342756D01*
G01Y1347087D02*
Y1345906D01*
G01Y1350236D02*
Y1349055D01*
G01X74803Y1351910D02*
Y1351811D01*
G01Y1353583D02*
Y1353484D01*
G01D02*
Y1351910D01*
G01Y1356910D02*
Y1356811D01*
G01Y1358583D02*
Y1358484D01*
G01D02*
Y1356910D01*
G01Y1361910D02*
Y1361811D01*
G01Y1363484D02*
Y1361910D01*
G01X74330Y1343937D02*
Y1342756D01*
G01Y1347087D02*
Y1345906D01*
G01Y1350236D02*
Y1349055D01*
G01X73228Y1344036D02*
X75590Y1344725D01*
G01X73228Y1347185D02*
X75590Y1347874D01*
G01X73228Y1350335D02*
X75590Y1351024D01*
G01X78473Y1350650D02*
X78372Y1350617D01*
G01X79527Y1353583D02*
X82677Y1354764D01*
G01X79527Y1358583D02*
X82677Y1359764D01*
G01X79411Y1348353D02*
X79243Y1348288D01*
G01X78975Y1349403D02*
X79143Y1349469D01*
G01X78305Y1349370D02*
X78473Y1349436D01*
G01X78707Y1348386D02*
X78573Y1348320D01*
G01X79411Y1349797D02*
X79277Y1349731D01*
G01X79478Y1348812D02*
X79444Y1348681D01*
G01X79411Y1350092D02*
X79444Y1350223D01*
G01X78908Y1348943D02*
X78937Y1349055D01*
G01D02*
X78942Y1349075D01*
G01X78774Y1348812D02*
X78741Y1348681D01*
G01X78238Y1348943D02*
X78267Y1349055D01*
G01D02*
X78272Y1349075D01*
G01X78071Y1350420D02*
X78104Y1350551D01*
G01X79645Y1348780D02*
X79612Y1348616D01*
G01X79645Y1350223D02*
X79612Y1350059D01*
G01X78071Y1348943D02*
X78093Y1349055D01*
G01D02*
X78104Y1349108D01*
G01X72756Y1343937D02*
Y1342756D01*
G01Y1347087D02*
Y1345906D01*
G01Y1350236D02*
Y1349055D01*
G01X70866Y1350236D02*
Y1388288D01*
G01Y1349055D02*
Y1350236D01*
G01Y1347087D02*
Y1349055D01*
G01Y1343937D02*
Y1345906D01*
G01D02*
Y1347087D01*
G01Y1342756D02*
Y1343937D01*
G01X78640Y1348550D02*
X78540Y1348484D01*
G01X78372Y1349206D02*
X78473Y1349272D01*
G01X79243Y1349928D02*
X79344Y1349993D01*
G01X79377Y1348550D02*
X79243Y1348451D01*
G01X79009Y1349206D02*
X79143Y1349304D01*
G01X79512Y1348451D02*
X79411Y1348353D01*
G01X78808Y1348484D02*
X78707Y1348386D01*
G01X79545Y1349928D02*
X79411Y1349797D01*
G01X78205Y1349272D02*
X78305Y1349370D01*
G01X78171Y1350682D02*
X78305Y1350814D01*
G01X78741Y1348681D02*
X78640Y1348550D01*
G01X78875Y1349272D02*
X78975Y1349403D01*
G01X78272Y1349075D02*
X78372Y1349206D01*
G01X79344Y1349993D02*
X79411Y1350092D01*
G01X78372Y1350617D02*
X78305Y1350518D01*
G01X79612Y1348616D02*
X79512Y1348451D01*
G01X78104Y1349108D02*
X78205Y1349272D01*
G01X79444Y1348681D02*
X79377Y1348550D01*
G01X78842D02*
X78808Y1348484D01*
G01X79612Y1350059D02*
X79545Y1349928D01*
G01X78942Y1349075D02*
X79009Y1349206D01*
G01X78842D02*
X78875Y1349272D01*
G01X78104Y1350551D02*
X78171Y1350682D01*
G01X78305Y1350518D02*
X78272Y1350420D01*
G01X79527Y1383583D02*
X74803D01*
G01X70866Y1383484D02*
X88110D01*
G01X70866Y1381910D02*
X88110D01*
G01X74803Y1381811D02*
X79527D01*
G01Y1378583D02*
X74803D01*
G01X70866Y1378484D02*
X88110D01*
G01X70866Y1376910D02*
X88110D01*
G01X74803Y1376811D02*
X79527D01*
G01Y1373583D02*
X74803D01*
G01X70866Y1373484D02*
X88110D01*
G01X70866Y1371910D02*
X88110D01*
G01X74803Y1371811D02*
X79527D01*
G01Y1368583D02*
X74803D01*
G01X70866Y1368484D02*
X88110D01*
G01X70866Y1366910D02*
X88110D01*
G01X74803Y1366811D02*
X79527D01*
G01Y1363583D02*
X74803D01*
G01X70866Y1363484D02*
X88110D01*
G01X82677Y1380630D02*
X79527Y1381811D01*
G01X82677Y1375630D02*
X79527Y1376811D01*
G01X82677Y1370630D02*
X79527Y1371811D01*
G01X82677Y1365630D02*
X79527Y1366811D01*
G01X82008Y1368484D02*
Y1366910D01*
G01Y1373484D02*
Y1371910D01*
G01Y1378484D02*
Y1376910D01*
G01Y1383484D02*
Y1381910D01*
G01X80433Y1368484D02*
Y1366910D01*
G01Y1373484D02*
Y1371910D01*
G01Y1378484D02*
Y1376910D01*
G01Y1383484D02*
Y1381910D01*
G01X74803Y1363583D02*
Y1363484D01*
G01Y1366910D02*
Y1366811D01*
G01Y1368583D02*
Y1368484D01*
G01Y1371910D02*
Y1371811D01*
G01Y1368484D02*
Y1366910D01*
G01Y1373583D02*
Y1373484D01*
G01Y1376910D02*
Y1376811D01*
G01Y1373484D02*
Y1371910D01*
G01Y1378583D02*
Y1378484D01*
G01Y1381910D02*
Y1381811D01*
G01Y1378484D02*
Y1376910D01*
G01Y1383583D02*
Y1383484D01*
G01D02*
Y1381910D01*
G01X79527Y1363583D02*
X82677Y1364764D01*
G01X79527Y1368583D02*
X82677Y1369764D01*
G01X79527Y1373583D02*
X82677Y1374764D01*
G01X79527Y1378583D02*
X82677Y1379764D01*
G01X79527Y1383583D02*
X82677Y1384764D01*
G01X80708Y1395000D02*
G03I-2559J0D01*
G01X81496D02*
G03I-3347J0D01*
G01X81653D02*
G03I-3504J0D01*
G01X78075Y1399133D02*
G03X78149Y1390866I73J-4133D01*
G01X78224Y1390867D02*
G03X78149Y1399134I-75J4133D01*
G01X72638Y1406811D02*
G03I-3741J0D01*
G01X90551Y1394390D02*
X70079D01*
G01X90551Y1388288D02*
X70866D01*
G01X78075Y1399134D02*
X78149D01*
G01X78224Y1390867D02*
X78149Y1390866D01*
G01X70866Y1386516D02*
X90551D01*
G01X69586D02*
X70866D01*
G01X78740Y1399784D02*
Y1412736D01*
G01X70079Y1399784D02*
Y1391437D01*
G01X72047Y1423780D02*
G03Y1422599I0J-590D01*
G01Y1426536D02*
G03Y1425354I0J-591D01*
G01X65748Y1422599D02*
G03Y1423780I0J591D01*
G01Y1425354D02*
G03Y1426536I0J591D01*
G01X72047Y1426831D02*
X73622D01*
G01X70472D02*
X72047D01*
G01X65748D02*
X64173D01*
G01X67323D02*
X65748D01*
G01X64173Y1424862D02*
X65748D01*
G01D02*
X67323D01*
G01X73622D02*
X72047D01*
G01D02*
X70472D01*
G01X64173Y1424272D02*
X65748D01*
G01D02*
X67323D01*
G01X73622D02*
X72047D01*
G01D02*
X70472D01*
G01X65759Y1423528D02*
X65852D01*
G01Y1422780D02*
X65759D01*
G01X72047Y1422303D02*
X73622D01*
G01X70472D02*
X72047D01*
G01X65748D02*
X64173D01*
G01X67323D02*
X65748D01*
G01Y1422008D02*
X72047D01*
G01X78543Y1406024D02*
Y1407599D01*
G01X73622Y1422303D02*
Y1424272D01*
G01Y1426831D02*
Y1424862D01*
G01X73189Y1407599D02*
Y1406024D01*
G01X72047Y1423780D02*
Y1425354D01*
G01Y1426536D02*
Y1427126D01*
G01Y1422008D02*
Y1422599D01*
G01X71850Y1407599D02*
Y1407795D01*
G01Y1406024D02*
Y1405827D01*
G01Y1407599D02*
Y1406024D01*
G01X71653Y1407599D02*
Y1406024D01*
G01X71063Y1422008D02*
Y1427126D01*
G01X70866D02*
Y1422008D01*
G01X70472Y1424862D02*
Y1426831D01*
G01Y1424272D02*
Y1422303D01*
G01X70079Y1406024D02*
Y1407599D01*
G01X67716Y1406024D02*
Y1407599D01*
G01X67323Y1424862D02*
Y1426831D01*
G01Y1424272D02*
Y1422303D01*
G01X66929Y1427126D02*
Y1422008D01*
G01X66732D02*
Y1427126D01*
G01X66142Y1406024D02*
Y1407599D01*
G01X65945Y1406024D02*
Y1407599D01*
G01Y1406024D02*
Y1405827D01*
G01Y1407795D02*
Y1407599D01*
G01X65852Y1423528D02*
Y1422780D01*
G01X65759D02*
Y1423400D01*
G01X65748Y1422599D02*
Y1422008D01*
G01Y1425354D02*
Y1423780D01*
G01Y1427126D02*
Y1426536D01*
G01X65665Y1423289D02*
Y1423416D01*
G01X64606Y1406024D02*
Y1407599D01*
G01X64173Y1422303D02*
Y1424272D01*
G01Y1426831D02*
Y1424862D01*
G01X65759Y1423400D02*
X65665Y1423289D01*
G01Y1423416D02*
X65759Y1423528D01*
G01X65748Y1427126D02*
X72047D01*
G01X72638Y1639095D02*
G03I-3741J0D01*
G01X78740Y1633169D02*
Y1646122D01*
G01X78543Y1638307D02*
Y1639882D01*
G01X73189D02*
Y1638307D01*
G01X71850D02*
Y1638110D01*
G01Y1639882D02*
Y1638307D01*
G01X71653Y1639882D02*
Y1638307D01*
G01X70079D02*
Y1639882D01*
G01X67716Y1638307D02*
Y1639882D01*
G01X66142Y1638307D02*
Y1639882D01*
G01X65945Y1638307D02*
Y1639882D01*
G01Y1638307D02*
Y1638110D01*
G01X64606Y1638307D02*
Y1639882D01*
G01X75899Y1648826D02*
X75779Y1648543D01*
G01X76017Y1649088D02*
X75899Y1648826D01*
G01X76132Y1649331D02*
X76017Y1649088D01*
G01X75779Y1648542D02*
Y1648543D01*
G01X75766Y1648511D02*
X75779Y1648542D01*
G01X80520Y1653269D02*
Y1653268D01*
G01X80533Y1653300D02*
X80520Y1653269D01*
G01X80286Y1652732D02*
X80167Y1652480D01*
G01X80404Y1652995D02*
X80286Y1652732D01*
G01X80520Y1653268D02*
X80404Y1652995D01*
G01X80281Y1649089D02*
X80167Y1649331D01*
G01X80399Y1648827D02*
X80281Y1649089D01*
G01X80520Y1648543D02*
X80399Y1648827D01*
G01X75895Y1652995D02*
X75779Y1653268D01*
G01X76013Y1652733D02*
X75895Y1652995D01*
G01X76132Y1652480D02*
X76013Y1652733D01*
G01X80167Y1649331D02*
G03Y1652480I-2018J1574D01*
G01X76132D02*
G03Y1649331I2017J-1574D01*
G01X80520Y1648543D02*
G03Y1653268I-2370J2362D01*
G01X75779D02*
G03Y1648543I2370J-2362D01*
G01X81653Y1650906D02*
G03I-3504J0D01*
G01X75472Y1654055D02*
G03Y1647756I2677J-3149D01*
G01X80827D02*
G03Y1654055I-2678J3149D01*
G01X69586Y1659390D02*
X70866D01*
G01X90551D02*
X70866D01*
G01Y1657618D02*
X90551D01*
G01X75472Y1654055D02*
X80827D01*
G01X80520Y1653268D02*
X75779D01*
G01X80167Y1652480D02*
X76132D01*
G01X70079Y1651516D02*
X90551D01*
G01X80167Y1649331D02*
X76132D01*
G01X75779Y1648543D02*
X80520D01*
G01X80827Y1647756D02*
X75472D01*
G01X80772Y1647904D02*
X80827Y1647756D01*
G01X75527Y1653907D02*
X75472Y1654055D01*
G01X80736Y1648000D02*
X80772Y1647904D01*
G01X75562Y1653811D02*
X75527Y1653907D01*
G01X80701Y1648091D02*
X80736Y1648000D01*
G01X75597Y1653720D02*
X75562Y1653811D01*
G01X80668Y1648177D02*
X80701Y1648091D01*
G01X75631Y1653634D02*
X75597Y1653720D01*
G01X80596Y1648356D02*
X80668Y1648177D01*
G01X75703Y1653454D02*
X75631Y1653634D01*
G01X80563Y1648438D02*
X80596Y1648356D01*
G01X75736Y1653373D02*
X75703Y1653454D01*
G01X80520Y1648543D02*
X80563Y1648438D01*
G01X75779Y1653268D02*
X75736Y1653373D01*
G01X71850Y1639882D02*
Y1640079D01*
G01X70866Y1657618D02*
Y1677421D01*
G01X70079Y1646122D02*
Y1654469D01*
G01X69586Y1659390D02*
Y1792028D01*
G01X68208D02*
Y1659390D01*
G01X66929D02*
Y1792028D01*
G01X65945Y1640079D02*
Y1639882D01*
G01X80573Y1653398D02*
X80533Y1653300D01*
G01X75725Y1648413D02*
X75766Y1648511D01*
G01X80609Y1653486D02*
X80573Y1653398D01*
G01X75690Y1648325D02*
X75725Y1648413D01*
G01X80668Y1653634D02*
X80609Y1653486D01*
G01X75631Y1648178D02*
X75690Y1648325D01*
G01X80701Y1653719D02*
X80668Y1653634D01*
G01X75597Y1648091D02*
X75631Y1648178D01*
G01X80736Y1653811D02*
X80701Y1653719D01*
G01X75562Y1648000D02*
X75597Y1648091D01*
G01X80772Y1653907D02*
X80736Y1653811D01*
G01X75527Y1647904D02*
X75562Y1648000D01*
G01X80827Y1654055D02*
X80772Y1653907D01*
G01X75472Y1647756D02*
X75527Y1647904D01*
G01X77559Y1679095D02*
X82677Y1680276D01*
G01X70866Y1680571D02*
X69685D01*
G01X77756Y1679331D02*
X70866D01*
G01X77559Y1679095D02*
X72834D01*
G01X69685Y1678996D02*
X89567D01*
G01X69685Y1677421D02*
X89567D01*
G01X72834Y1677323D02*
X77559D01*
G01X69685Y1675847D02*
X70866D01*
G01X79527Y1674095D02*
X74803D01*
G01X70866Y1673996D02*
X88110D01*
G01X70866Y1672421D02*
X88110D01*
G01X74803Y1672323D02*
X79527D01*
G01Y1669095D02*
X74803D01*
G01X70866Y1668996D02*
X88110D01*
G01X70866Y1667421D02*
X88110D01*
G01X74803Y1667323D02*
X79527D01*
G01Y1664095D02*
X74803D01*
G01X70866Y1663996D02*
X88110D01*
G01X70866Y1662421D02*
X88110D01*
G01X74803Y1662323D02*
X79527D01*
G01X82677Y1676142D02*
X77559Y1677323D01*
G01X82677Y1671142D02*
X79527Y1672323D01*
G01X82677Y1666142D02*
X79527Y1667323D01*
G01X82677Y1661142D02*
X79527Y1662323D01*
G01X82008Y1663996D02*
Y1662421D01*
G01Y1668996D02*
Y1667421D01*
G01Y1673996D02*
Y1672421D01*
G01Y1678996D02*
Y1677421D01*
G01X80433Y1663996D02*
Y1662421D01*
G01Y1668996D02*
Y1667421D01*
G01Y1673996D02*
Y1672421D01*
G01Y1678996D02*
Y1677421D01*
G01X77756Y1679331D02*
Y1682087D01*
G01X74803Y1662421D02*
Y1662323D01*
G01Y1664095D02*
Y1663996D01*
G01Y1667421D02*
Y1667323D01*
G01Y1663996D02*
Y1662421D01*
G01Y1669095D02*
Y1668996D01*
G01Y1672421D02*
Y1672323D01*
G01Y1668996D02*
Y1667421D01*
G01Y1674095D02*
Y1673996D01*
G01D02*
Y1672421D01*
G01X72834Y1677421D02*
Y1677323D01*
G01Y1679095D02*
Y1678996D01*
G01D02*
Y1677421D01*
G01X70866D02*
Y1678996D01*
G01D02*
Y1717421D01*
G01X69685Y1680571D02*
Y1675847D01*
G01X79527Y1664095D02*
X82677Y1665276D01*
G01X79527Y1669095D02*
X82677Y1670276D01*
G01X79527Y1674095D02*
X82677Y1675276D01*
G01X79527Y1699095D02*
X74803D01*
G01X70866Y1698996D02*
X88110D01*
G01X70866Y1697421D02*
X88110D01*
G01X74803Y1697323D02*
X79527D01*
G01Y1694095D02*
X74803D01*
G01X70866Y1693996D02*
X88110D01*
G01X70866Y1692421D02*
X88110D01*
G01X74803Y1692323D02*
X79527D01*
G01Y1689095D02*
X74803D01*
G01X70866Y1688996D02*
X88110D01*
G01X70866Y1687421D02*
X88110D01*
G01X74803Y1687323D02*
X79527D01*
G01Y1684095D02*
X74803D01*
G01X70866Y1683996D02*
X88110D01*
G01X70866Y1682421D02*
X88110D01*
G01X74803Y1682323D02*
X79527D01*
G01X70866Y1682087D02*
X77756D01*
G01X82677Y1701142D02*
X79527Y1702323D01*
G01X82677Y1696142D02*
X79527Y1697323D01*
G01X82677Y1691142D02*
X79527Y1692323D01*
G01X82677Y1686142D02*
X79527Y1687323D01*
G01X82677Y1681142D02*
X79527Y1682323D01*
G01X82008Y1683996D02*
Y1682421D01*
G01Y1688996D02*
Y1687421D01*
G01Y1693996D02*
Y1692421D01*
G01Y1698996D02*
Y1697421D01*
G01X80433Y1683996D02*
Y1682421D01*
G01Y1688996D02*
Y1687421D01*
G01Y1693996D02*
Y1692421D01*
G01Y1698996D02*
Y1697421D01*
G01X74803Y1682421D02*
Y1682323D01*
G01Y1684095D02*
Y1683996D01*
G01D02*
Y1682421D01*
G01Y1687421D02*
Y1687323D01*
G01Y1689095D02*
Y1688996D01*
G01D02*
Y1687421D01*
G01Y1692421D02*
Y1692323D01*
G01Y1694095D02*
Y1693996D01*
G01D02*
Y1692421D01*
G01Y1697421D02*
Y1697323D01*
G01Y1699095D02*
Y1698996D01*
G01D02*
Y1697421D01*
G01X79527Y1684095D02*
X82677Y1685276D01*
G01X79527Y1689095D02*
X82677Y1690276D01*
G01X79527Y1694095D02*
X82677Y1695276D01*
G01X79527Y1699095D02*
X82677Y1700276D01*
G01X77559Y1719095D02*
X82677Y1720276D01*
G01X70866Y1722421D02*
X88110D01*
G01X74803Y1722323D02*
X79527D01*
G01X70866Y1720571D02*
X69685D01*
G01X77559Y1719095D02*
X72834D01*
G01X69685Y1718996D02*
X89567D01*
G01X69685Y1717421D02*
X89567D01*
G01X72834Y1717323D02*
X77559D01*
G01X69685Y1715847D02*
X70866D01*
G01X79527Y1714095D02*
X74803D01*
G01X70866Y1713996D02*
X88110D01*
G01X70866Y1712421D02*
X88110D01*
G01X74803Y1712323D02*
X79527D01*
G01Y1709095D02*
X74803D01*
G01X70866Y1708996D02*
X88110D01*
G01X70866Y1707421D02*
X88110D01*
G01X74803Y1707323D02*
X79527D01*
G01X70866Y1707087D02*
X77756D01*
G01Y1704331D02*
X70866D01*
G01X79527Y1704095D02*
X74803D01*
G01X70866Y1703996D02*
X88110D01*
G01X70866Y1702421D02*
X88110D01*
G01X74803Y1702323D02*
X79527D01*
G01X82677Y1716142D02*
X77559Y1717323D01*
G01X82677Y1721142D02*
X79527Y1722323D01*
G01X82677Y1711142D02*
X79527Y1712323D01*
G01X82677Y1706142D02*
X79527Y1707323D01*
G01X82008Y1703996D02*
Y1702421D01*
G01Y1708996D02*
Y1707421D01*
G01Y1713996D02*
Y1712421D01*
G01Y1718996D02*
Y1717421D01*
G01Y1723996D02*
Y1722421D01*
G01X80433Y1703996D02*
Y1702421D01*
G01Y1708996D02*
Y1707421D01*
G01Y1713996D02*
Y1712421D01*
G01Y1718996D02*
Y1717421D01*
G01Y1723996D02*
Y1722421D01*
G01X77756Y1704331D02*
Y1707087D01*
G01X74803Y1702421D02*
Y1702323D01*
G01Y1704095D02*
Y1703996D01*
G01D02*
Y1702421D01*
G01Y1707421D02*
Y1707323D01*
G01Y1709095D02*
Y1708996D01*
G01D02*
Y1707421D01*
G01Y1712421D02*
Y1712323D01*
G01Y1714095D02*
Y1713996D01*
G01D02*
Y1712421D01*
G01Y1722421D02*
Y1722323D01*
G01Y1723996D02*
Y1722421D01*
G01X72834Y1717421D02*
Y1717323D01*
G01Y1719095D02*
Y1718996D01*
G01D02*
Y1717421D01*
G01X70866D02*
Y1718996D01*
G01D02*
Y1735669D01*
G01X69685Y1720571D02*
Y1715847D01*
G01X79527Y1704095D02*
X82677Y1705276D01*
G01X79527Y1709095D02*
X82677Y1710276D01*
G01X79527Y1714095D02*
X82677Y1715276D01*
G01X73228Y1743248D02*
X70866D01*
G01X68110Y1743150D02*
X80118D01*
G01X68110Y1741969D02*
X80118D01*
G01X73228Y1741870D02*
X70866D01*
G01X73228Y1740099D02*
X70866D01*
G01X68110Y1740000D02*
X80118D01*
G01X68110Y1738819D02*
X80118D01*
G01X73228Y1738721D02*
X70866D01*
G01X73228Y1736949D02*
X70866D01*
G01X68110Y1736851D02*
X80118D01*
G01X68110Y1735669D02*
X80118D01*
G01X73228Y1735571D02*
X70866D01*
G01X75590Y1734685D02*
X78937D01*
G01Y1734095D02*
X74803D01*
G01X70866Y1733996D02*
X89567D01*
G01X70866Y1732421D02*
X89567D01*
G01X74803Y1732323D02*
X79527D01*
G01X70866Y1732087D02*
X77756D01*
G01Y1729331D02*
X70866D01*
G01X79527Y1729095D02*
X74803D01*
G01X70866Y1728996D02*
X88110D01*
G01X70866Y1727421D02*
X88110D01*
G01X74803Y1727323D02*
X79527D01*
G01Y1724095D02*
X74803D01*
G01X70866Y1723996D02*
X88110D01*
G01X75590Y1741181D02*
X73228Y1741870D01*
G01X75590Y1738032D02*
X73228Y1738721D01*
G01X75590Y1734882D02*
X73228Y1735571D01*
G01X82677Y1731142D02*
X79527Y1732323D01*
G01X82677Y1726142D02*
X79527Y1727323D01*
G01X82008Y1728996D02*
Y1727421D01*
G01Y1733996D02*
Y1732421D01*
G01X80433Y1728996D02*
Y1727421D01*
G01Y1733996D02*
Y1732421D01*
G01X80118Y1736851D02*
Y1735669D01*
G01Y1740000D02*
Y1738819D01*
G01Y1743150D02*
Y1741969D01*
G01X78937Y1734685D02*
Y1734095D01*
G01X77756Y1729331D02*
Y1732087D01*
G01X75590Y1738032D02*
Y1737638D01*
G01Y1734882D02*
Y1734685D01*
G01Y1741181D02*
Y1740788D01*
G01Y1744331D02*
Y1743937D01*
G01X75512Y1741969D02*
Y1743150D01*
G01Y1738819D02*
Y1740000D01*
G01Y1735669D02*
Y1736851D01*
G01X75118D02*
Y1735669D01*
G01Y1740000D02*
Y1738819D01*
G01Y1743150D02*
Y1741969D01*
G01X74803Y1724095D02*
Y1723996D01*
G01Y1727421D02*
Y1727323D01*
G01Y1729095D02*
Y1728996D01*
G01Y1732421D02*
Y1732323D01*
G01Y1728996D02*
Y1727421D01*
G01Y1734095D02*
Y1733996D01*
G01D02*
Y1732421D01*
G01X74330Y1736851D02*
Y1735669D01*
G01Y1740000D02*
Y1738819D01*
G01Y1743150D02*
Y1741969D01*
G01X72756Y1736851D02*
Y1735669D01*
G01Y1740000D02*
Y1738819D01*
G01Y1743150D02*
Y1741969D01*
G01X70866Y1743150D02*
Y1745118D01*
G01Y1741969D02*
Y1743150D01*
G01Y1740000D02*
Y1741969D01*
G01Y1736851D02*
Y1738819D01*
G01D02*
Y1740000D01*
G01Y1735669D02*
Y1736851D01*
G01X68110Y1757914D02*
Y1733504D01*
G01X73228Y1736949D02*
X75590Y1737638D01*
G01X73228Y1740099D02*
X75590Y1740788D01*
G01X73228Y1743248D02*
X75590Y1743937D01*
G01X79527Y1724095D02*
X82677Y1725276D01*
G01X79527Y1729095D02*
X82677Y1730276D01*
G01X78305Y1756325D02*
X78439Y1756358D01*
G01X77756Y1764331D02*
X70866D01*
G01X79527Y1764095D02*
X74803D01*
G01X70866Y1763996D02*
X88110D01*
G01X70866Y1762421D02*
X88110D01*
G01X74803Y1762323D02*
X79527D01*
G01Y1759095D02*
X74803D01*
G01X70866Y1758996D02*
X88110D01*
G01X70866Y1757421D02*
X88110D01*
G01X74803Y1757323D02*
X78937D01*
G01Y1756732D02*
X75590D01*
G01X78439Y1756358D02*
X78573D01*
G01X78540Y1756162D02*
X78473D01*
G01X73228Y1755847D02*
X70866D01*
G01X68110Y1755748D02*
X80118D01*
G01X79143Y1755440D02*
X79243D01*
G01X79277Y1755243D02*
X79109D01*
G01X79143Y1754980D02*
X79243D01*
G01X78473Y1754947D02*
X78573D01*
G01X79143Y1754816D02*
X79243D01*
G01X78473Y1754784D02*
X78540D01*
G01X68110Y1754567D02*
X80118D01*
G01X73228Y1754469D02*
X70866D01*
G01X78540Y1753996D02*
X78473D01*
G01X79243Y1753963D02*
X79143D01*
G01X78573Y1753832D02*
X78473D01*
G01X79243Y1753799D02*
X79143D01*
G01X73228Y1752697D02*
X70866D01*
G01X68110Y1752599D02*
X80118D01*
G01X68110Y1751417D02*
X80118D01*
G01X73228Y1751319D02*
X70866D01*
G01X73228Y1749547D02*
X70866D01*
G01X68110Y1749449D02*
X80118D01*
G01X68110Y1748268D02*
X80118D01*
G01X73228Y1748169D02*
X70866D01*
G01X73228Y1746398D02*
X70866D01*
G01X68110Y1746299D02*
X80118D01*
G01X68110Y1745118D02*
X80118D01*
G01X73228Y1745020D02*
X70866D01*
G01X79210Y1756457D02*
X79344Y1756424D01*
G01X78573Y1756358D02*
X78707Y1756325D01*
G01X79243Y1754980D02*
X79411Y1754915D01*
G01X79143Y1753799D02*
X78975Y1753865D01*
G01X78473Y1753832D02*
X78305Y1753898D01*
G01X82677Y1761142D02*
X79527Y1762323D01*
G01X79310Y1756227D02*
X79210Y1756260D01*
G01X78640Y1756128D02*
X78540Y1756162D01*
G01X78439Y1755341D02*
X78339Y1755374D01*
G01X75590Y1753780D02*
X73228Y1754469D01*
G01X75590Y1750630D02*
X73228Y1751319D01*
G01X75590Y1747480D02*
X73228Y1748169D01*
G01X75590Y1744331D02*
X73228Y1745020D01*
G01X79109Y1755243D02*
X78975Y1755308D01*
G01X78372Y1755571D02*
X78439Y1755538D01*
G01X78573Y1754947D02*
X78707Y1754882D01*
G01X79042Y1755505D02*
X79143Y1755440D01*
G01X78540Y1754784D02*
X78640Y1754718D01*
G01X78473Y1753996D02*
X78372Y1754062D01*
G01X79344Y1756424D02*
X79512Y1756325D01*
G01X79243Y1754816D02*
X79377Y1754718D01*
G01X78339Y1755374D02*
X78205Y1755473D01*
G01X79143Y1753963D02*
X79009Y1754062D01*
G01X79411Y1756128D02*
X79310Y1756227D01*
G01X78707Y1756325D02*
X78842Y1756194D01*
G01X79411Y1754915D02*
X79512Y1754816D01*
G01X78975Y1755308D02*
X78842Y1755440D01*
G01X78305Y1755636D02*
X78372Y1755571D01*
G01X78707Y1754882D02*
X78808Y1754784D01*
G01X78305Y1753898D02*
X78205Y1753996D01*
G01Y1755473D02*
X78104Y1755604D01*
G01X78640Y1754718D02*
X78741Y1754587D01*
G01X78975Y1753865D02*
X78875Y1753996D01*
G01X78372Y1754062D02*
X78272Y1754193D01*
G01X79512Y1756325D02*
X79612Y1756162D01*
G01X79512Y1754816D02*
X79612Y1754652D01*
G01X78205Y1753996D02*
X78104Y1754160D01*
G01X78707Y1756030D02*
X78640Y1756128D01*
G01X78975Y1755604D02*
X79042Y1755505D01*
G01X78842Y1756194D02*
X78908Y1756063D01*
G01X79377Y1754718D02*
X79444Y1754587D01*
G01X78842Y1755440D02*
X78774Y1755571D01*
G01X78808Y1754784D02*
X78842Y1754718D01*
G01X79009Y1754062D02*
X78942Y1754193D01*
G01X78875Y1753996D02*
X78842Y1754062D01*
G01X78741Y1755932D02*
X78707Y1756030D01*
G01X78272Y1755735D02*
X78305Y1755636D01*
G01X79612Y1756162D02*
X79645Y1755997D01*
G01X79629Y1754567D02*
X79645Y1754488D01*
G01X79612Y1754652D02*
X79629Y1754567D01*
G01X78774Y1755571D02*
X78741Y1755735D01*
G01X78075Y1755748D02*
X78071Y1755768D01*
G01X78104Y1755604D02*
X78075Y1755748D01*
G01X78104Y1754160D02*
X78071Y1754324D01*
G01X79444Y1755997D02*
X79411Y1756128D01*
G01X79449Y1754567D02*
X79478Y1754455D01*
G01X79444Y1754587D02*
X79449Y1754567D01*
G01X78908Y1756063D02*
X78942Y1755932D01*
G01Y1755735D02*
X78975Y1755604D01*
G01X78942Y1754193D02*
X78908Y1754324D01*
G01X78746Y1754567D02*
X78774Y1754455D01*
G01X78741Y1754587D02*
X78746Y1754567D01*
G01X78272Y1754193D02*
X78238Y1754324D01*
G01X82008Y1758996D02*
Y1757421D01*
G01Y1763996D02*
Y1762421D01*
G01X80433Y1758996D02*
Y1757421D01*
G01Y1763996D02*
Y1762421D01*
G01X80118Y1746299D02*
Y1745118D01*
G01Y1749449D02*
Y1748268D01*
G01Y1752599D02*
Y1751417D01*
G01Y1755748D02*
Y1754567D01*
G01X79645Y1754488D02*
Y1754291D01*
G01Y1755997D02*
Y1755748D01*
G01D02*
Y1755735D01*
G01X79478Y1754455D02*
Y1754324D01*
G01X79444Y1755748D02*
Y1755997D01*
G01Y1755735D02*
Y1755748D01*
G01X79210Y1756260D02*
Y1756457D01*
G01X78942Y1755932D02*
Y1755748D01*
G01D02*
Y1755735D01*
G01X78937Y1757323D02*
Y1756732D01*
G01X78908Y1754324D02*
Y1754455D01*
G01X78774D02*
Y1754324D01*
G01X78741Y1755748D02*
Y1755932D01*
G01Y1755735D02*
Y1755748D01*
G01X78439Y1755538D02*
Y1755341D01*
G01X78272Y1755932D02*
Y1755748D01*
G01D02*
Y1755735D01*
G01X78238Y1754324D02*
Y1754455D01*
G01X78071Y1754324D02*
Y1754455D01*
G01Y1755768D02*
Y1755932D01*
G01X77756Y1764331D02*
Y1767087D01*
G01X75590Y1750630D02*
Y1750236D01*
G01Y1747480D02*
Y1747087D01*
G01Y1756732D02*
Y1756536D01*
G01Y1753780D02*
Y1753386D01*
G01X75512Y1754567D02*
Y1755748D01*
G01Y1751417D02*
Y1752599D01*
G01Y1748268D02*
Y1749449D01*
G01Y1745118D02*
Y1746299D01*
G01X75118D02*
Y1745118D01*
G01Y1749449D02*
Y1748268D01*
G01Y1752599D02*
Y1751417D01*
G01Y1755748D02*
Y1754567D01*
G01X74803Y1757421D02*
Y1757323D01*
G01Y1759095D02*
Y1758996D01*
G01D02*
Y1757421D01*
G01Y1762421D02*
Y1762323D01*
G01Y1764095D02*
Y1763996D01*
G01D02*
Y1762421D01*
G01X74330Y1746299D02*
Y1745118D01*
G01Y1749449D02*
Y1748268D01*
G01Y1755748D02*
Y1754567D01*
G01Y1752599D02*
Y1751417D01*
G01X72756Y1746299D02*
Y1745118D01*
G01Y1749449D02*
Y1748268D01*
G01Y1755748D02*
Y1754567D01*
G01Y1752599D02*
Y1751417D01*
G01X70866Y1755748D02*
Y1793799D01*
G01Y1752599D02*
Y1754567D01*
G01D02*
Y1755748D01*
G01Y1751417D02*
Y1752599D01*
G01Y1749449D02*
Y1751417D01*
G01Y1746299D02*
Y1748268D01*
G01D02*
Y1749449D01*
G01Y1745118D02*
Y1746299D01*
G01X79645Y1754291D02*
X79612Y1754127D01*
G01X79645Y1755735D02*
X79612Y1755571D01*
G01X78071Y1754455D02*
X78093Y1754567D01*
G01D02*
X78104Y1754619D01*
G01X78305Y1756030D02*
X78272Y1755932D01*
G01X79478Y1754324D02*
X79444Y1754193D01*
G01X79411Y1755604D02*
X79444Y1755735D01*
G01X78908Y1754455D02*
X78937Y1754567D01*
G01D02*
X78942Y1754587D01*
G01X78774Y1754324D02*
X78741Y1754193D01*
G01X78238Y1754455D02*
X78267Y1754567D01*
G01D02*
X78272Y1754587D01*
G01X78071Y1755932D02*
X78104Y1756063D01*
G01X79444Y1754193D02*
X79377Y1754062D01*
G01X79612Y1755571D02*
X79545Y1755440D01*
G01X78842Y1754062D02*
X78808Y1753996D01*
G01X78942Y1754587D02*
X79009Y1754718D01*
G01X78842D02*
X78875Y1754784D01*
G01X78104Y1756063D02*
X78171Y1756194D01*
G01X78741Y1754193D02*
X78640Y1754062D01*
G01X78875Y1754784D02*
X78975Y1754915D01*
G01X78272Y1754587D02*
X78372Y1754718D01*
G01X79344Y1755505D02*
X79411Y1755604D01*
G01X78372Y1756128D02*
X78305Y1756030D01*
G01X79612Y1754127D02*
X79512Y1753963D01*
G01X78104Y1754619D02*
X78205Y1754784D01*
G01X73228Y1746398D02*
X75590Y1747087D01*
G01X73228Y1749547D02*
X75590Y1750236D01*
G01X73228Y1752697D02*
X75590Y1753386D01*
G01X73228Y1755847D02*
X75590Y1756536D01*
G01X78473Y1756162D02*
X78372Y1756128D01*
G01X79527Y1759095D02*
X82677Y1760276D01*
G01X79527Y1764095D02*
X82677Y1765276D01*
G01X79411Y1753865D02*
X79243Y1753799D01*
G01X78975Y1754915D02*
X79143Y1754980D01*
G01X78305Y1754882D02*
X78473Y1754947D01*
G01X78707Y1753898D02*
X78573Y1753832D01*
G01X79411Y1755308D02*
X79277Y1755243D01*
G01X78640Y1754062D02*
X78540Y1753996D01*
G01X78372Y1754718D02*
X78473Y1754784D01*
G01X79243Y1755440D02*
X79344Y1755505D01*
G01X79377Y1754062D02*
X79243Y1753963D01*
G01X79009Y1754718D02*
X79143Y1754816D01*
G01X79512Y1753963D02*
X79411Y1753865D01*
G01X78808Y1753996D02*
X78707Y1753898D01*
G01X79545Y1755440D02*
X79411Y1755308D01*
G01X78205Y1754784D02*
X78305Y1754882D01*
G01X78171Y1756194D02*
X78305Y1756325D01*
G01X79527Y1784095D02*
X74803D01*
G01X70866Y1783996D02*
X88110D01*
G01X70866Y1782421D02*
X88110D01*
G01X74803Y1782323D02*
X79527D01*
G01Y1779095D02*
X74803D01*
G01X70866Y1778996D02*
X88110D01*
G01X70866Y1777421D02*
X88110D01*
G01X74803Y1777323D02*
X79527D01*
G01Y1774095D02*
X74803D01*
G01X70866Y1773996D02*
X88110D01*
G01X70866Y1772421D02*
X88110D01*
G01X74803Y1772323D02*
X79527D01*
G01Y1769095D02*
X74803D01*
G01X70866Y1768996D02*
X88110D01*
G01X70866Y1767421D02*
X88110D01*
G01X74803Y1767323D02*
X79527D01*
G01X70866Y1767087D02*
X77756D01*
G01X82677Y1786142D02*
X79527Y1787323D01*
G01X82677Y1781142D02*
X79527Y1782323D01*
G01X82677Y1776142D02*
X79527Y1777323D01*
G01X82677Y1771142D02*
X79527Y1772323D01*
G01X82677Y1766142D02*
X79527Y1767323D01*
G01X82008Y1768996D02*
Y1767421D01*
G01Y1773996D02*
Y1772421D01*
G01Y1778996D02*
Y1777421D01*
G01Y1783996D02*
Y1782421D01*
G01X80433Y1768996D02*
Y1767421D01*
G01Y1773996D02*
Y1772421D01*
G01Y1778996D02*
Y1777421D01*
G01Y1783996D02*
Y1782421D01*
G01X74803Y1767421D02*
Y1767323D01*
G01Y1769095D02*
Y1768996D01*
G01D02*
Y1767421D01*
G01Y1772421D02*
Y1772323D01*
G01Y1774095D02*
Y1773996D01*
G01D02*
Y1772421D01*
G01Y1777421D02*
Y1777323D01*
G01Y1779095D02*
Y1778996D01*
G01D02*
Y1777421D01*
G01Y1782421D02*
Y1782323D01*
G01Y1784095D02*
Y1783996D01*
G01D02*
Y1782421D01*
G01X79527Y1769095D02*
X82677Y1770276D01*
G01X79527Y1774095D02*
X82677Y1775276D01*
G01X79527Y1779095D02*
X82677Y1780276D01*
G01X79527Y1784095D02*
X82677Y1785276D01*
G01X80708Y1800512D02*
G03I-2559J0D01*
G01X81496D02*
G03I-3347J0D01*
G01X81653D02*
G03I-3504J0D01*
G01X78075Y1804645D02*
G03X78149Y1796378I73J-4133D01*
G01X78224D02*
G03X78149Y1804646I-75J4134D01*
G01X90551Y1799902D02*
X70079D01*
G01X90551Y1793799D02*
X70866D01*
G01Y1792028D02*
X90551D01*
G01X69586D02*
X70866D01*
G01X79527Y1789095D02*
X74803D01*
G01X70866Y1788996D02*
X88110D01*
G01X70866Y1787421D02*
X88110D01*
G01X74803Y1787323D02*
X79527D01*
G01X78075Y1804645D02*
X78149D01*
G01X78224Y1796378D02*
X78149D01*
G01X82008Y1788996D02*
Y1787421D01*
G01X80433Y1788996D02*
Y1787421D01*
G01X78740Y1805295D02*
Y1818248D01*
G01X74803Y1787421D02*
Y1787323D01*
G01Y1789095D02*
Y1788996D01*
G01D02*
Y1787421D01*
G01X70079Y1805295D02*
Y1796949D01*
G01X79527Y1789095D02*
X82677Y1790276D01*
G01X72047Y1829291D02*
G03Y1828110I0J-590D01*
G01X65748D02*
G03Y1829291I0J591D01*
G01X72638Y1812323D02*
G03I-3741J0D01*
G01X65852Y1828291D02*
X65759D01*
G01X72047Y1827815D02*
X73622D01*
G01X70472D02*
X72047D01*
G01X65748D02*
X64173D01*
G01X67323D02*
X65748D01*
G01Y1827520D02*
X72047D01*
G01X78543Y1811536D02*
Y1813110D01*
G01X73622Y1827815D02*
Y1829784D01*
G01X73189Y1813110D02*
Y1811536D01*
G01X72047Y1827520D02*
Y1828110D01*
G01X71850Y1813110D02*
Y1813307D01*
G01Y1811536D02*
Y1811339D01*
G01Y1813110D02*
Y1811536D01*
G01X71653Y1813110D02*
Y1811536D01*
G01X71063Y1827520D02*
Y1832638D01*
G01X70866D02*
Y1827520D01*
G01X70472Y1829784D02*
Y1827815D01*
G01X70079Y1811536D02*
Y1813110D01*
G01X67716Y1811536D02*
Y1813110D01*
G01X67323Y1829784D02*
Y1827815D01*
G01X66929Y1832638D02*
Y1827520D01*
G01X66732D02*
Y1832638D01*
G01X66142Y1811536D02*
Y1813110D01*
G01X65945Y1811536D02*
Y1813110D01*
G01Y1811536D02*
Y1811339D01*
G01Y1813307D02*
Y1813110D01*
G01X65852Y1829040D02*
Y1828291D01*
G01X65759D02*
Y1828912D01*
G01X65748Y1828110D02*
Y1827520D01*
G01X64606Y1811536D02*
Y1813110D01*
G01X64173Y1827815D02*
Y1829784D01*
G01X65748Y1830866D02*
G03Y1832047I0J590D01*
G01X72047D02*
G03Y1830866I0J-591D01*
G01X65748Y1832638D02*
X72047D01*
G01Y1832343D02*
X73622D01*
G01X70472D02*
X72047D01*
G01X65748D02*
X64173D01*
G01X67323D02*
X65748D01*
G01X64173Y1830374D02*
X65748D01*
G01D02*
X67323D01*
G01X73622D02*
X72047D01*
G01D02*
X70472D01*
G01X72047Y1830040D02*
X66496D01*
G01X64173Y1829784D02*
X65748D01*
G01D02*
X67323D01*
G01X73622D02*
X72047D01*
G01D02*
X70472D01*
G01X65759Y1829040D02*
X65852D01*
G01X73622Y1832343D02*
Y1830374D01*
G01X72047Y1832047D02*
Y1832638D01*
G01Y1829291D02*
Y1830866D01*
G01X70472Y1830374D02*
Y1832343D01*
G01X67323Y1830374D02*
Y1832343D01*
G01X65748Y1830866D02*
Y1829291D01*
G01Y1832638D02*
Y1832047D01*
G01X65665Y1828801D02*
Y1828928D01*
G01X64173Y1832343D02*
Y1830374D01*
G01X65759Y1828912D02*
X65665Y1828801D01*
G01Y1828928D02*
X65759Y1829040D01*
G01X82677Y20138D02*
Y7185D01*
G01X94488Y20138D02*
Y187185D01*
G01X90551Y24075D02*
Y37343D01*
G01X82677Y20138D02*
X94488D01*
G01X88110Y41949D02*
Y40374D01*
G01Y46949D02*
Y45374D01*
G01Y51949D02*
Y50374D01*
G01X83189D02*
Y51949D01*
G01Y45374D02*
Y46949D01*
G01Y40374D02*
Y41949D01*
G01X82795D02*
Y40374D01*
G01Y46949D02*
Y45374D01*
G01Y51949D02*
Y50374D01*
G01X82677Y39095D02*
Y37343D01*
G01Y44095D02*
Y43228D01*
G01Y49095D02*
Y48228D01*
G01X89567Y56949D02*
Y55374D01*
G01X88110Y61949D02*
Y60374D01*
G01Y66949D02*
Y65374D01*
G01Y71949D02*
Y70374D01*
G01X83189D02*
Y71949D01*
G01Y65374D02*
Y66949D01*
G01Y60374D02*
Y61949D01*
G01Y55374D02*
Y56949D01*
G01X82795D02*
Y55374D01*
G01Y61949D02*
Y60374D01*
G01Y66949D02*
Y65374D01*
G01Y71949D02*
Y70374D01*
G01X82677Y54095D02*
Y53228D01*
G01Y59095D02*
Y58228D01*
G01Y64095D02*
Y63228D01*
G01Y69095D02*
Y68228D01*
G01Y74095D02*
Y73228D01*
G01X88110Y76949D02*
Y75374D01*
G01Y81949D02*
Y80374D01*
G01Y86949D02*
Y85374D01*
G01Y91949D02*
Y90374D01*
G01X83189D02*
Y91949D01*
G01Y85374D02*
Y86949D01*
G01Y80374D02*
Y81949D01*
G01Y75374D02*
Y76949D01*
G01X82795D02*
Y75374D01*
G01Y81949D02*
Y80374D01*
G01Y86949D02*
Y85374D01*
G01Y91949D02*
Y90374D01*
G01X82677Y79095D02*
Y78228D01*
G01Y84095D02*
Y83228D01*
G01Y89095D02*
Y88228D01*
G01Y94095D02*
Y93228D01*
G01X85817Y110873D02*
X85918Y110906D01*
G01X85884Y111103D02*
X85784Y111069D01*
G01X85918Y110906D02*
X86052Y111004D01*
G01X85583Y110414D02*
X85817Y110610D01*
G01X85549D02*
X85315Y110414D01*
G01X85951Y111168D02*
X85884Y111103D01*
G01X86052Y111004D02*
X86153Y111135D01*
G01X85985Y111266D02*
X85951Y111168D01*
G01X86153Y111135D02*
X86186Y111299D01*
G01X89567Y96949D02*
Y95374D01*
G01Y111949D02*
Y110374D01*
G01X88110Y101949D02*
Y100374D01*
G01Y106949D02*
Y105374D01*
G01X86890Y110217D02*
Y110374D01*
G01Y111949D02*
Y112087D01*
G01Y110374D02*
Y110414D01*
G01Y111890D02*
Y111949D01*
G01X86186Y111299D02*
Y111890D01*
G01X85985D02*
Y111266D01*
G01X85482D02*
Y111890D01*
G01X85315Y110374D02*
Y110217D01*
G01Y112087D02*
Y111949D01*
G01Y110414D02*
Y110374D01*
G01Y111949D02*
Y111299D01*
G01X83189Y110374D02*
Y111949D01*
G01Y105374D02*
Y106949D01*
G01Y100374D02*
Y101949D01*
G01Y95374D02*
Y96949D01*
G01X82795D02*
Y95374D01*
G01Y101949D02*
Y100374D01*
G01Y106949D02*
Y105374D01*
G01Y111949D02*
Y110374D01*
G01X82677Y99095D02*
Y98228D01*
G01Y104095D02*
Y103228D01*
G01Y109095D02*
Y108228D01*
G01X85315Y111299D02*
X85348Y111135D01*
G01X85516Y111168D02*
X85482Y111266D01*
G01X85348Y111135D02*
X85449Y111004D01*
G01X86890Y112087D02*
X85315D01*
G01X85482Y111890D02*
X85985D01*
G01X86186D02*
X86890D01*
G01X85784Y111069D02*
X85683D01*
G01Y110873D02*
X85817D01*
G01Y110610D02*
X85549D01*
G01X86890Y110414D02*
X85583D01*
G01X85315Y110217D02*
X86890D01*
G01X85583Y111103D02*
X85516Y111168D01*
G01X85449Y111004D02*
X85583Y110906D01*
G01X85683Y111069D02*
X85583Y111103D01*
G01Y110906D02*
X85683Y110873D01*
G01X88110Y136949D02*
Y135374D01*
G01X83189D02*
Y136949D01*
G01X82795D02*
Y135374D01*
G01X88110Y141949D02*
Y140374D01*
G01Y146949D02*
Y145374D01*
G01Y151949D02*
Y150374D01*
G01Y156949D02*
Y155374D01*
G01X83189D02*
Y156949D01*
G01Y150374D02*
Y151949D01*
G01Y145374D02*
Y146949D01*
G01Y140374D02*
Y141949D01*
G01X82795D02*
Y140374D01*
G01Y146949D02*
Y145374D01*
G01Y151949D02*
Y150374D01*
G01Y156949D02*
Y155374D01*
G01X82677Y139095D02*
Y138228D01*
G01Y144095D02*
Y143228D01*
G01Y149095D02*
Y148228D01*
G01Y154095D02*
Y153228D01*
G01X85756Y166831D02*
X85656Y166798D01*
G01X86694Y165978D02*
X86560Y165912D01*
G01X86527Y166109D02*
X86627Y166175D01*
G01X85622Y165453D02*
X85857Y165650D01*
G01X85589D02*
X85354Y165453D01*
G01X86829Y166109D02*
X86694Y165978D01*
G01X85542Y166949D02*
X85589Y166995D01*
G01X85455Y166864D02*
X85542Y166949D01*
G01X86627Y166175D02*
X86694Y166273D01*
G01X85656Y166798D02*
X85589Y166699D01*
G01X86895Y166240D02*
X86829Y166109D01*
G01X85388Y166732D02*
X85455Y166864D01*
G01X85589Y166699D02*
X85555Y166601D01*
G01X86694Y166273D02*
X86728Y166404D01*
G01X85354Y166601D02*
X85388Y166732D01*
G01X86929Y166404D02*
X86895Y166240D01*
G01X90551Y169980D02*
Y183248D01*
G01X88110Y161949D02*
Y160374D01*
G01Y166949D02*
Y165374D01*
G01X86929Y165256D02*
Y165374D01*
G01D02*
Y165453D01*
G01Y166667D02*
Y166404D01*
G01X86728D02*
Y166667D01*
G01X86493Y166949D02*
Y167126D01*
G01Y166929D02*
Y166949D01*
G01X86225Y166601D02*
Y166404D01*
G01X86024D02*
Y166601D01*
G01X85723Y166207D02*
Y166010D01*
G01X85555Y166601D02*
Y166404D01*
G01X85354Y166437D02*
Y166601D01*
G01Y165374D02*
Y165256D01*
G01Y165453D02*
Y165374D01*
G01X83189D02*
Y166949D01*
G01Y160374D02*
Y161949D01*
G01X82795D02*
Y160374D01*
G01Y166949D02*
Y165374D01*
G01X82677Y159095D02*
Y158228D01*
G01Y164095D02*
Y163228D01*
G01Y169980D02*
Y168228D01*
G01X86895Y166831D02*
X86929Y166667D01*
G01X86058Y166240D02*
X86024Y166404D01*
G01X85388Y166273D02*
X85354Y166437D01*
G01X86728Y166667D02*
X86694Y166798D01*
G01X86192Y166732D02*
X86225Y166601D01*
G01Y166404D02*
X86259Y166273D01*
G01X86024Y166601D02*
X85991Y166699D01*
G01X85555Y166404D02*
X85589Y166306D01*
G01Y166995D02*
X85723Y167028D01*
G01X86125Y166864D02*
X86192Y166732D01*
G01X86125Y166109D02*
X86058Y166240D01*
G01X86795Y166995D02*
X86823Y166949D01*
G01D02*
X86895Y166831D01*
G01X85991Y166699D02*
X85924Y166798D01*
G01X86259Y166273D02*
X86326Y166175D01*
G01X85488Y166142D02*
X85388Y166273D01*
G01X86694Y166798D02*
X86594Y166896D01*
G01X85991Y166995D02*
X86038Y166949D01*
G01D02*
X86125Y166864D01*
G01X86259Y165978D02*
X86125Y166109D01*
G01X85589Y166306D02*
X85656Y166240D01*
G01X85723Y167028D02*
X85857D01*
G01X85823Y166831D02*
X85756D01*
G01X86427Y166109D02*
X86527D01*
G01X86560Y165912D02*
X86393D01*
G01X85857Y165650D02*
X85589D01*
G01X86929Y165453D02*
X85622D01*
G01X85354Y165256D02*
X86929D01*
G01X85622Y166043D02*
X85488Y166142D01*
G01X86326Y166175D02*
X86427Y166109D01*
G01X86627Y167093D02*
X86795Y166995D01*
G01X86393Y165912D02*
X86259Y165978D01*
G01X85656Y166240D02*
X85723Y166207D01*
G01X86594Y166896D02*
X86493Y166929D01*
G01X85924Y166798D02*
X85823Y166831D01*
G01X85723Y166010D02*
X85622Y166043D01*
G01X86493Y167126D02*
X86627Y167093D01*
G01X85857Y167028D02*
X85991Y166995D01*
G01X82677Y200138D02*
Y187185D01*
G01X94488D02*
X82677D01*
G01X94488Y425650D02*
Y592697D01*
G01X90551Y429587D02*
Y442854D01*
G01X82677Y425650D02*
Y412697D01*
G01Y425650D02*
X94488D01*
G01X88110Y447461D02*
Y445886D01*
G01Y452461D02*
Y450886D01*
G01X83189D02*
Y452461D01*
G01Y445886D02*
Y447461D01*
G01X82795D02*
Y445886D01*
G01Y452461D02*
Y450886D01*
G01X82677Y444606D02*
Y442854D01*
G01Y449606D02*
Y448740D01*
G01Y454606D02*
Y453740D01*
G01X89567Y462461D02*
Y460886D01*
G01X88110Y457461D02*
Y455886D01*
G01Y467461D02*
Y465886D01*
G01Y472461D02*
Y470886D01*
G01X83189D02*
Y472461D01*
G01Y465886D02*
Y467461D01*
G01Y460886D02*
Y462461D01*
G01Y455886D02*
Y457461D01*
G01X82795D02*
Y455886D01*
G01Y462461D02*
Y460886D01*
G01Y467461D02*
Y465886D01*
G01Y472461D02*
Y470886D01*
G01X82677Y459606D02*
Y458740D01*
G01Y464606D02*
Y463740D01*
G01Y469606D02*
Y468740D01*
G01Y474606D02*
Y473740D01*
G01X88110Y477461D02*
Y475886D01*
G01Y482461D02*
Y480886D01*
G01Y487461D02*
Y485886D01*
G01Y492461D02*
Y490886D01*
G01Y497461D02*
Y495886D01*
G01X83189D02*
Y497461D01*
G01Y490886D02*
Y492461D01*
G01Y485886D02*
Y487461D01*
G01Y480886D02*
Y482461D01*
G01Y475886D02*
Y477461D01*
G01X82795D02*
Y475886D01*
G01Y482461D02*
Y480886D01*
G01Y487461D02*
Y485886D01*
G01Y492461D02*
Y490886D01*
G01Y497461D02*
Y495886D01*
G01X82677Y479606D02*
Y478740D01*
G01Y484606D02*
Y483740D01*
G01Y489606D02*
Y488740D01*
G01Y494606D02*
Y493740D01*
G01X85817Y516384D02*
X85918Y516417D01*
G01X85884Y516614D02*
X85784Y516581D01*
G01X85918Y516417D02*
X86052Y516516D01*
G01X85583Y515925D02*
X85817Y516122D01*
G01X85549D02*
X85315Y515925D01*
G01X85951Y516680D02*
X85884Y516614D01*
G01X86052Y516516D02*
X86153Y516647D01*
G01X85985Y516778D02*
X85951Y516680D01*
G01X86153Y516647D02*
X86186Y516811D01*
G01X89567Y502461D02*
Y500886D01*
G01Y517461D02*
Y515886D01*
G01X88110Y507461D02*
Y505886D01*
G01Y512461D02*
Y510886D01*
G01X86890Y517402D02*
Y517461D01*
G01Y515728D02*
Y515886D01*
G01D02*
Y515925D01*
G01X86186Y516811D02*
Y517402D01*
G01X85985D02*
Y516778D01*
G01X85482D02*
Y517402D01*
G01X85315Y515886D02*
Y515728D01*
G01Y515925D02*
Y515886D01*
G01Y517461D02*
Y516811D01*
G01X83189Y515886D02*
Y517461D01*
G01Y510886D02*
Y512461D01*
G01Y505886D02*
Y507461D01*
G01Y500886D02*
Y502461D01*
G01X82795D02*
Y500886D01*
G01Y507461D02*
Y505886D01*
G01Y512461D02*
Y510886D01*
G01Y517461D02*
Y515886D01*
G01X82677Y499606D02*
Y498740D01*
G01Y504606D02*
Y503740D01*
G01Y509606D02*
Y508740D01*
G01Y514606D02*
Y513740D01*
G01X85315Y516811D02*
X85348Y516647D01*
G01X85482Y517402D02*
X85985D01*
G01X86186D02*
X86890D01*
G01X85784Y516581D02*
X85683D01*
G01Y516384D02*
X85817D01*
G01Y516122D02*
X85549D01*
G01X86890Y515925D02*
X85583D01*
G01X85315Y515728D02*
X86890D01*
G01X85516Y516680D02*
X85482Y516778D01*
G01X85683Y516581D02*
X85583Y516614D01*
G01Y516417D02*
X85683Y516384D01*
G01X85348Y516647D02*
X85449Y516516D01*
G01X85583Y516614D02*
X85516Y516680D01*
G01X85449Y516516D02*
X85583Y516417D01*
G01X86890Y517461D02*
Y517599D01*
G01X85315D02*
Y517461D01*
G01X86890Y517599D02*
X85315D01*
G01X88110Y542461D02*
Y540886D01*
G01Y547461D02*
Y545886D01*
G01Y552461D02*
Y550886D01*
G01Y557461D02*
Y555886D01*
G01X83189D02*
Y557461D01*
G01Y550886D02*
Y552461D01*
G01Y545886D02*
Y547461D01*
G01Y540886D02*
Y542461D01*
G01X82795D02*
Y540886D01*
G01Y547461D02*
Y545886D01*
G01Y552461D02*
Y550886D01*
G01Y557461D02*
Y555886D01*
G01X82677Y544606D02*
Y543740D01*
G01Y549606D02*
Y548740D01*
G01Y554606D02*
Y553740D01*
G01Y559606D02*
Y558740D01*
G01X85756Y572343D02*
X85656Y572310D01*
G01X86694Y571490D02*
X86560Y571424D01*
G01X86527Y571621D02*
X86627Y571686D01*
G01X85622Y570965D02*
X85857Y571162D01*
G01X85589D02*
X85354Y570965D01*
G01X86829Y571621D02*
X86694Y571490D01*
G01X85542Y572461D02*
X85589Y572506D01*
G01X85455Y572375D02*
X85542Y572461D01*
G01X86627Y571686D02*
X86694Y571785D01*
G01X85656Y572310D02*
X85589Y572211D01*
G01X86895Y571752D02*
X86829Y571621D01*
G01X85388Y572244D02*
X85455Y572375D01*
G01X85589Y572211D02*
X85555Y572113D01*
G01X85589Y572506D02*
X85723Y572540D01*
G01X86694Y571785D02*
X86728Y571916D01*
G01X85354Y572113D02*
X85388Y572244D01*
G01X86929Y571916D02*
X86895Y571752D01*
G01X85723Y572540D02*
X85857D01*
G01X85823Y572343D02*
X85756D01*
G01X86427Y571621D02*
X86527D01*
G01X86560Y571424D02*
X86393D01*
G01X85857Y571162D02*
X85589D01*
G01X86929Y570965D02*
X85622D01*
G01X85354Y570768D02*
X86929D01*
G01X90551Y575492D02*
Y588760D01*
G01X88110Y562461D02*
Y560886D01*
G01Y567461D02*
Y565886D01*
G01Y572461D02*
Y570886D01*
G01X86929Y570768D02*
Y570886D01*
G01D02*
Y570965D01*
G01Y572178D02*
Y571916D01*
G01X86728D02*
Y572178D01*
G01X86493Y572461D02*
Y572638D01*
G01Y572441D02*
Y572461D01*
G01X86225Y572113D02*
Y571916D01*
G01X86024D02*
Y572113D01*
G01X85723Y571719D02*
Y571522D01*
G01X85555Y572113D02*
Y571916D01*
G01X85354Y571949D02*
Y572113D01*
G01Y570886D02*
Y570768D01*
G01Y570965D02*
Y570886D01*
G01X83189D02*
Y572461D01*
G01Y565886D02*
Y567461D01*
G01Y560886D02*
Y562461D01*
G01X82795D02*
Y560886D01*
G01Y567461D02*
Y565886D01*
G01Y572461D02*
Y570886D01*
G01X82677Y564606D02*
Y563740D01*
G01Y569606D02*
Y568740D01*
G01Y575492D02*
Y573740D01*
G01X86895Y572343D02*
X86929Y572178D01*
G01X86058Y571752D02*
X86024Y571916D01*
G01X85388Y571785D02*
X85354Y571949D01*
G01X86493Y572638D02*
X86627Y572605D01*
G01X85857Y572540D02*
X85991Y572506D01*
G01X86728Y572178D02*
X86694Y572310D01*
G01X86192Y572244D02*
X86225Y572113D01*
G01Y571916D02*
X86259Y571785D01*
G01X86024Y572113D02*
X85991Y572211D01*
G01X85555Y571916D02*
X85589Y571817D01*
G01X86125Y572375D02*
X86192Y572244D01*
G01X86125Y571621D02*
X86058Y571752D01*
G01X86795Y572506D02*
X86823Y572461D01*
G01D02*
X86895Y572343D01*
G01X85991Y572211D02*
X85924Y572310D01*
G01X86259Y571785D02*
X86326Y571686D01*
G01D02*
X86427Y571621D01*
G01X86627Y572605D02*
X86795Y572506D01*
G01X86393Y571424D02*
X86259Y571490D01*
G01X85656Y571752D02*
X85723Y571719D01*
G01X86594Y572408D02*
X86493Y572441D01*
G01X85924Y572310D02*
X85823Y572343D01*
G01X85723Y571522D02*
X85622Y571555D01*
G01X85488Y571654D02*
X85388Y571785D01*
G01X86694Y572310D02*
X86594Y572408D01*
G01X85991Y572506D02*
X86038Y572461D01*
G01D02*
X86125Y572375D01*
G01X86259Y571490D02*
X86125Y571621D01*
G01X85589Y571817D02*
X85656Y571752D01*
G01X85622Y571555D02*
X85488Y571654D01*
G01X94488Y592697D02*
X82677D01*
G01Y605650D02*
Y592697D01*
G01Y831162D02*
X94488D01*
G01D02*
Y998209D01*
G01X82677Y831162D02*
Y818209D01*
G01X90551Y835099D02*
Y848366D01*
G01X88110Y852973D02*
Y851398D01*
G01X83189D02*
Y852973D01*
G01X82795D02*
Y851398D01*
G01X82677Y850118D02*
Y848366D01*
G01Y855118D02*
Y854252D01*
G01X89567Y867973D02*
Y866398D01*
G01X88110Y857973D02*
Y856398D01*
G01Y862973D02*
Y861398D01*
G01Y872973D02*
Y871398D01*
G01Y877973D02*
Y876398D01*
G01X83189D02*
Y877973D01*
G01Y871398D02*
Y872973D01*
G01Y866398D02*
Y867973D01*
G01Y861398D02*
Y862973D01*
G01Y856398D02*
Y857973D01*
G01X82795D02*
Y856398D01*
G01Y862973D02*
Y861398D01*
G01Y867973D02*
Y866398D01*
G01Y872973D02*
Y871398D01*
G01Y877973D02*
Y876398D01*
G01X82677Y860118D02*
Y859252D01*
G01Y865118D02*
Y864252D01*
G01Y870118D02*
Y869252D01*
G01Y875118D02*
Y874252D01*
G01X88110Y882973D02*
Y881398D01*
G01Y887973D02*
Y886398D01*
G01Y892973D02*
Y891398D01*
G01Y897973D02*
Y896398D01*
G01X83189D02*
Y897973D01*
G01Y891398D02*
Y892973D01*
G01Y886398D02*
Y887973D01*
G01Y881398D02*
Y882973D01*
G01X82795D02*
Y881398D01*
G01Y887973D02*
Y886398D01*
G01Y892973D02*
Y891398D01*
G01Y897973D02*
Y896398D01*
G01X82677Y880118D02*
Y879252D01*
G01Y885118D02*
Y884252D01*
G01Y890118D02*
Y889252D01*
G01Y895118D02*
Y894252D01*
G01X89567Y907973D02*
Y906398D01*
G01X88110Y902973D02*
Y901398D01*
G01Y912973D02*
Y911398D01*
G01Y917973D02*
Y916398D01*
G01X83189D02*
Y917973D01*
G01Y911398D02*
Y912973D01*
G01Y906398D02*
Y907973D01*
G01Y901398D02*
Y902973D01*
G01X82795D02*
Y901398D01*
G01Y907973D02*
Y906398D01*
G01Y912973D02*
Y911398D01*
G01Y917973D02*
Y916398D01*
G01X82677Y900118D02*
Y899252D01*
G01Y905118D02*
Y904252D01*
G01Y910118D02*
Y909252D01*
G01Y915118D02*
Y914252D01*
G01Y920118D02*
Y919252D01*
G01X85817Y921896D02*
X85918Y921929D01*
G01X85884Y922126D02*
X85784Y922093D01*
G01X86890Y923110D02*
X85315D01*
G01X85482Y922914D02*
X85985D01*
G01X86186D02*
X86890D01*
G01X85784Y922093D02*
X85683D01*
G01Y921896D02*
X85817D01*
G01Y921634D02*
X85549D01*
G01X86890Y921437D02*
X85583D01*
G01X85315Y921240D02*
X86890D01*
G01X85683Y922093D02*
X85583Y922126D01*
G01Y921929D02*
X85683Y921896D01*
G01X85918Y921929D02*
X86052Y922028D01*
G01X85583Y921437D02*
X85817Y921634D01*
G01X85549D02*
X85315Y921437D01*
G01X85951Y922191D02*
X85884Y922126D01*
G01X85583D02*
X85516Y922191D01*
G01X85449Y922028D02*
X85583Y921929D01*
G01X86052Y922028D02*
X86153Y922159D01*
G01X85315Y922323D02*
X85348Y922159D01*
G01X85516Y922191D02*
X85482Y922290D01*
G01X85348Y922159D02*
X85449Y922028D01*
G01X85985Y922290D02*
X85951Y922191D01*
G01X86153Y922159D02*
X86186Y922323D01*
G01X89567Y922973D02*
Y921398D01*
G01X86890Y921240D02*
Y921398D01*
G01Y922973D02*
Y923110D01*
G01Y921398D02*
Y921437D01*
G01Y922914D02*
Y922973D01*
G01X86186Y922323D02*
Y922914D01*
G01X85985D02*
Y922290D01*
G01X85482D02*
Y922914D01*
G01X85315Y921398D02*
Y921240D01*
G01Y923110D02*
Y922973D01*
G01Y921437D02*
Y921398D01*
G01Y922973D02*
Y922323D01*
G01X83189Y921398D02*
Y922973D01*
G01X82795D02*
Y921398D01*
G01X88110Y947973D02*
Y946398D01*
G01Y952973D02*
Y951398D01*
G01Y957973D02*
Y956398D01*
G01Y962973D02*
Y961398D01*
G01X83189D02*
Y962973D01*
G01Y956398D02*
Y957973D01*
G01Y951398D02*
Y952973D01*
G01Y946398D02*
Y947973D01*
G01X82795D02*
Y946398D01*
G01Y952973D02*
Y951398D01*
G01Y957973D02*
Y956398D01*
G01Y962973D02*
Y961398D01*
G01X82677Y950118D02*
Y949252D01*
G01Y955118D02*
Y954252D01*
G01Y960118D02*
Y959252D01*
G01X85589Y978018D02*
X85723Y978051D01*
G01D02*
X85857D01*
G01X85823Y977854D02*
X85756D01*
G01X86427Y977132D02*
X86527D01*
G01X86560Y976936D02*
X86393D01*
G01X85857Y976673D02*
X85589D01*
G01X86929Y976477D02*
X85622D01*
G01X85354Y976280D02*
X86929D01*
G01X86493Y978150D02*
X86627Y978117D01*
G01X85857Y978051D02*
X85991Y978018D01*
G01X85756Y977854D02*
X85656Y977821D01*
G01X86393Y976936D02*
X86259Y977001D01*
G01X85656Y977264D02*
X85723Y977231D01*
G01X86594Y977920D02*
X86493Y977953D01*
G01X85924Y977821D02*
X85823Y977854D01*
G01X85723Y977034D02*
X85622Y977067D01*
G01X86694Y977001D02*
X86560Y976936D01*
G01X85622Y977067D02*
X85488Y977166D01*
G01X86326Y977198D02*
X86427Y977132D01*
G01X86627Y978117D02*
X86795Y978018D01*
G01X86527Y977132D02*
X86627Y977198D01*
G01X85622Y976477D02*
X85857Y976673D01*
G01X85589D02*
X85354Y976477D01*
G01X86829Y977132D02*
X86694Y977001D01*
G01X85542Y977973D02*
X85589Y978018D01*
G01X85455Y977887D02*
X85542Y977973D01*
G01X85991Y977723D02*
X85924Y977821D01*
G01X86259Y977297D02*
X86326Y977198D01*
G01X85488Y977166D02*
X85388Y977297D01*
G01X86694Y977821D02*
X86594Y977920D01*
G01X85991Y978018D02*
X86038Y977973D01*
G01D02*
X86125Y977887D01*
G01X86259Y977001D02*
X86125Y977132D01*
G01X85589Y977329D02*
X85656Y977264D01*
G01X86627Y977198D02*
X86694Y977297D01*
G01X85656Y977821D02*
X85589Y977723D01*
G01X86895Y977854D02*
X86929Y977690D01*
G01X86058Y977264D02*
X86024Y977428D01*
G01X85388Y977297D02*
X85354Y977461D01*
G01X86728Y977690D02*
X86694Y977821D01*
G01X86192Y977756D02*
X86225Y977625D01*
G01Y977428D02*
X86259Y977297D01*
G01X86024Y977625D02*
X85991Y977723D01*
G01X85555Y977428D02*
X85589Y977329D01*
G01X86125Y977887D02*
X86192Y977756D01*
G01X86125Y977132D02*
X86058Y977264D01*
G01X86795Y978018D02*
X86823Y977973D01*
G01D02*
X86895Y977854D01*
G01Y977264D02*
X86829Y977132D01*
G01X85388Y977756D02*
X85455Y977887D01*
G01X85589Y977723D02*
X85555Y977625D01*
G01X86694Y977297D02*
X86728Y977428D01*
G01X85354Y977625D02*
X85388Y977756D01*
G01X86929Y977428D02*
X86895Y977264D01*
G01X90551Y981004D02*
Y994272D01*
G01X88110Y967973D02*
Y966398D01*
G01Y972973D02*
Y971398D01*
G01Y977973D02*
Y976398D01*
G01X86929Y976280D02*
Y976398D01*
G01D02*
Y976477D01*
G01Y977690D02*
Y977428D01*
G01X86728D02*
Y977690D01*
G01X86493Y977973D02*
Y978150D01*
G01Y977953D02*
Y977973D01*
G01X86225Y977625D02*
Y977428D01*
G01X86024D02*
Y977625D01*
G01X85723Y977231D02*
Y977034D01*
G01X85555Y977625D02*
Y977428D01*
G01X85354Y977461D02*
Y977625D01*
G01Y976398D02*
Y976280D01*
G01Y976477D02*
Y976398D01*
G01X83189D02*
Y977973D01*
G01Y971398D02*
Y972973D01*
G01Y966398D02*
Y967973D01*
G01X82795D02*
Y966398D01*
G01Y972973D02*
Y971398D01*
G01Y977973D02*
Y976398D01*
G01X82677Y965118D02*
Y964252D01*
G01Y970118D02*
Y969252D01*
G01Y975118D02*
Y974252D01*
G01Y981004D02*
Y979252D01*
G01X94488Y998209D02*
X82677D01*
G01Y1011162D02*
Y998209D01*
G01Y1236673D02*
Y1223721D01*
G01Y1236673D02*
X94488D01*
G01D02*
Y1403721D01*
G01X90551Y1240610D02*
Y1253878D01*
G01X88110Y1258484D02*
Y1256910D01*
G01X83189D02*
Y1258484D01*
G01X82795D02*
Y1256910D01*
G01X82677Y1255630D02*
Y1253878D01*
G01X89567Y1273484D02*
Y1271910D01*
G01X88110Y1263484D02*
Y1261910D01*
G01Y1268484D02*
Y1266910D01*
G01Y1278484D02*
Y1276910D01*
G01X83189D02*
Y1278484D01*
G01Y1271910D02*
Y1273484D01*
G01Y1266910D02*
Y1268484D01*
G01Y1261910D02*
Y1263484D01*
G01X82795D02*
Y1261910D01*
G01Y1268484D02*
Y1266910D01*
G01Y1273484D02*
Y1271910D01*
G01Y1278484D02*
Y1276910D01*
G01X82677Y1260630D02*
Y1259764D01*
G01Y1265630D02*
Y1264764D01*
G01Y1270630D02*
Y1269764D01*
G01Y1275630D02*
Y1274764D01*
G01X88110Y1283484D02*
Y1281910D01*
G01Y1288484D02*
Y1286910D01*
G01Y1293484D02*
Y1291910D01*
G01Y1298484D02*
Y1296910D01*
G01X83189D02*
Y1298484D01*
G01Y1291910D02*
Y1293484D01*
G01Y1286910D02*
Y1288484D01*
G01Y1281910D02*
Y1283484D01*
G01X82795D02*
Y1281910D01*
G01Y1288484D02*
Y1286910D01*
G01Y1293484D02*
Y1291910D01*
G01Y1298484D02*
Y1296910D01*
G01X82677Y1280630D02*
Y1279764D01*
G01Y1285630D02*
Y1284764D01*
G01Y1290630D02*
Y1289764D01*
G01Y1295630D02*
Y1294764D01*
G01Y1300630D02*
Y1299764D01*
G01X89567Y1313484D02*
Y1311910D01*
G01X88110Y1303484D02*
Y1301910D01*
G01Y1308484D02*
Y1306910D01*
G01Y1318484D02*
Y1316910D01*
G01X83189D02*
Y1318484D01*
G01Y1311910D02*
Y1313484D01*
G01Y1306910D02*
Y1308484D01*
G01Y1301910D02*
Y1303484D01*
G01X82795D02*
Y1301910D01*
G01Y1308484D02*
Y1306910D01*
G01Y1313484D02*
Y1311910D01*
G01Y1318484D02*
Y1316910D01*
G01X82677Y1305630D02*
Y1304764D01*
G01Y1310630D02*
Y1309764D01*
G01Y1315630D02*
Y1314764D01*
G01Y1320630D02*
Y1319764D01*
G01X86890Y1328622D02*
X85315D01*
G01X85482Y1328425D02*
X85985D01*
G01X86186D02*
X86890D01*
G01X85784Y1327605D02*
X85683D01*
G01Y1327408D02*
X85817D01*
G01Y1327146D02*
X85549D01*
G01X86890Y1326949D02*
X85583D01*
G01X85315Y1326752D02*
X86890D01*
G01X85683Y1327605D02*
X85583Y1327638D01*
G01Y1327441D02*
X85683Y1327408D01*
G01X85449Y1327540D02*
X85583Y1327441D01*
G01Y1327638D02*
X85516Y1327703D01*
G01X85348Y1327671D02*
X85449Y1327540D01*
G01X85315Y1327835D02*
X85348Y1327671D01*
G01X85516Y1327703D02*
X85482Y1327802D01*
G01X89567Y1328484D02*
Y1326910D01*
G01X88110Y1323484D02*
Y1321910D01*
G01X86890Y1326752D02*
Y1326910D01*
G01Y1328484D02*
Y1328622D01*
G01Y1326910D02*
Y1326949D01*
G01Y1328425D02*
Y1328484D01*
G01X86186Y1327835D02*
Y1328425D01*
G01X85985D02*
Y1327802D01*
G01X85482D02*
Y1328425D01*
G01X85315Y1326910D02*
Y1326752D01*
G01Y1328622D02*
Y1328484D01*
G01Y1326949D02*
Y1326910D01*
G01Y1328484D02*
Y1327835D01*
G01X83189Y1326910D02*
Y1328484D01*
G01Y1321910D02*
Y1323484D01*
G01X82795D02*
Y1321910D01*
G01Y1328484D02*
Y1326910D01*
G01X82677Y1325630D02*
Y1324764D01*
G01X85817Y1327408D02*
X85918Y1327441D01*
G01X85884Y1327638D02*
X85784Y1327605D01*
G01X85985Y1327802D02*
X85951Y1327703D01*
G01X86153Y1327671D02*
X86186Y1327835D01*
G01X85918Y1327441D02*
X86052Y1327540D01*
G01X85583Y1326949D02*
X85817Y1327146D01*
G01X85549D02*
X85315Y1326949D01*
G01X85951Y1327703D02*
X85884Y1327638D01*
G01X86052Y1327540D02*
X86153Y1327671D01*
G01X88110Y1353484D02*
Y1351910D01*
G01Y1358484D02*
Y1356910D01*
G01Y1363484D02*
Y1361910D01*
G01X83189D02*
Y1363484D01*
G01Y1356910D02*
Y1358484D01*
G01Y1351910D02*
Y1353484D01*
G01X82795D02*
Y1351910D01*
G01Y1358484D02*
Y1356910D01*
G01Y1363484D02*
Y1361910D01*
G01X82677Y1355630D02*
Y1354764D01*
G01Y1360630D02*
Y1359764D01*
G01X85589Y1383530D02*
X85723Y1383563D01*
G01D02*
X85857D01*
G01X85823Y1383366D02*
X85756D01*
G01X86427Y1382644D02*
X86527D01*
G01X86560Y1382447D02*
X86393D01*
G01X85857Y1382185D02*
X85589D01*
G01X86929Y1381988D02*
X85622D01*
G01X85354Y1381791D02*
X86929D01*
G01X86493Y1383662D02*
X86627Y1383628D01*
G01X85857Y1383563D02*
X85991Y1383530D01*
G01X86594Y1383432D02*
X86493Y1383465D01*
G01X85924Y1383333D02*
X85823Y1383366D01*
G01X85723Y1382546D02*
X85622Y1382579D01*
G01X86326Y1382710D02*
X86427Y1382644D01*
G01X86627Y1383628D02*
X86795Y1383530D01*
G01X86393Y1382447D02*
X86259Y1382513D01*
G01X85656Y1382776D02*
X85723Y1382743D01*
G01X85622Y1382579D02*
X85488Y1382677D01*
G01X86694Y1383333D02*
X86594Y1383432D01*
G01X85991Y1383530D02*
X86038Y1383484D01*
G01D02*
X86125Y1383399D01*
G01X86259Y1382513D02*
X86125Y1382644D01*
G01X85589Y1382841D02*
X85656Y1382776D01*
G01X85991Y1383235D02*
X85924Y1383333D01*
G01X86259Y1382808D02*
X86326Y1382710D01*
G01X85488Y1382677D02*
X85388Y1382808D01*
G01X86125Y1383399D02*
X86192Y1383268D01*
G01X86125Y1382644D02*
X86058Y1382776D01*
G01X86795Y1383530D02*
X86823Y1383484D01*
G01D02*
X86895Y1383366D01*
G01X86024Y1383136D02*
X85991Y1383235D01*
G01X85555Y1382940D02*
X85589Y1382841D01*
G01X86895Y1383366D02*
X86929Y1383202D01*
G01X86058Y1382776D02*
X86024Y1382940D01*
G01X85388Y1382808D02*
X85354Y1382973D01*
G01X86728Y1383202D02*
X86694Y1383333D01*
G01X86192Y1383268D02*
X86225Y1383136D01*
G01Y1382940D02*
X86259Y1382808D01*
G01X88110Y1368484D02*
Y1366910D01*
G01Y1373484D02*
Y1371910D01*
G01Y1378484D02*
Y1376910D01*
G01Y1383484D02*
Y1381910D01*
G01X86929Y1381791D02*
Y1381910D01*
G01D02*
Y1381988D01*
G01Y1383202D02*
Y1382940D01*
G01X86728D02*
Y1383202D01*
G01X86493Y1383484D02*
Y1383662D01*
G01Y1383465D02*
Y1383484D01*
G01X86225Y1383136D02*
Y1382940D01*
G01X86024D02*
Y1383136D01*
G01X85723Y1382743D02*
Y1382546D01*
G01X85555Y1383136D02*
Y1382940D01*
G01X85354Y1382973D02*
Y1383136D01*
G01Y1381910D02*
Y1381791D01*
G01Y1381988D02*
Y1381910D01*
G01X83189D02*
Y1383484D01*
G01Y1376910D02*
Y1378484D01*
G01Y1371910D02*
Y1373484D01*
G01Y1366910D02*
Y1368484D01*
G01X82795D02*
Y1366910D01*
G01Y1373484D02*
Y1371910D01*
G01Y1378484D02*
Y1376910D01*
G01Y1383484D02*
Y1381910D01*
G01X82677Y1365630D02*
Y1364764D01*
G01Y1370630D02*
Y1369764D01*
G01Y1375630D02*
Y1374764D01*
G01Y1380630D02*
Y1379764D01*
G01X85756Y1383366D02*
X85656Y1383333D01*
G01X86694Y1382808D02*
X86728Y1382940D01*
G01X85354Y1383136D02*
X85388Y1383268D01*
G01X86929Y1382940D02*
X86895Y1382776D01*
G01X86694Y1382513D02*
X86560Y1382447D01*
G01X86527Y1382644D02*
X86627Y1382710D01*
G01X85622Y1381988D02*
X85857Y1382185D01*
G01X85589D02*
X85354Y1381988D01*
G01X86829Y1382644D02*
X86694Y1382513D01*
G01X85542Y1383484D02*
X85589Y1383530D01*
G01X85455Y1383399D02*
X85542Y1383484D01*
G01X86627Y1382710D02*
X86694Y1382808D01*
G01X85656Y1383333D02*
X85589Y1383235D01*
G01X86895Y1382776D02*
X86829Y1382644D01*
G01X85388Y1383268D02*
X85455Y1383399D01*
G01X85589Y1383235D02*
X85555Y1383136D01*
G01X94488Y1403721D02*
X82677D01*
G01X90551Y1386516D02*
Y1399784D01*
G01X82677Y1386516D02*
Y1384764D01*
G01Y1416673D02*
Y1403721D01*
G01X122244Y1479784D02*
X102165D01*
G01Y1506358D02*
Y1479784D01*
G01X122244Y1506358D02*
X102165D01*
G01X82677Y1642185D02*
Y1629232D01*
G01Y1642185D02*
X94488D01*
G01D02*
Y1809232D01*
G01X90551Y1646122D02*
Y1659390D01*
G01X82677Y1661142D02*
Y1659390D01*
G01X89567Y1678996D02*
Y1677421D01*
G01X88110Y1663996D02*
Y1662421D01*
G01Y1668996D02*
Y1667421D01*
G01Y1673996D02*
Y1672421D01*
G01X83189Y1677421D02*
Y1678996D01*
G01Y1672421D02*
Y1673996D01*
G01Y1667421D02*
Y1668996D01*
G01Y1662421D02*
Y1663996D01*
G01X82795D02*
Y1662421D01*
G01Y1668996D02*
Y1667421D01*
G01Y1673996D02*
Y1672421D01*
G01Y1678996D02*
Y1677421D01*
G01X82677Y1666142D02*
Y1665276D01*
G01Y1671142D02*
Y1670276D01*
G01Y1676142D02*
Y1675276D01*
G01Y1681142D02*
Y1680276D01*
G01X88110Y1683996D02*
Y1682421D01*
G01Y1688996D02*
Y1687421D01*
G01Y1693996D02*
Y1692421D01*
G01Y1698996D02*
Y1697421D01*
G01X83189D02*
Y1698996D01*
G01Y1692421D02*
Y1693996D01*
G01Y1687421D02*
Y1688996D01*
G01Y1682421D02*
Y1683996D01*
G01X82795D02*
Y1682421D01*
G01Y1688996D02*
Y1687421D01*
G01Y1693996D02*
Y1692421D01*
G01Y1698996D02*
Y1697421D01*
G01X82677Y1686142D02*
Y1685276D01*
G01Y1691142D02*
Y1690276D01*
G01Y1696142D02*
Y1695276D01*
G01Y1701142D02*
Y1700276D01*
G01X89567Y1718996D02*
Y1717421D01*
G01X88110Y1703996D02*
Y1702421D01*
G01Y1708996D02*
Y1707421D01*
G01Y1713996D02*
Y1712421D01*
G01Y1723996D02*
Y1722421D01*
G01X83189D02*
Y1723996D01*
G01Y1717421D02*
Y1718996D01*
G01Y1712421D02*
Y1713996D01*
G01Y1707421D02*
Y1708996D01*
G01Y1702421D02*
Y1703996D01*
G01X82795D02*
Y1702421D01*
G01Y1708996D02*
Y1707421D01*
G01Y1713996D02*
Y1712421D01*
G01Y1718996D02*
Y1717421D01*
G01Y1723996D02*
Y1722421D01*
G01X82677Y1706142D02*
Y1705276D01*
G01Y1711142D02*
Y1710276D01*
G01Y1716142D02*
Y1715276D01*
G01Y1721142D02*
Y1720276D01*
G01X86890Y1734134D02*
X85315D01*
G01X85482Y1733937D02*
X85985D01*
G01X86186D02*
X86890D01*
G01X85784Y1733117D02*
X85683D01*
G01Y1732920D02*
X85817D01*
G01Y1732658D02*
X85549D01*
G01X86890Y1732461D02*
X85583D01*
G01X85315Y1732264D02*
X86890D01*
G01X85683Y1733117D02*
X85583Y1733150D01*
G01Y1732953D02*
X85683Y1732920D01*
G01X85449Y1733051D02*
X85583Y1732953D01*
G01Y1733150D02*
X85516Y1733215D01*
G01X85348Y1733182D02*
X85449Y1733051D01*
G01X85516Y1733215D02*
X85482Y1733314D01*
G01X85315Y1733347D02*
X85348Y1733182D01*
G01X89567Y1733996D02*
Y1732421D01*
G01X88110Y1728996D02*
Y1727421D01*
G01X86890Y1733996D02*
Y1734134D01*
G01Y1733937D02*
Y1733996D01*
G01Y1732264D02*
Y1732421D01*
G01D02*
Y1732461D01*
G01X86186Y1733347D02*
Y1733937D01*
G01X85985D02*
Y1733314D01*
G01X85482D02*
Y1733937D01*
G01X85315Y1732421D02*
Y1732264D01*
G01Y1732461D02*
Y1732421D01*
G01Y1734134D02*
Y1733996D01*
G01D02*
Y1733347D01*
G01X83189Y1732421D02*
Y1733996D01*
G01Y1727421D02*
Y1728996D01*
G01X82795D02*
Y1727421D01*
G01Y1733996D02*
Y1732421D01*
G01X82677Y1726142D02*
Y1725276D01*
G01Y1731142D02*
Y1730276D01*
G01X86153Y1733182D02*
X86186Y1733347D01*
G01X85985Y1733314D02*
X85951Y1733215D01*
G01X86052Y1733051D02*
X86153Y1733182D01*
G01X85817Y1732920D02*
X85918Y1732953D01*
G01X85884Y1733150D02*
X85784Y1733117D01*
G01X85918Y1732953D02*
X86052Y1733051D01*
G01X85583Y1732461D02*
X85817Y1732658D01*
G01X85549D02*
X85315Y1732461D01*
G01X85951Y1733215D02*
X85884Y1733150D01*
G01X88110Y1758996D02*
Y1757421D01*
G01Y1763996D02*
Y1762421D01*
G01X83189D02*
Y1763996D01*
G01Y1757421D02*
Y1758996D01*
G01X82795D02*
Y1757421D01*
G01Y1763996D02*
Y1762421D01*
G01X82677Y1761142D02*
Y1760276D01*
G01Y1766142D02*
Y1765276D01*
G01X88110Y1768996D02*
Y1767421D01*
G01Y1773996D02*
Y1772421D01*
G01Y1778996D02*
Y1777421D01*
G01Y1783996D02*
Y1782421D01*
G01X83189D02*
Y1783996D01*
G01Y1777421D02*
Y1778996D01*
G01Y1772421D02*
Y1773996D01*
G01Y1767421D02*
Y1768996D01*
G01X82795D02*
Y1767421D01*
G01Y1773996D02*
Y1772421D01*
G01Y1778996D02*
Y1777421D01*
G01Y1783996D02*
Y1782421D01*
G01X82677Y1771142D02*
Y1770276D01*
G01Y1776142D02*
Y1775276D01*
G01Y1781142D02*
Y1780276D01*
G01Y1786142D02*
Y1785276D01*
G01X85589Y1789042D02*
X85723Y1789075D01*
G01D02*
X85857D01*
G01X85823Y1788878D02*
X85756D01*
G01X86427Y1788156D02*
X86527D01*
G01X86560Y1787959D02*
X86393D01*
G01X85857Y1787697D02*
X85589D01*
G01X86929Y1787500D02*
X85622D01*
G01X85354Y1787303D02*
X86929D01*
G01X86493Y1789173D02*
X86627Y1789140D01*
G01X85857Y1789075D02*
X85991Y1789042D01*
G01X86594Y1788943D02*
X86493Y1788977D01*
G01X85924Y1788845D02*
X85823Y1788878D01*
G01X85723Y1788058D02*
X85622Y1788091D01*
G01X86393Y1787959D02*
X86259Y1788025D01*
G01X85656Y1788288D02*
X85723Y1788254D01*
G01X86326Y1788222D02*
X86427Y1788156D01*
G01X86627Y1789140D02*
X86795Y1789042D01*
G01X85622Y1788091D02*
X85488Y1788189D01*
G01X86694Y1788845D02*
X86594Y1788943D01*
G01X85991Y1789042D02*
X86038Y1788996D01*
G01D02*
X86125Y1788911D01*
G01X86259Y1788025D02*
X86125Y1788156D01*
G01X85589Y1788353D02*
X85656Y1788288D01*
G01X85991Y1788747D02*
X85924Y1788845D01*
G01X86259Y1788320D02*
X86326Y1788222D01*
G01X85488Y1788189D02*
X85388Y1788320D01*
G01X86795Y1789042D02*
X86823Y1788996D01*
G01D02*
X86895Y1788878D01*
G01X86125Y1788911D02*
X86192Y1788780D01*
G01X86125Y1788156D02*
X86058Y1788288D01*
G01X86024Y1788648D02*
X85991Y1788747D01*
G01X85555Y1788451D02*
X85589Y1788353D01*
G01X86895Y1788878D02*
X86929Y1788714D01*
G01X86058Y1788288D02*
X86024Y1788451D01*
G01X85388Y1788320D02*
X85354Y1788484D01*
G01X86728Y1788714D02*
X86694Y1788845D01*
G01X86192Y1788780D02*
X86225Y1788648D01*
G01Y1788451D02*
X86259Y1788320D01*
G01X90551Y1792028D02*
Y1805295D01*
G01X88110Y1788996D02*
Y1787421D01*
G01X86929Y1787303D02*
Y1787421D01*
G01D02*
Y1787500D01*
G01Y1788714D02*
Y1788451D01*
G01X86728D02*
Y1788714D01*
G01X86493Y1788996D02*
Y1789173D01*
G01Y1788977D02*
Y1788996D01*
G01X86225Y1788648D02*
Y1788451D01*
G01X86024D02*
Y1788648D01*
G01X85723Y1788254D02*
Y1788058D01*
G01X85555Y1788648D02*
Y1788451D01*
G01X85354Y1788484D02*
Y1788648D01*
G01Y1787421D02*
Y1787303D01*
G01Y1787500D02*
Y1787421D01*
G01X83189D02*
Y1788996D01*
G01X82795D02*
Y1787421D01*
G01X82677Y1792028D02*
Y1790276D01*
G01X86929Y1788451D02*
X86895Y1788288D01*
G01X85589Y1788747D02*
X85555Y1788648D01*
G01X86694Y1788320D02*
X86728Y1788451D01*
G01X85354Y1788648D02*
X85388Y1788780D01*
G01X86895Y1788288D02*
X86829Y1788156D01*
G01X85388Y1788780D02*
X85455Y1788911D01*
G01X86627Y1788222D02*
X86694Y1788320D01*
G01X85656Y1788845D02*
X85589Y1788747D01*
G01X85756Y1788878D02*
X85656Y1788845D01*
G01X86694Y1788025D02*
X86560Y1787959D01*
G01X86527Y1788156D02*
X86627Y1788222D01*
G01X85622Y1787500D02*
X85857Y1787697D01*
G01X85589D02*
X85354Y1787500D01*
G01X86829Y1788156D02*
X86694Y1788025D01*
G01X85542Y1788996D02*
X85589Y1789042D01*
G01X85455Y1788911D02*
X85542Y1788996D01*
G01X94488Y1809232D02*
X82677D01*
G01Y1822185D02*
Y1809232D01*
G01X145669Y17717D02*
G03I-15748J0D01*
G01X137795D02*
G03I-7874J0D01*
G01X106102Y1487362D02*
X118307D01*
G01X108858Y1487166D02*
X107874D01*
G01X113976D02*
X112992D01*
G01X111417D02*
X110433D01*
G01X116535D02*
X115551D01*
G01X108858Y1487084D02*
X107874D01*
G01X111417D02*
X110433D01*
G01X113976D02*
X112992D01*
G01X116535D02*
X115551D01*
G01X108858Y1485689D02*
X107874D01*
G01X113976D02*
X112992D01*
G01X111417D02*
X110433D01*
G01X116535D02*
X115551D01*
G01X108858Y1485608D02*
X107874D01*
G01X111417D02*
X110433D01*
G01X113976D02*
X112992D01*
G01X116535D02*
X115551D01*
G01X108858Y1483721D02*
X107874D01*
G01X111417D02*
X110433D01*
G01X113976D02*
X112992D01*
G01X116535D02*
X115551D01*
G01X122244Y1479784D02*
Y1506358D01*
G01X118307Y1487362D02*
Y1498780D01*
G01X116535Y1483721D02*
Y1487362D01*
G01X115551Y1483721D02*
Y1487362D01*
G01X113976Y1483721D02*
Y1487362D01*
G01X112992Y1483721D02*
Y1487362D01*
G01X111417Y1483721D02*
Y1487362D01*
G01X110433Y1483721D02*
Y1487362D01*
G01X108858Y1483721D02*
Y1487362D01*
G01X107874Y1483721D02*
Y1487362D01*
G01X106102Y1498780D02*
Y1487362D01*
G01X116732Y1497008D02*
G03I-590J0D01*
G01X108858Y1502421D02*
X107874D01*
G01X111417D02*
X110433D01*
G01X113976D02*
X112992D01*
G01X116535D02*
X115551D01*
G01X108858Y1500534D02*
X107874D01*
G01X113976D02*
X112992D01*
G01X111417D02*
X110433D01*
G01X116535D02*
X115551D01*
G01X108858Y1500453D02*
X107874D01*
G01X113976D02*
X112992D01*
G01X111417D02*
X110433D01*
G01X116535D02*
X115551D01*
G01X116606Y1500158D02*
X116673D01*
G01X116535Y1500108D02*
X116665D01*
G01X116338D02*
X116535D01*
G01X116732Y1500059D02*
X116535D01*
G01D02*
X116338D01*
G01X108858Y1499058D02*
X107874D01*
G01X113976D02*
X112992D01*
G01X111417D02*
X110433D01*
G01X116535D02*
X115551D01*
G01X108858Y1498977D02*
X107874D01*
G01X113976D02*
X112992D01*
G01X111417D02*
X110433D01*
G01X116535D02*
X115551D01*
G01X118307Y1498780D02*
X106102D01*
G01X116673Y1500158D02*
X116732Y1500108D01*
G01X116665D02*
X116606Y1500158D01*
G01X116732Y1500108D02*
Y1500059D01*
G01X116535Y1498780D02*
Y1502421D01*
G01X116338Y1500059D02*
Y1500108D01*
G01X115551Y1498780D02*
Y1502421D01*
G01X113976Y1498780D02*
Y1502421D01*
G01X112992Y1498780D02*
Y1502421D01*
G01X111417Y1498780D02*
Y1502421D01*
G01X110433Y1498780D02*
Y1502421D01*
G01X108858Y1498780D02*
Y1502421D01*
G01X107874Y1498780D02*
Y1502421D01*
G01X134360Y-63957D02*
X135215Y-65288D01*
X136356Y-66048D01*
X137640Y-66238D01*
X138781Y-66048D01*
X139921Y-65098D01*
X140634Y-63957D01*
X140777Y-62816D01*
X140492Y-61485D01*
X139493Y-60535D01*
X138495Y-60154D01*
X137212D01*
G01X138495D02*
X139351Y-59584D01*
X140064Y-58634D01*
X140349Y-57493D01*
X140064Y-56352D01*
X139351Y-55402D01*
X138067Y-54831D01*
X136784Y-55021D01*
X135501Y-55782D01*
G01X141732Y349941D02*
Y182894D01*
G01D02*
X153543D01*
G01Y349941D02*
X141732D01*
G01Y588406D02*
X153543D01*
G01X141732Y755453D02*
Y588406D01*
G01X153543Y755453D02*
X141732D01*
G01Y993917D02*
X153543D01*
G01X141732Y1160965D02*
Y993917D01*
G01X153543Y1160965D02*
X141732D01*
G01Y1399429D02*
X153543D01*
G01X141732Y1566477D02*
Y1399429D01*
G01X153543Y1566477D02*
X141732D01*
G01Y1804941D02*
X153543D01*
G01X141732Y1971988D02*
Y1804941D01*
G01X153543Y1971988D02*
X141732D01*
G01X134360Y2113798D02*
X135215Y2112467D01*
X136356Y2111707D01*
X137640Y2111517D01*
X138781Y2111707D01*
X139921Y2112657D01*
X140634Y2113798D01*
X140777Y2114939D01*
X140492Y2116270D01*
X139493Y2117220D01*
X138495Y2117601D01*
X137212D01*
G01X138495D02*
X139351Y2118171D01*
X140064Y2119121D01*
X140349Y2120262D01*
X140064Y2121403D01*
X139351Y2122353D01*
X138067Y2122924D01*
X136784Y2122734D01*
X135501Y2121973D01*
G01X164173Y162835D02*
G03Y164016I0J591D01*
G01Y160079D02*
G03Y161260I0J591D01*
G01X171063Y179803D02*
G03I-3740J0D01*
G01X165748Y162343D02*
Y164311D01*
G01Y161752D02*
Y159784D01*
G01X165354Y159488D02*
Y164606D01*
G01X165157D02*
Y159488D01*
G01X164370Y179016D02*
Y178819D01*
G01X164173Y160079D02*
Y159488D01*
G01Y162835D02*
Y161260D01*
G01Y164606D02*
Y164016D01*
G01X162598Y159784D02*
Y161752D01*
G01Y164311D02*
Y162343D01*
G01X157480Y173878D02*
Y186831D01*
G01X153543Y169941D02*
Y182894D01*
G01X177165Y178819D02*
X157480D01*
G01Y177835D02*
X177165D01*
G01X157480Y175847D02*
X177165D01*
G01X157480Y173878D02*
X177165D01*
G01X181102Y169941D02*
X153543D01*
G01X164173Y164606D02*
X170472D01*
G01X164173Y164311D02*
X162598D01*
G01X165748D02*
X164173D01*
G01X162598Y162343D02*
X164173D01*
G01D02*
X165748D01*
G01X164173Y162087D02*
X169724D01*
G01X162598Y161752D02*
X164173D01*
G01D02*
X165748D01*
G01X164173Y159784D02*
X162598D01*
G01X165748D02*
X164173D01*
G01Y159488D02*
X170472D01*
G01X160630Y191614D02*
G03I-2559J0D01*
G01X161417D02*
G03I-3346J0D01*
G01X161575D02*
G03I-3504J0D01*
G01X158145Y187481D02*
G03X158071Y195748I-74J4133D01*
G01X157996Y195747D02*
G03X158071Y187480I73J-4133D01*
G01X166634Y332736D02*
Y200099D01*
G01X166142Y186831D02*
Y195177D01*
G01Y180591D02*
Y179016D01*
G01X165354Y198327D02*
Y236378D01*
G01X164567Y179016D02*
Y180591D01*
G01X164370D02*
Y180788D01*
G01Y179016D02*
Y180591D01*
G01X163031Y179016D02*
Y180591D01*
G01X157677D02*
Y179016D01*
G01X153543Y200099D02*
Y201851D01*
G01X145669Y186831D02*
Y200099D01*
G01X165354D02*
X166634D01*
G01X165354D02*
X145669D01*
G01Y198327D02*
X165354D01*
G01X145669Y195177D02*
X195669D01*
G01X166142Y192225D02*
X177165D01*
G01X145669D02*
X166142D01*
G01X199606Y188012D02*
X166142D01*
G01X199606Y186831D02*
X145669D01*
G01X157480Y184862D02*
X177165D01*
G01Y181772D02*
X157480D01*
G01Y180788D02*
X177165D01*
G01X176968Y180591D02*
X157677D01*
G01X176968Y179016D02*
X157677D01*
G01X157996Y195748D02*
X158071D01*
G01X158145Y187481D02*
X158071Y187480D01*
G01X150464Y203248D02*
X150564Y203281D01*
G01X156693Y203032D02*
X153543Y201851D01*
G01X156693Y208032D02*
X153543Y206851D01*
G01X156693Y213032D02*
X153543Y211851D01*
G01X156693Y218032D02*
X153543Y216851D01*
G01X149526Y204101D02*
X149660Y204167D01*
G01X149693Y203970D02*
X149593Y203904D01*
G01X150631Y204429D02*
X150866Y204626D01*
G01X150598D02*
X150364Y204429D01*
G01X150679Y203130D02*
X150631Y203084D01*
G01X150766Y203215D02*
X150679Y203130D01*
G01X149392Y203970D02*
X149526Y204101D01*
G01X150564Y203281D02*
X150631Y203379D01*
G01X149593Y203904D02*
X149526Y203806D01*
G01X150832Y203347D02*
X150766Y203215D01*
G01X149325Y203839D02*
X149392Y203970D01*
G01X150631Y203379D02*
X150665Y203478D01*
G01X150866D02*
X150832Y203347D01*
G01X149526Y203806D02*
X149492Y203675D01*
G01X149291D02*
X149325Y203839D01*
G01X161417Y219705D02*
Y219803D01*
G01Y218032D02*
Y218130D01*
G01D02*
Y219705D01*
G01Y214705D02*
Y214803D01*
G01Y213032D02*
Y213130D01*
G01D02*
Y214705D01*
G01Y209705D02*
Y209803D01*
G01Y208032D02*
Y208130D01*
G01D02*
Y209705D01*
G01Y204705D02*
Y204803D01*
G01Y203032D02*
Y203130D01*
G01D02*
Y204705D01*
G01X155787Y218130D02*
Y219705D01*
G01Y213130D02*
Y214705D01*
G01Y208130D02*
Y209705D01*
G01Y203130D02*
Y204705D01*
G01X154212Y218130D02*
Y219705D01*
G01Y213130D02*
Y214705D01*
G01Y208130D02*
Y209705D01*
G01Y203130D02*
Y204705D01*
G01X153543Y220984D02*
Y221851D01*
G01Y215984D02*
Y216851D01*
G01Y210984D02*
Y211851D01*
G01Y205984D02*
Y206851D01*
G01X153425Y204705D02*
Y203130D01*
G01Y209705D02*
Y208130D01*
G01Y214705D02*
Y213130D01*
G01Y219705D02*
Y218130D01*
G01X153031Y204705D02*
Y203130D01*
G01Y209705D02*
Y208130D01*
G01Y214705D02*
Y213130D01*
G01Y219705D02*
Y218130D01*
G01X150866Y204705D02*
Y204823D01*
G01Y204626D02*
Y204705D01*
G01Y203642D02*
Y203478D01*
G01X150665D02*
Y203675D01*
G01X150497Y203871D02*
Y204068D01*
G01X150196Y203675D02*
Y203478D01*
G01X149995D02*
Y203675D01*
G01X149727Y203130D02*
Y202953D01*
G01Y203150D02*
Y203130D01*
G01X149492Y203675D02*
Y203412D01*
G01X149291D02*
Y203675D01*
G01Y204823D02*
Y204705D01*
G01D02*
Y204626D01*
G01X148110Y218130D02*
Y219705D01*
G01Y213130D02*
Y214705D01*
G01Y208130D02*
Y209705D01*
G01Y203130D02*
Y204705D01*
G01X150832Y203806D02*
X150866Y203642D01*
G01X150162Y203839D02*
X150196Y203675D01*
G01X149325Y203248D02*
X149291Y203412D01*
G01X149995Y203675D02*
X149961Y203806D01*
G01X150028Y203347D02*
X149995Y203478D01*
G01X149492Y203412D02*
X149526Y203281D01*
G01X150665Y203675D02*
X150631Y203773D01*
G01X150196Y203478D02*
X150229Y203379D01*
G01X150095Y203970D02*
X150162Y203839D01*
G01X150095Y203215D02*
X150028Y203347D01*
G01X149425Y203084D02*
X149397Y203130D01*
G01D02*
X149325Y203248D01*
G01X150631Y203084D02*
X150497Y203051D01*
G01X149961Y203806D02*
X149894Y203904D01*
G01X150229Y203379D02*
X150296Y203281D01*
G01X150732Y203937D02*
X150832Y203806D01*
G01X150631Y203773D02*
X150564Y203839D01*
G01X149961Y204101D02*
X150095Y203970D01*
G01X150229Y203084D02*
X150182Y203130D01*
G01D02*
X150095Y203215D01*
G01X149526Y203281D02*
X149626Y203182D01*
G01X165354Y219803D02*
X197638D01*
G01X161417D02*
X156693D01*
G01X165354Y219705D02*
X195876D01*
G01X148110D02*
X165354D01*
G01Y218130D02*
X195876D01*
G01X165354D02*
X148110D01*
G01X165354Y218032D02*
X197638D01*
G01X156693D02*
X161417D01*
G01X165354Y214803D02*
X197638D01*
G01X161417D02*
X156693D01*
G01X165354Y214705D02*
X195876D01*
G01X148110D02*
X165354D01*
G01Y213130D02*
X195876D01*
G01X165354D02*
X148110D01*
G01X165354Y213032D02*
X197638D01*
G01X156693D02*
X161417D01*
G01X165354Y209803D02*
X197638D01*
G01X161417D02*
X156693D01*
G01X165354Y209705D02*
X195876D01*
G01X148110D02*
X165354D01*
G01Y208130D02*
X195876D01*
G01X165354D02*
X148110D01*
G01X165354Y208032D02*
X197638D01*
G01X156693D02*
X161417D01*
G01X150866Y204823D02*
X149291D01*
G01X165354Y204803D02*
X197638D01*
G01X161417D02*
X156693D01*
G01X165354Y204705D02*
X195876D01*
G01X148110D02*
X165354D01*
G01X149291Y204626D02*
X150598D01*
G01X150364Y204429D02*
X150631D01*
G01X149660Y204167D02*
X149827D01*
G01X149794Y203970D02*
X149693D01*
G01X150397Y203248D02*
X150464D01*
G01X165354Y203130D02*
X195876D01*
G01X165354D02*
X148110D01*
G01X150497Y203051D02*
X150364D01*
G01X165354Y203032D02*
X197638D01*
G01X156693D02*
X161417D01*
G01X150598Y204036D02*
X150732Y203937D01*
G01X149894Y203904D02*
X149794Y203970D01*
G01X149593Y202986D02*
X149425Y203084D01*
G01X150564Y203839D02*
X150497Y203871D01*
G01X149827Y204167D02*
X149961Y204101D01*
G01X153543Y220984D02*
X156693Y219803D01*
G01X153543Y215984D02*
X156693Y214803D01*
G01X153543Y210984D02*
X156693Y209803D01*
G01X153543Y205984D02*
X156693Y204803D01*
G01X150497Y204068D02*
X150598Y204036D01*
G01X150296Y203281D02*
X150397Y203248D01*
G01X149626Y203182D02*
X149727Y203150D01*
G01X150364Y203051D02*
X150229Y203084D01*
G01X149727Y202953D02*
X149593Y202986D01*
G01X162992Y236280D02*
X160630Y235591D01*
G01X162992Y239429D02*
X160630Y238740D01*
G01X162992Y242579D02*
X160630Y241890D01*
G01X157747Y235965D02*
X157848Y235997D01*
G01X156693Y223032D02*
X153543Y221851D01*
G01X156693Y228032D02*
X153543Y226851D01*
G01X156693Y233032D02*
X153543Y231851D01*
G01X157915Y237244D02*
X157747Y237178D01*
G01X157245Y237211D02*
X157077Y237146D01*
G01X156809Y238261D02*
X156977Y238327D01*
G01X156809Y236817D02*
X156943Y236883D01*
G01X157513Y238228D02*
X157647Y238294D01*
G01X156977Y236686D02*
X156876Y236621D01*
G01X157848Y237408D02*
X157747Y237343D01*
G01X157580Y238064D02*
X157680Y238130D01*
G01X157211Y237408D02*
X157077Y237310D01*
G01X156843Y238064D02*
X156977Y238163D01*
G01X158049Y235932D02*
X157915Y235801D01*
G01X158016Y237343D02*
X157915Y237244D01*
G01X156675Y236686D02*
X156809Y236817D01*
G01X157412Y238130D02*
X157513Y238228D01*
G01X156709Y238163D02*
X156809Y238261D01*
G01X157948Y237540D02*
X157848Y237408D01*
G01X157345Y237343D02*
X157245Y237211D01*
G01X157479Y237933D02*
X157580Y238064D01*
G01X157848Y235997D02*
X157915Y236096D01*
G01X156876Y236621D02*
X156809Y236522D01*
G01X158116Y237506D02*
X158016Y237343D01*
G01X156608Y237999D02*
X156709Y238163D01*
G01X158116Y236063D02*
X158049Y235932D01*
G01X157379Y237408D02*
X157345Y237343D01*
G01X157278Y237540D02*
X157211Y237408D01*
G01X157379Y238064D02*
X157412Y238130D01*
G01X156608Y236555D02*
X156675Y236686D01*
G01X156776Y237933D02*
X156843Y238064D01*
G01X157915Y236096D02*
X157948Y236194D01*
G01X158149D02*
X158116Y236063D01*
G01X157982Y237671D02*
X157953Y237559D01*
G01D02*
X157948Y237540D01*
G01X157446Y237802D02*
X157479Y237933D01*
G01X157283Y237559D02*
X157278Y237540D01*
G01X157312Y237671D02*
X157283Y237559D01*
G01X156809Y236522D02*
X156776Y236391D01*
G01X156742Y237802D02*
X156776Y237933D01*
G01X158149Y237671D02*
X158127Y237559D01*
G01D02*
X158116Y237506D01*
G01X156575Y236391D02*
X156608Y236555D01*
G01X156575Y237835D02*
X156608Y237999D01*
G01X165354Y239528D02*
Y237559D01*
G01D02*
Y236378D01*
G01Y242677D02*
Y240709D01*
G01D02*
Y239528D01*
G01X163464D02*
Y240709D01*
G01Y236378D02*
Y237559D01*
G01X161890Y239528D02*
Y240709D01*
G01Y236378D02*
Y237559D01*
G01X161417Y234705D02*
Y234803D01*
G01Y233032D02*
Y233130D01*
G01D02*
Y234705D01*
G01Y229705D02*
Y229803D01*
G01Y228032D02*
Y228130D01*
G01D02*
Y229705D01*
G01Y224705D02*
Y224803D01*
G01Y223032D02*
Y223130D01*
G01D02*
Y224705D01*
G01X161102Y237559D02*
Y236378D01*
G01Y240709D02*
Y239528D01*
G01X160708Y237559D02*
Y236378D01*
G01Y240709D02*
Y239528D01*
G01X160630Y241496D02*
Y241890D01*
G01Y235394D02*
Y235591D01*
G01Y238347D02*
Y238740D01*
G01X158464Y227795D02*
Y225040D01*
G01X158149Y237802D02*
Y237671D01*
G01Y236358D02*
Y236194D01*
G01X157982Y237802D02*
Y237671D01*
G01X157948Y236194D02*
Y236378D01*
G01D02*
Y236391D01*
G01X157781Y236588D02*
Y236785D01*
G01X157479Y236378D02*
Y236194D01*
G01Y236391D02*
Y236378D01*
G01X157446Y237671D02*
Y237802D01*
G01X157312D02*
Y237671D01*
G01X157283Y234803D02*
Y235394D01*
G01X157278Y236194D02*
Y236378D01*
G01D02*
Y236391D01*
G01X157010Y235866D02*
Y235669D01*
G01X156776Y236378D02*
Y236128D01*
G01Y236391D02*
Y236378D01*
G01X156742Y237671D02*
Y237802D01*
G01X156575Y237638D02*
Y237835D01*
G01Y236128D02*
Y236378D01*
G01D02*
Y236391D01*
G01X156102Y239528D02*
Y240709D01*
G01Y236378D02*
Y237559D01*
G01X155787Y233130D02*
Y234705D01*
G01Y228130D02*
Y229705D01*
G01Y223130D02*
Y224705D01*
G01X154212Y233130D02*
Y234705D01*
G01Y228130D02*
Y229705D01*
G01Y223130D02*
Y224705D01*
G01X153543Y230984D02*
Y231851D01*
G01Y225984D02*
Y226851D01*
G01X153425Y224705D02*
Y223130D01*
G01Y229705D02*
Y228130D01*
G01Y234705D02*
Y233130D01*
G01X153031Y224705D02*
Y223130D01*
G01Y229705D02*
Y228130D01*
G01Y234705D02*
Y233130D01*
G01X148110D02*
Y234705D01*
G01Y228130D02*
Y229705D01*
G01Y223130D02*
Y224705D01*
G01X158116Y237966D02*
X158149Y237802D01*
G01X158145Y236378D02*
X158149Y236358D01*
G01X158116Y236522D02*
X158145Y236378D01*
G01X157446Y236555D02*
X157479Y236391D01*
G01X156591Y237559D02*
X156575Y237638D01*
G01X156608Y237474D02*
X156591Y237559D01*
G01X156608Y235965D02*
X156575Y236128D01*
G01X157948Y237933D02*
X157982Y237802D01*
G01X157474Y237559D02*
X157446Y237671D01*
G01X157479Y237540D02*
X157474Y237559D01*
G01X157278Y237933D02*
X157312Y237802D01*
G01X157278Y236391D02*
X157245Y236522D01*
G01X157312Y236063D02*
X157278Y236194D01*
G01X156771Y237559D02*
X156742Y237671D01*
G01X156776Y237540D02*
X156771Y237559D01*
G01X156776Y236128D02*
X156809Y235997D01*
G01X157948Y236391D02*
X157915Y236490D01*
G01X157479Y236194D02*
X157513Y236096D01*
G01X157345Y238130D02*
X157379Y238064D01*
G01X157211D02*
X157278Y237933D01*
G01X157412Y237343D02*
X157379Y237408D01*
G01Y236686D02*
X157446Y236555D01*
G01X156843Y237408D02*
X156776Y237540D01*
G01X157379Y235932D02*
X157312Y236063D01*
G01X157915Y235801D02*
X157781Y235768D01*
G01X158016Y238130D02*
X158116Y237966D01*
G01X156709Y237310D02*
X156608Y237474D01*
G01X156709Y235801D02*
X156608Y235965D01*
G01X157245Y236522D02*
X157178Y236621D01*
G01X157513Y236096D02*
X157580Y235997D01*
G01X157848Y238064D02*
X157948Y237933D01*
G01X157245Y238261D02*
X157345Y238130D01*
G01X157580Y237408D02*
X157479Y237540D01*
G01X158016Y236654D02*
X158116Y236522D01*
G01X157915Y238228D02*
X158016Y238130D01*
G01X157513Y237244D02*
X157412Y237343D01*
G01X157915Y236490D02*
X157848Y236555D01*
G01X157245Y236817D02*
X157379Y236686D01*
G01X156809Y237211D02*
X156709Y237310D01*
G01X157513Y235801D02*
X157379Y235932D01*
G01X156809Y235997D02*
X156910Y235899D01*
G01X157077Y238163D02*
X157211Y238064D01*
G01X157881Y236752D02*
X158016Y236654D01*
G01X156977Y237310D02*
X156843Y237408D01*
G01X160630Y241496D02*
X162992Y240807D01*
G01X157647Y235768D02*
X157513Y235801D01*
G01X157010Y235669D02*
X156876Y235702D01*
G01X162992Y240807D02*
X165354D01*
G01X156102Y240709D02*
X168110D01*
G01X156102Y239528D02*
X168110D01*
G01X162992Y239429D02*
X165354D01*
G01X156977Y238327D02*
X157077D01*
G01X157647Y238294D02*
X157747D01*
G01X156977Y238163D02*
X157077D01*
G01X157680Y238130D02*
X157747D01*
G01X162992Y237658D02*
X165354D01*
G01X156102Y237559D02*
X168110D01*
G01X157747Y237343D02*
X157680D01*
G01X157077Y237310D02*
X156977D01*
G01X157747Y237178D02*
X157647D01*
G01X157077Y237146D02*
X156977D01*
G01X156943Y236883D02*
X157111D01*
G01X157077Y236686D02*
X156977D01*
G01X156102Y236378D02*
X168110D01*
G01X162992Y236280D02*
X165354D01*
G01X157680Y235965D02*
X157747D01*
G01X157781Y235768D02*
X157647D01*
G01X157283Y235394D02*
X160630D01*
G01X161417Y234803D02*
X157283D01*
G01X194685D02*
X165354D01*
G01Y234705D02*
X195756D01*
G01X148110D02*
X165354D01*
G01Y234213D02*
X197638D01*
G01X165354Y233130D02*
X148110D01*
G01X195756D02*
X165354D01*
G01Y233032D02*
X194685D01*
G01X156693D02*
X161417D01*
G01Y229803D02*
X156693D01*
G01X197638D02*
X165354D01*
G01Y229705D02*
X195876D01*
G01X148110D02*
X165354D01*
G01Y228130D02*
X195876D01*
G01X165354D02*
X148110D01*
G01X165354Y228032D02*
X197638D01*
G01X156693D02*
X161417D01*
G01X158464Y227795D02*
X165354D01*
G01Y225040D02*
X158464D01*
G01X165354Y224803D02*
X197638D01*
G01X161417D02*
X156693D01*
G01X165354Y224705D02*
X195876D01*
G01X148110D02*
X165354D01*
G01Y223130D02*
X195876D01*
G01X165354D02*
X148110D01*
G01X165354Y223032D02*
X197638D01*
G01X156693D02*
X161417D01*
G01X157747Y238130D02*
X157848Y238064D01*
G01X157680Y237343D02*
X157580Y237408D01*
G01X157178Y236621D02*
X157077Y236686D01*
G01X156876Y235702D02*
X156709Y235801D01*
G01X157647Y237178D02*
X157513Y237244D01*
G01X157848Y236555D02*
X157781Y236588D01*
G01X157111Y236883D02*
X157245Y236817D01*
G01X157747Y238294D02*
X157915Y238228D01*
G01X157077Y238327D02*
X157245Y238261D01*
G01X156977Y237146D02*
X156809Y237211D01*
G01X153543Y230984D02*
X156693Y229803D01*
G01X153543Y225984D02*
X156693Y224803D01*
G01X157781Y236785D02*
X157881Y236752D01*
G01X157580Y235997D02*
X157680Y235965D01*
G01X156910Y235899D02*
X157010Y235866D01*
G01X160630Y238347D02*
X162992Y237658D01*
G01Y245728D02*
X160630Y245040D01*
G01X162992Y248878D02*
X160630Y248189D01*
G01X162992Y252028D02*
X160630Y251339D01*
G01X162992Y255177D02*
X160630Y254488D01*
G01X150336Y258977D02*
X150436Y259009D01*
G01X150403Y259206D02*
X150302Y259173D01*
G01X156693Y263032D02*
X153543Y261851D01*
G01X150302Y259173D02*
X150168Y259075D01*
G01X150671Y259469D02*
X150905Y259666D01*
G01X150637D02*
X150403Y259469D01*
G01X150269Y258911D02*
X150336Y258977D01*
G01X150168Y259075D02*
X150067Y258943D01*
G01X150235Y258812D02*
X150269Y258911D01*
G01X150067Y258943D02*
X150034Y258780D01*
G01X165354Y256457D02*
Y273130D01*
G01Y243858D02*
Y242677D01*
G01Y245827D02*
Y243858D01*
G01Y248977D02*
Y247008D01*
G01D02*
Y245827D01*
G01Y252126D02*
Y250158D01*
G01D02*
Y248977D01*
G01Y253307D02*
Y252126D01*
G01Y255276D02*
Y253307D01*
G01Y256457D02*
Y255276D01*
G01X163464D02*
Y256457D01*
G01Y248977D02*
Y250158D01*
G01Y252126D02*
Y253307D01*
G01Y245827D02*
Y247008D01*
G01Y242677D02*
Y243858D01*
G01X161890Y255276D02*
Y256457D01*
G01Y252126D02*
Y253307D01*
G01Y248977D02*
Y250158D01*
G01Y245827D02*
Y247008D01*
G01Y242677D02*
Y243858D01*
G01X161417Y263130D02*
Y264705D01*
G01Y263032D02*
Y263130D01*
G01Y259705D02*
Y259803D01*
G01Y258130D02*
Y259705D01*
G01Y258032D02*
Y258130D01*
G01X161102Y243858D02*
Y242677D01*
G01Y247008D02*
Y245827D01*
G01Y250158D02*
Y248977D01*
G01Y253307D02*
Y252126D01*
G01Y256457D02*
Y255276D01*
G01X160708Y243858D02*
Y242677D01*
G01Y247008D02*
Y245827D01*
G01Y250158D02*
Y248977D01*
G01Y253307D02*
Y252126D01*
G01Y256457D02*
Y255276D01*
G01X160630Y254095D02*
Y254488D01*
G01Y257244D02*
Y257441D01*
G01Y250945D02*
Y251339D01*
G01Y244646D02*
Y245040D01*
G01Y247795D02*
Y248189D01*
G01X158464Y262795D02*
Y260040D01*
G01X157283Y257441D02*
Y258032D01*
G01X156102Y255276D02*
Y256457D01*
G01Y248977D02*
Y250158D01*
G01Y252126D02*
Y253307D01*
G01Y245827D02*
Y247008D01*
G01Y242677D02*
Y243858D01*
G01X155787Y263130D02*
Y264705D01*
G01Y258130D02*
Y259705D01*
G01X154212Y263130D02*
Y264705D01*
G01Y258130D02*
Y259705D01*
G01X153543Y260984D02*
Y261851D01*
G01X153425Y259705D02*
Y258130D01*
G01Y264705D02*
Y263130D01*
G01X153031Y259705D02*
Y258130D01*
G01Y264705D02*
Y263130D01*
G01X150905Y259705D02*
Y259862D01*
G01Y259666D02*
Y259705D01*
G01Y257992D02*
Y258130D01*
G01D02*
Y258780D01*
G01X150738Y258812D02*
Y258189D01*
G01X150235D02*
Y258812D01*
G01X150034Y258780D02*
Y258189D01*
G01X149330Y258130D02*
Y257992D01*
G01Y258189D02*
Y258130D01*
G01Y259862D02*
Y259705D01*
G01D02*
Y259666D01*
G01X148110Y263130D02*
Y264705D01*
G01X146653Y258130D02*
Y259705D01*
G01X150905Y258780D02*
X150872Y258943D01*
G01X150704Y258911D02*
X150738Y258812D01*
G01X150872Y258943D02*
X150771Y259075D01*
G01X165354Y263130D02*
X148110D01*
G01X195876D02*
X165354D01*
G01Y263032D02*
X197638D01*
G01X156693D02*
X161417D01*
G01X158464Y262795D02*
X165354D01*
G01Y260040D02*
X158464D01*
G01X150905Y259862D02*
X149330D01*
G01X165354Y259803D02*
X194685D01*
G01X161417D02*
X156693D01*
G01X165354Y259705D02*
X195756D01*
G01X146653D02*
X165354D01*
G01X149330Y259666D02*
X150637D01*
G01X150403Y259469D02*
X150671D01*
G01X150537Y259206D02*
X150403D01*
G01X150436Y259009D02*
X150537D01*
G01X165354Y258622D02*
X197638D01*
G01X150738Y258189D02*
X150235D01*
G01X150034D02*
X149330D01*
G01X165354Y258130D02*
X195756D01*
G01X146653D02*
X165354D01*
G01Y258032D02*
X194685D01*
G01X157283D02*
X161417D01*
G01X149330Y257992D02*
X150905D01*
G01X160630Y257441D02*
X157283D01*
G01X162992Y256555D02*
X165354D01*
G01X156102Y256457D02*
X168110D01*
G01X156102Y255276D02*
X168110D01*
G01X162992Y255177D02*
X165354D01*
G01X162992Y253406D02*
X165354D01*
G01X156102Y253307D02*
X168110D01*
G01X156102Y252126D02*
X168110D01*
G01X162992Y252028D02*
X165354D01*
G01X162992Y250256D02*
X165354D01*
G01X156102Y250158D02*
X168110D01*
G01X156102Y248977D02*
X168110D01*
G01X162992Y248878D02*
X165354D01*
G01X162992Y247106D02*
X165354D01*
G01X156102Y247008D02*
X168110D01*
G01X156102Y245827D02*
X168110D01*
G01X162992Y245728D02*
X165354D01*
G01X150637Y258977D02*
X150704Y258911D01*
G01X150771Y259075D02*
X150637Y259173D01*
G01X153543Y260984D02*
X156693Y259803D01*
G01X150637Y259173D02*
X150537Y259206D01*
G01Y259009D02*
X150637Y258977D01*
G01X160630Y257244D02*
X162992Y256555D01*
G01X160630Y254095D02*
X162992Y253406D01*
G01X160630Y250945D02*
X162992Y250256D01*
G01X160630Y247795D02*
X162992Y247106D01*
G01X160630Y244646D02*
X162992Y243957D01*
G01D02*
X165354D01*
G01X156102Y243858D02*
X168110D01*
G01X156102Y242677D02*
X168110D01*
G01X162992Y242579D02*
X165354D01*
G01X156693Y268032D02*
X153543Y266851D01*
G01X156693Y278032D02*
X153543Y276851D01*
G01X156693Y283032D02*
X153543Y281851D01*
G01X166535Y271555D02*
Y276280D01*
G01X165354Y274705D02*
Y313130D01*
G01Y274705D02*
Y273130D01*
G01X163386Y274705D02*
Y274803D01*
G01Y273032D02*
Y273130D01*
G01D02*
Y274705D01*
G01X161417Y284705D02*
Y284803D01*
G01Y283032D02*
Y283130D01*
G01D02*
Y284705D01*
G01Y279705D02*
Y279803D01*
G01Y278032D02*
Y278130D01*
G01D02*
Y279705D01*
G01Y269705D02*
Y269803D01*
G01Y268130D02*
Y269705D01*
G01Y268032D02*
Y268130D01*
G01Y264705D02*
Y264803D01*
G01X155787Y283130D02*
Y284705D01*
G01Y278130D02*
Y279705D01*
G01Y273130D02*
Y274705D01*
G01Y268130D02*
Y269705D01*
G01X154212Y283130D02*
Y284705D01*
G01Y278130D02*
Y279705D01*
G01Y273130D02*
Y274705D01*
G01Y268130D02*
Y269705D01*
G01X153543Y280984D02*
Y281851D01*
G01Y275984D02*
Y276851D01*
G01Y270984D02*
Y271851D01*
G01Y265984D02*
Y266851D01*
G01X153425Y269705D02*
Y268130D01*
G01Y274705D02*
Y273130D01*
G01Y279705D02*
Y278130D01*
G01Y284705D02*
Y283130D01*
G01X153031Y269705D02*
Y268130D01*
G01Y274705D02*
Y273130D01*
G01Y279705D02*
Y278130D01*
G01Y284705D02*
Y283130D01*
G01X148110D02*
Y284705D01*
G01Y278130D02*
Y279705D01*
G01Y268130D02*
Y269705D01*
G01X146653Y273130D02*
Y274705D01*
G01X158661Y273032D02*
X153543Y271851D01*
G01X165354Y284705D02*
X195876D01*
G01X148110D02*
X165354D01*
G01Y283130D02*
X195876D01*
G01X165354D02*
X148110D01*
G01X165354Y283032D02*
X197638D01*
G01X156693D02*
X161417D01*
G01X165354Y279803D02*
X197638D01*
G01X161417D02*
X156693D01*
G01X165354Y279705D02*
X195876D01*
G01X148110D02*
X165354D01*
G01Y278130D02*
X195876D01*
G01X165354D02*
X148110D01*
G01X165354Y278032D02*
X197638D01*
G01X156693D02*
X161417D01*
G01X166535Y276280D02*
X165354D01*
G01X163386Y274803D02*
X158661D01*
G01X197638D02*
X166535D01*
G01Y274705D02*
X195876D01*
G01X146653D02*
X166535D01*
G01Y273130D02*
X195876D01*
G01X146653D02*
X166535D01*
G01Y273032D02*
X197638D01*
G01X158661D02*
X163386D01*
G01X165354Y271555D02*
X166535D01*
G01X165354Y269803D02*
X197638D01*
G01X161417D02*
X156693D01*
G01X165354Y269705D02*
X195876D01*
G01X148110D02*
X165354D01*
G01Y268130D02*
X195876D01*
G01X165354D02*
X148110D01*
G01X165354Y268032D02*
X197638D01*
G01X156693D02*
X161417D01*
G01X165354Y264803D02*
X197638D01*
G01X161417D02*
X156693D01*
G01X165354Y264705D02*
X195876D01*
G01X148110D02*
X165354D01*
G01X153543Y280984D02*
X156693Y279803D01*
G01X153543Y270984D02*
X156693Y269803D01*
G01X153543Y265984D02*
X156693Y264803D01*
G01X153543Y275984D02*
X158661Y274803D01*
G01X156693Y288032D02*
X153543Y286851D01*
G01X156693Y293032D02*
X153543Y291851D01*
G01X156693Y298032D02*
X153543Y296851D01*
G01X156693Y303032D02*
X153543Y301851D01*
G01X161417Y304705D02*
Y304803D01*
G01Y303032D02*
Y303130D01*
G01D02*
Y304705D01*
G01Y299705D02*
Y299803D01*
G01Y298032D02*
Y298130D01*
G01D02*
Y299705D01*
G01Y294705D02*
Y294803D01*
G01Y293032D02*
Y293130D01*
G01D02*
Y294705D01*
G01Y289705D02*
Y289803D01*
G01Y288032D02*
Y288130D01*
G01D02*
Y289705D01*
G01X158464Y287795D02*
Y285040D01*
G01X155787Y303130D02*
Y304705D01*
G01Y298130D02*
Y299705D01*
G01Y293130D02*
Y294705D01*
G01Y288130D02*
Y289705D01*
G01X154212Y303130D02*
Y304705D01*
G01Y298130D02*
Y299705D01*
G01Y293130D02*
Y294705D01*
G01Y288130D02*
Y289705D01*
G01X153543Y300984D02*
Y301851D01*
G01Y295984D02*
Y296851D01*
G01Y290984D02*
Y291851D01*
G01Y285984D02*
Y286851D01*
G01X153425Y289705D02*
Y288130D01*
G01Y294705D02*
Y293130D01*
G01Y299705D02*
Y298130D01*
G01Y304705D02*
Y303130D01*
G01X153031Y289705D02*
Y288130D01*
G01Y294705D02*
Y293130D01*
G01Y299705D02*
Y298130D01*
G01Y304705D02*
Y303130D01*
G01X148110D02*
Y304705D01*
G01Y298130D02*
Y299705D01*
G01Y293130D02*
Y294705D01*
G01Y288130D02*
Y289705D01*
G01X165354Y304803D02*
X197638D01*
G01X161417D02*
X156693D01*
G01X165354Y304705D02*
X195876D01*
G01X148110D02*
X165354D01*
G01Y303130D02*
X195876D01*
G01X165354D02*
X148110D01*
G01X165354Y303032D02*
X197638D01*
G01X156693D02*
X161417D01*
G01X165354Y299803D02*
X197638D01*
G01X161417D02*
X156693D01*
G01X165354Y299705D02*
X195876D01*
G01X148110D02*
X165354D01*
G01Y298130D02*
X195876D01*
G01X165354D02*
X148110D01*
G01X165354Y298032D02*
X197638D01*
G01X156693D02*
X161417D01*
G01X165354Y294803D02*
X197638D01*
G01X161417D02*
X156693D01*
G01X165354Y294705D02*
X195876D01*
G01X148110D02*
X165354D01*
G01Y293130D02*
X195876D01*
G01X165354D02*
X148110D01*
G01X165354Y293032D02*
X197638D01*
G01X156693D02*
X161417D01*
G01X165354Y289803D02*
X197638D01*
G01X161417D02*
X156693D01*
G01X165354Y289705D02*
X195876D01*
G01X148110D02*
X165354D01*
G01Y288130D02*
X195876D01*
G01X165354D02*
X148110D01*
G01X165354Y288032D02*
X197638D01*
G01X156693D02*
X161417D01*
G01X158464Y287795D02*
X165354D01*
G01Y285040D02*
X158464D01*
G01X165354Y284803D02*
X197638D01*
G01X161417D02*
X156693D01*
G01X153543Y305984D02*
X156693Y304803D01*
G01X153543Y300984D02*
X156693Y299803D01*
G01X153543Y295984D02*
X156693Y294803D01*
G01X153543Y290984D02*
X156693Y289803D01*
G01X153543Y285984D02*
X156693Y284803D01*
G01Y308032D02*
X153543Y306851D01*
G01X156693Y318032D02*
X153543Y316851D01*
G01X156693Y323032D02*
X153543Y321851D01*
G01X156693Y328032D02*
X153543Y326851D01*
G01X166535Y311555D02*
Y316280D01*
G01X165354Y314705D02*
Y334508D01*
G01Y314705D02*
Y313130D01*
G01X163386Y314705D02*
Y314803D01*
G01Y313032D02*
Y313130D01*
G01D02*
Y314705D01*
G01X161417Y324705D02*
Y324803D01*
G01Y323130D02*
Y324705D01*
G01Y323032D02*
Y323130D01*
G01Y319705D02*
Y319803D01*
G01Y318130D02*
Y319705D01*
G01Y318032D02*
Y318130D01*
G01Y309705D02*
Y309803D01*
G01Y308032D02*
Y308130D01*
G01D02*
Y309705D01*
G01X158464Y312795D02*
Y310040D01*
G01X155787Y323130D02*
Y324705D01*
G01Y318130D02*
Y319705D01*
G01Y313130D02*
Y314705D01*
G01Y308130D02*
Y309705D01*
G01X154212Y323130D02*
Y324705D01*
G01Y318130D02*
Y319705D01*
G01Y313130D02*
Y314705D01*
G01Y308130D02*
Y309705D01*
G01X153543Y325984D02*
Y326851D01*
G01Y320984D02*
Y321851D01*
G01Y315984D02*
Y316851D01*
G01Y310984D02*
Y311851D01*
G01Y305984D02*
Y306851D01*
G01X153425Y309705D02*
Y308130D01*
G01Y314705D02*
Y313130D01*
G01Y319705D02*
Y318130D01*
G01Y324705D02*
Y323130D01*
G01X153031Y309705D02*
Y308130D01*
G01Y314705D02*
Y313130D01*
G01Y319705D02*
Y318130D01*
G01Y324705D02*
Y323130D01*
G01X148110D02*
Y324705D01*
G01Y318130D02*
Y319705D01*
G01Y308130D02*
Y309705D01*
G01X146653Y313130D02*
Y314705D01*
G01X158661Y313032D02*
X153543Y311851D01*
G01X165354Y324803D02*
X197638D01*
G01X161417D02*
X156693D01*
G01X165354Y324705D02*
X195876D01*
G01X148110D02*
X165354D01*
G01Y323130D02*
X195876D01*
G01X165354D02*
X148110D01*
G01X165354Y323032D02*
X197638D01*
G01X156693D02*
X161417D01*
G01X153543Y315984D02*
X158661Y314803D01*
G01X165354Y319803D02*
X197638D01*
G01X161417D02*
X156693D01*
G01X165354Y319705D02*
X195876D01*
G01X148110D02*
X165354D01*
G01Y318130D02*
X195876D01*
G01X165354D02*
X148110D01*
G01X165354Y318032D02*
X197638D01*
G01X156693D02*
X161417D01*
G01X166535Y316280D02*
X165354D01*
G01X163386Y314803D02*
X158661D01*
G01X197638D02*
X166535D01*
G01Y314705D02*
X195876D01*
G01X146653D02*
X166535D01*
G01Y313130D02*
X195876D01*
G01X146653D02*
X166535D01*
G01Y313032D02*
X197638D01*
G01X158661D02*
X163386D01*
G01X158464Y312795D02*
X165354D01*
G01Y311555D02*
X166535D01*
G01X165354Y310040D02*
X158464D01*
G01X165354Y309803D02*
X197638D01*
G01X161417D02*
X156693D01*
G01X165354Y309705D02*
X195876D01*
G01X148110D02*
X165354D01*
G01Y308130D02*
X195876D01*
G01X165354D02*
X148110D01*
G01X165354Y308032D02*
X197638D01*
G01X156693D02*
X161417D01*
G01X153543Y325984D02*
X156693Y324803D01*
G01X153543Y320984D02*
X156693Y319803D01*
G01X153543Y310984D02*
X156693Y309803D01*
G01X160325Y339131D02*
X160441Y338858D01*
G01X160207Y339393D02*
X160325Y339131D01*
G01X160088Y339646D02*
X160207Y339393D01*
G01X155939Y343037D02*
X156054Y342795D01*
G01X155821Y343300D02*
X155939Y343037D01*
G01X155700Y343583D02*
X155821Y343300D01*
G01X155700Y338857D02*
Y338858D01*
G01X155698Y338853D02*
X155700Y338857D01*
G01X155674Y338795D02*
X155698Y338853D01*
G01X160442Y343584D02*
X160441Y343583D01*
G01X160443Y343588D02*
X160442Y343584D01*
G01X160467Y343647D02*
X160443Y343588D01*
G01X155934Y339393D02*
X156054Y339646D01*
G01X155816Y339131D02*
X155934Y339393D01*
G01X155700Y338858D02*
X155816Y339131D01*
G01X160321Y343300D02*
X160441Y343583D01*
G01X160203Y343038D02*
X160321Y343300D01*
G01X160088Y342795D02*
X160203Y343038D01*
G01X156054Y342795D02*
G03Y339646I2017J-1574D01*
G01X160088D02*
G03Y342795I-2017J1574D01*
G01X155700Y343583D02*
G03Y338858I2370J-2363D01*
G01X160441D02*
G03Y343583I-2370J2363D01*
G01X161575Y341221D02*
G03I-3504J0D01*
G01X160748Y338071D02*
G03Y344370I-2677J3150D01*
G01X155393D02*
G03Y338071I2678J-3149D01*
G01X160506Y343740D02*
X160467Y343647D01*
G01X155636Y338701D02*
X155674Y338795D01*
G01X160589Y343949D02*
X160506Y343740D01*
G01X155553Y338493D02*
X155636Y338701D01*
G01X160623Y344034D02*
X160589Y343949D01*
G01X155519Y338406D02*
X155553Y338493D01*
G01X160658Y344126D02*
X160623Y344034D01*
G01X155484Y338315D02*
X155519Y338406D01*
G01X160693Y344222D02*
X160658Y344126D01*
G01X155448Y338219D02*
X155484Y338315D01*
G01X160748Y344370D02*
X160693Y344222D01*
G01X155393Y338071D02*
X155448Y338219D01*
G01X166142Y337658D02*
Y346004D01*
G01X161417Y329705D02*
Y329803D01*
G01Y328130D02*
Y329705D01*
G01Y328032D02*
Y328130D01*
G01X157480Y346004D02*
Y358957D01*
G01X155787Y328130D02*
Y329705D01*
G01X154212Y328130D02*
Y329705D01*
G01X153543Y330984D02*
Y332736D01*
G01X153425Y329705D02*
Y328130D01*
G01X153031Y329705D02*
Y328130D01*
G01X148110D02*
Y329705D01*
G01X145669Y332736D02*
Y346004D01*
G01X160693Y338219D02*
X160748Y338071D01*
G01X155448Y344222D02*
X155393Y344370D01*
G01X160658Y338315D02*
X160693Y338219D01*
G01X155484Y344126D02*
X155448Y344222D01*
G01X160623Y338406D02*
X160658Y338315D01*
G01X155519Y344035D02*
X155484Y344126D01*
G01X160589Y338492D02*
X160623Y338406D01*
G01X155552Y343949D02*
X155519Y344035D01*
G01X160517Y338671D02*
X160589Y338492D01*
G01X155624Y343769D02*
X155552Y343949D01*
G01X160484Y338753D02*
X160517Y338671D01*
G01X155657Y343688D02*
X155624Y343769D01*
G01X160441Y338858D02*
X160484Y338753D01*
G01X155700Y343583D02*
X155657Y343688D01*
G01X177165Y347973D02*
X157480D01*
G01X199606Y346004D02*
X145669D01*
G01X166142Y344823D02*
X199606D01*
G01X155393Y344370D02*
X160748D01*
G01X160441Y343583D02*
X155700D01*
G01X156054Y342795D02*
X160088D01*
G01X166142Y340610D02*
X145669D01*
G01X177165D02*
X166142D01*
G01X156054Y339646D02*
X160088D01*
G01X155700Y338858D02*
X160441D01*
G01X160748Y338071D02*
X155393D01*
G01X195669Y337658D02*
X145669D01*
G01X165354Y334508D02*
X145669D01*
G01Y332736D02*
X165354D01*
G01D02*
X166634D01*
G01X161417Y329803D02*
X156693D01*
G01X197638D02*
X165354D01*
G01Y329705D02*
X195876D01*
G01X148110D02*
X165354D01*
G01Y328130D02*
X195876D01*
G01X165354D02*
X148110D01*
G01X165354Y328032D02*
X197638D01*
G01X156693D02*
X161417D01*
G01X153543Y330984D02*
X156693Y329803D01*
G01X171063Y353032D02*
G03I-3740J0D01*
G01X166142Y353819D02*
Y352244D01*
G01X164567D02*
Y353819D01*
G01X164370D02*
Y354016D01*
G01Y352244D02*
Y353819D01*
G01Y352244D02*
Y352047D01*
G01X163031Y352244D02*
Y353819D01*
G01X157677D02*
Y352244D01*
G01X153543Y349941D02*
Y362894D01*
G01D02*
X181102D01*
G01X177165Y358957D02*
X157480D01*
G01X177165Y356988D02*
X157480D01*
G01X177165Y355000D02*
X157480D01*
G01Y354016D02*
X177165D01*
G01X176968Y353819D02*
X157677D01*
G01X176968Y352244D02*
X157677D01*
G01X177165Y352047D02*
X157480D01*
G01Y351063D02*
X177165D01*
G01X165945Y532028D02*
Y535669D01*
G01X164370Y532028D02*
Y535669D01*
G01X163386Y532028D02*
Y535669D01*
G01X161614Y547087D02*
Y535669D01*
G01X157677Y554666D02*
Y528091D01*
G01X161614Y535669D02*
X173819D01*
G01X166929Y535473D02*
X165945D01*
G01X164370D02*
X163386D01*
G01X166929Y535391D02*
X165945D01*
G01X164370D02*
X163386D01*
G01X166929Y533996D02*
X165945D01*
G01X164370D02*
X163386D01*
G01X166929Y533915D02*
X165945D01*
G01X164370D02*
X163386D01*
G01X164370Y532028D02*
X163386D01*
G01X166929D02*
X165945D01*
G01X177756Y528091D02*
X157677D01*
G01X165945Y547087D02*
Y550728D01*
G01X164370Y547087D02*
Y550728D01*
G01X163386Y547087D02*
Y550728D01*
G01X177756Y554666D02*
X157677D01*
G01X164370Y550728D02*
X163386D01*
G01X166929D02*
X165945D01*
G01X166929Y548841D02*
X165945D01*
G01X164370D02*
X163386D01*
G01X166929Y548760D02*
X165945D01*
G01X164370D02*
X163386D01*
G01X166929Y547365D02*
X165945D01*
G01X164370D02*
X163386D01*
G01X166929Y547284D02*
X165945D01*
G01X164370D02*
X163386D01*
G01X173819Y547087D02*
X161614D01*
G01X164173Y568347D02*
G03Y569528I0J590D01*
G01Y565591D02*
G03Y566772I0J591D01*
G01X165748Y567854D02*
Y569823D01*
G01Y567264D02*
Y565295D01*
G01X165354Y565000D02*
Y570118D01*
G01X165157D02*
Y565000D01*
G01X164173Y565591D02*
Y565000D01*
G01Y568347D02*
Y566772D01*
G01Y570118D02*
Y569528D01*
G01X162598Y565295D02*
Y567264D01*
G01Y569823D02*
Y567854D01*
G01X157480Y579390D02*
Y592343D01*
G01X153543Y575453D02*
Y588406D01*
G01X157480Y579390D02*
X177165D01*
G01X181102Y575453D02*
X153543D01*
G01X164173Y570118D02*
X170472D01*
G01X164173Y569823D02*
X162598D01*
G01X165748D02*
X164173D01*
G01X162598Y567854D02*
X164173D01*
G01D02*
X165748D01*
G01X162598Y567264D02*
X164173D01*
G01D02*
X165748D01*
G01X164173Y565295D02*
X162598D01*
G01X165748D02*
X164173D01*
G01Y565000D02*
X170472D01*
G01X171063Y585315D02*
G03I-3740J0D01*
G01X160630Y597126D02*
G03I-2559J0D01*
G01X161417D02*
G03I-3346J0D01*
G01X161575D02*
G03I-3504J0D01*
G01X158145Y592993D02*
G03X158071Y601260I-74J4133D01*
G01X157996Y601259D02*
G03X158071Y592992I73J-4133D01*
G01X166142Y592343D02*
Y600689D01*
G01Y586103D02*
Y584528D01*
G01X164567D02*
Y586103D01*
G01X164370D02*
Y586299D01*
G01Y584528D02*
Y586103D01*
G01Y584528D02*
Y584331D01*
G01X163031Y584528D02*
Y586103D01*
G01X157677D02*
Y584528D01*
G01X145669Y600689D02*
X195669D01*
G01X166142Y597736D02*
X177165D01*
G01X145669D02*
X166142D01*
G01X199606Y593524D02*
X166142D01*
G01X199606Y592343D02*
X145669D01*
G01X157480Y590374D02*
X177165D01*
G01Y587284D02*
X157480D01*
G01Y586299D02*
X177165D01*
G01X176968Y586103D02*
X157677D01*
G01X176968Y584528D02*
X157677D01*
G01X177165Y584331D02*
X157480D01*
G01Y583347D02*
X177165D01*
G01X157480Y581358D02*
X177165D01*
G01X157996Y601260D02*
X158071D01*
G01X158145Y592993D02*
X158071Y592992D01*
G01X145669Y592343D02*
Y605610D01*
G01X150464Y608760D02*
X150564Y608793D01*
G01X156693Y608543D02*
X153543Y607362D01*
G01X156693Y613543D02*
X153543Y612362D01*
G01X156693Y618543D02*
X153543Y617362D01*
G01X156693Y623543D02*
X153543Y622362D01*
G01X149526Y609613D02*
X149660Y609678D01*
G01X149693Y609482D02*
X149593Y609416D01*
G01X150631Y609941D02*
X150866Y610138D01*
G01X150598D02*
X150364Y609941D01*
G01X150679Y608642D02*
X150631Y608596D01*
G01X150766Y608727D02*
X150679Y608642D01*
G01X149392Y609482D02*
X149526Y609613D01*
G01X150564Y608793D02*
X150631Y608891D01*
G01X149593Y609416D02*
X149526Y609317D01*
G01X150832Y608858D02*
X150766Y608727D01*
G01X149325Y609351D02*
X149392Y609482D01*
G01X150631Y608596D02*
X150497Y608563D01*
G01X150631Y608891D02*
X150665Y608990D01*
G01X150866D02*
X150832Y608858D01*
G01X149526Y609317D02*
X149492Y609186D01*
G01X149291D02*
X149325Y609351D01*
G01X166634Y738248D02*
Y605610D01*
G01X165354Y603839D02*
Y641890D01*
G01X161417Y620217D02*
Y620315D01*
G01Y618642D02*
Y620217D01*
G01Y618543D02*
Y618642D01*
G01Y615217D02*
Y615315D01*
G01Y613642D02*
Y615217D01*
G01Y613543D02*
Y613642D01*
G01Y610217D02*
Y610315D01*
G01Y608642D02*
Y610217D01*
G01Y608543D02*
Y608642D01*
G01X155787Y618642D02*
Y620217D01*
G01Y613642D02*
Y615217D01*
G01Y608642D02*
Y610217D01*
G01X154212Y618642D02*
Y620217D01*
G01Y613642D02*
Y615217D01*
G01Y608642D02*
Y610217D01*
G01X153543Y621496D02*
Y622362D01*
G01Y616496D02*
Y617362D01*
G01Y611496D02*
Y612362D01*
G01Y605610D02*
Y607362D01*
G01X153425Y610217D02*
Y608642D01*
G01Y615217D02*
Y613642D01*
G01Y620217D02*
Y618642D01*
G01X153031Y610217D02*
Y608642D01*
G01Y615217D02*
Y613642D01*
G01Y620217D02*
Y618642D01*
G01X150866Y610217D02*
Y610335D01*
G01Y610138D02*
Y610217D01*
G01Y609154D02*
Y608990D01*
G01X150665D02*
Y609186D01*
G01X150497Y609383D02*
Y609580D01*
G01X150196Y609186D02*
Y608990D01*
G01X149995D02*
Y609186D01*
G01X149727Y608642D02*
Y608465D01*
G01Y608662D02*
Y608642D01*
G01X149492Y609186D02*
Y608924D01*
G01X149291D02*
Y609186D01*
G01Y610335D02*
Y610217D01*
G01D02*
Y610138D01*
G01X150832Y609317D02*
X150866Y609154D01*
G01X150162Y609351D02*
X150196Y609186D01*
G01X149325Y608760D02*
X149291Y608924D01*
G01X165354Y620315D02*
X197638D01*
G01X161417D02*
X156693D01*
G01X165354Y620217D02*
X195876D01*
G01X148110D02*
X165354D01*
G01Y618642D02*
X195876D01*
G01X165354D02*
X148110D01*
G01X165354Y618543D02*
X197638D01*
G01X156693D02*
X161417D01*
G01X165354Y615315D02*
X197638D01*
G01X161417D02*
X156693D01*
G01X165354Y615217D02*
X195876D01*
G01X148110D02*
X165354D01*
G01Y613642D02*
X195876D01*
G01X165354D02*
X148110D01*
G01X165354Y613543D02*
X197638D01*
G01X156693D02*
X161417D01*
G01X150866Y610335D02*
X149291D01*
G01X165354Y610315D02*
X197638D01*
G01X161417D02*
X156693D01*
G01X165354Y610217D02*
X195876D01*
G01X148110D02*
X165354D01*
G01X149291Y610138D02*
X150598D01*
G01X150364Y609941D02*
X150631D01*
G01X149660Y609678D02*
X149827D01*
G01X149794Y609482D02*
X149693D01*
G01X150397Y608760D02*
X150464D01*
G01X165354Y608642D02*
X195876D01*
G01X165354D02*
X148110D01*
G01X150497Y608563D02*
X150364D01*
G01X165354Y608543D02*
X197638D01*
G01X156693D02*
X161417D01*
G01X165354Y605610D02*
X166634D01*
G01X165354D02*
X145669D01*
G01Y603839D02*
X165354D01*
G01X148110Y618642D02*
Y620217D01*
G01Y613642D02*
Y615217D01*
G01Y608642D02*
Y610217D01*
G01X149995Y609186D02*
X149961Y609317D01*
G01X150028Y608858D02*
X149995Y608990D01*
G01X149492Y608924D02*
X149526Y608793D01*
G01X150665Y609186D02*
X150631Y609285D01*
G01X150196Y608990D02*
X150229Y608891D01*
G01X150095Y609482D02*
X150162Y609351D01*
G01X150095Y608727D02*
X150028Y608858D01*
G01X149425Y608596D02*
X149397Y608642D01*
G01D02*
X149325Y608760D01*
G01X149593Y608497D02*
X149425Y608596D01*
G01X150564Y609351D02*
X150497Y609383D01*
G01X149827Y609678D02*
X149961Y609613D01*
G01X153543Y621496D02*
X156693Y620315D01*
G01X153543Y616496D02*
X156693Y615315D01*
G01X153543Y611496D02*
X156693Y610315D01*
G01X150497Y609580D02*
X150598Y609547D01*
G01X150296Y608793D02*
X150397Y608760D01*
G01X149626Y608694D02*
X149727Y608662D01*
G01X150364Y608563D02*
X150229Y608596D01*
G01X149727Y608465D02*
X149593Y608497D01*
G01X149961Y609317D02*
X149894Y609416D01*
G01X150229Y608891D02*
X150296Y608793D01*
G01X150732Y609449D02*
X150832Y609317D01*
G01X150631Y609285D02*
X150564Y609351D01*
G01X149961Y609613D02*
X150095Y609482D01*
G01X150229Y608596D02*
X150182Y608642D01*
G01D02*
X150095Y608727D01*
G01X149526Y608793D02*
X149626Y608694D01*
G01X150598Y609547D02*
X150732Y609449D01*
G01X149894Y609416D02*
X149794Y609482D01*
G01X162992Y641791D02*
X160630Y641103D01*
G01X162992Y644941D02*
X160630Y644252D01*
G01X157747Y641477D02*
X157848Y641509D01*
G01X156693Y628543D02*
X153543Y627362D01*
G01X156693Y633543D02*
X153543Y632362D01*
G01X156693Y638543D02*
X153543Y637362D01*
G01X157915Y642756D02*
X157747Y642690D01*
G01X157245Y642723D02*
X157077Y642658D01*
G01X156809Y643773D02*
X156977Y643839D01*
G01X156809Y642329D02*
X156943Y642395D01*
G01X157513Y643740D02*
X157647Y643806D01*
G01X156977Y642198D02*
X156876Y642132D01*
G01X157848Y642920D02*
X157747Y642854D01*
G01X157580Y643576D02*
X157680Y643642D01*
G01X157211Y642920D02*
X157077Y642821D01*
G01X156843Y643576D02*
X156977Y643675D01*
G01X158049Y641443D02*
X157915Y641312D01*
G01X158016Y642854D02*
X157915Y642756D01*
G01X156675Y642198D02*
X156809Y642329D01*
G01X157412Y643642D02*
X157513Y643740D01*
G01X156709Y643675D02*
X156809Y643773D01*
G01X157948Y643051D02*
X157848Y642920D01*
G01X157345Y642854D02*
X157245Y642723D01*
G01X157479Y643445D02*
X157580Y643576D01*
G01X157848Y641509D02*
X157915Y641608D01*
G01X156876Y642132D02*
X156809Y642034D01*
G01X158116Y643018D02*
X158016Y642854D01*
G01X156608Y643510D02*
X156709Y643675D01*
G01X158116Y641575D02*
X158049Y641443D01*
G01X157379Y642920D02*
X157345Y642854D01*
G01X157278Y643051D02*
X157211Y642920D01*
G01X157379Y643576D02*
X157412Y643642D01*
G01X156608Y642067D02*
X156675Y642198D01*
G01X156776Y643445D02*
X156843Y643576D01*
G01X157915Y641312D02*
X157781Y641280D01*
G01X157915Y641608D02*
X157948Y641706D01*
G01X158149D02*
X158116Y641575D01*
G01X157982Y643182D02*
X157953Y643071D01*
G01D02*
X157948Y643051D01*
G01X157446Y643314D02*
X157479Y643445D01*
G01X157312Y643182D02*
X157283Y643071D01*
G01D02*
X157278Y643051D01*
G01X156809Y642034D02*
X156776Y641903D01*
G01X156742Y643314D02*
X156776Y643445D01*
G01X158149Y643182D02*
X158127Y643071D01*
G01D02*
X158116Y643018D01*
G01X156575Y641903D02*
X156608Y642067D01*
G01X156575Y643347D02*
X156608Y643510D01*
G01X156977Y643839D02*
X157077D01*
G01X157647Y643806D02*
X157747D01*
G01X156977Y643675D02*
X157077D01*
G01X157680Y643642D02*
X157747D01*
G01X162992Y643169D02*
X165354D01*
G01X156102Y643071D02*
X168110D01*
G01X157747Y642854D02*
X157680D01*
G01X157077Y642821D02*
X156977D01*
G01X157747Y642690D02*
X157647D01*
G01X157077Y642658D02*
X156977D01*
G01X156943Y642395D02*
X157111D01*
G01X157077Y642198D02*
X156977D01*
G01X156102Y641890D02*
X168110D01*
G01X162992Y641791D02*
X165354D01*
G01X157680Y641477D02*
X157747D01*
G01X157781Y641280D02*
X157647D01*
G01X157283Y640906D02*
X160630D01*
G01X161417Y640315D02*
X157283D01*
G01X194685D02*
X165354D01*
G01Y640217D02*
X195756D01*
G01X148110D02*
X165354D01*
G01Y639725D02*
X197638D01*
G01X165354Y638642D02*
X148110D01*
G01X195756D02*
X165354D01*
G01Y638543D02*
X194685D01*
G01X156693D02*
X161417D01*
G01Y635315D02*
X156693D01*
G01X197638D02*
X165354D01*
G01Y635217D02*
X195876D01*
G01X148110D02*
X165354D01*
G01Y633642D02*
X195876D01*
G01X165354D02*
X148110D01*
G01X165354Y633543D02*
X197638D01*
G01X156693D02*
X161417D01*
G01X158464Y633307D02*
X165354D01*
G01Y630551D02*
X158464D01*
G01X165354Y630315D02*
X197638D01*
G01X161417D02*
X156693D01*
G01X165354Y630217D02*
X195876D01*
G01X148110D02*
X165354D01*
G01Y628642D02*
X195876D01*
G01X165354D02*
X148110D01*
G01X165354Y628543D02*
X197638D01*
G01X156693D02*
X161417D01*
G01X165354Y645040D02*
Y643071D01*
G01D02*
Y641890D01*
G01X163464D02*
Y643071D01*
G01X161890Y641890D02*
Y643071D01*
G01X161417Y640217D02*
Y640315D01*
G01Y638543D02*
Y638642D01*
G01D02*
Y640217D01*
G01Y635217D02*
Y635315D01*
G01Y633543D02*
Y633642D01*
G01D02*
Y635217D01*
G01Y630217D02*
Y630315D01*
G01Y628543D02*
Y628642D01*
G01D02*
Y630217D01*
G01Y625217D02*
Y625315D01*
G01Y623642D02*
Y625217D01*
G01Y623543D02*
Y623642D01*
G01X161102Y643071D02*
Y641890D01*
G01X160708Y643071D02*
Y641890D01*
G01X160630Y643858D02*
Y644252D01*
G01Y640906D02*
Y641103D01*
G01X158464Y633307D02*
Y630551D01*
G01X158149Y641870D02*
Y641706D01*
G01Y643314D02*
Y643182D01*
G01X157982Y643314D02*
Y643182D01*
G01X157948Y641706D02*
Y641890D01*
G01D02*
Y641903D01*
G01X157781Y642100D02*
Y642297D01*
G01X157479Y641890D02*
Y641706D01*
G01Y641903D02*
Y641890D01*
G01X157446Y643182D02*
Y643314D01*
G01X157312D02*
Y643182D01*
G01X157283Y640315D02*
Y640906D01*
G01X157278Y641706D02*
Y641890D01*
G01D02*
Y641903D01*
G01X157010Y641378D02*
Y641181D01*
G01X156776Y641890D02*
Y641640D01*
G01Y641903D02*
Y641890D01*
G01X156742Y643182D02*
Y643314D01*
G01X156575Y643150D02*
Y643347D01*
G01Y641640D02*
Y641890D01*
G01D02*
Y641903D01*
G01X156102Y641890D02*
Y643071D01*
G01X155787Y638642D02*
Y640217D01*
G01Y633642D02*
Y635217D01*
G01Y628642D02*
Y630217D01*
G01Y623642D02*
Y625217D01*
G01X154212Y638642D02*
Y640217D01*
G01Y633642D02*
Y635217D01*
G01Y628642D02*
Y630217D01*
G01Y623642D02*
Y625217D01*
G01X153543Y636496D02*
Y637362D01*
G01Y631496D02*
Y632362D01*
G01Y626496D02*
Y627362D01*
G01X153425Y625217D02*
Y623642D01*
G01Y630217D02*
Y628642D01*
G01Y635217D02*
Y633642D01*
G01Y640217D02*
Y638642D01*
G01X153031Y625217D02*
Y623642D01*
G01Y630217D02*
Y628642D01*
G01Y635217D02*
Y633642D01*
G01Y640217D02*
Y638642D01*
G01X158116Y643478D02*
X158149Y643314D01*
G01X158145Y641890D02*
X158149Y641870D01*
G01X158116Y642034D02*
X158145Y641890D01*
G01X157446Y642067D02*
X157479Y641903D01*
G01X156591Y643071D02*
X156575Y643150D01*
G01X156608Y642986D02*
X156591Y643071D01*
G01X156608Y641477D02*
X156575Y641640D01*
G01X157948Y643445D02*
X157982Y643314D01*
G01X157474Y643071D02*
X157446Y643182D01*
G01X157479Y643051D02*
X157474Y643071D01*
G01X157278Y643445D02*
X157312Y643314D01*
G01X157278Y641903D02*
X157245Y642034D01*
G01X157312Y641575D02*
X157278Y641706D01*
G01X156771Y643071D02*
X156742Y643182D01*
G01X156776Y643051D02*
X156771Y643071D01*
G01X156776Y641640D02*
X156809Y641509D01*
G01X160630Y643858D02*
X162992Y643169D01*
G01X157647Y641280D02*
X157513Y641312D01*
G01X157010Y641181D02*
X156876Y641214D01*
G01X165354Y625315D02*
X197638D01*
G01X161417D02*
X156693D01*
G01X165354Y625217D02*
X195876D01*
G01X148110D02*
X165354D01*
G01Y623642D02*
X195876D01*
G01X165354D02*
X148110D01*
G01X165354Y623543D02*
X197638D01*
G01X156693D02*
X161417D01*
G01X148110Y638642D02*
Y640217D01*
G01Y633642D02*
Y635217D01*
G01Y628642D02*
Y630217D01*
G01Y623642D02*
Y625217D01*
G01X157948Y641903D02*
X157915Y642001D01*
G01X157479Y641706D02*
X157513Y641608D01*
G01X157345Y643642D02*
X157379Y643576D01*
G01X157211D02*
X157278Y643445D01*
G01X157412Y642854D02*
X157379Y642920D01*
G01Y642198D02*
X157446Y642067D01*
G01X156843Y642920D02*
X156776Y643051D01*
G01X157379Y641443D02*
X157312Y641575D01*
G01X158016Y643642D02*
X158116Y643478D01*
G01X156709Y642821D02*
X156608Y642986D01*
G01X156709Y641312D02*
X156608Y641477D01*
G01X157245Y642034D02*
X157178Y642132D01*
G01X157513Y641608D02*
X157580Y641509D01*
G01X157848Y643576D02*
X157948Y643445D01*
G01X157245Y643773D02*
X157345Y643642D01*
G01X157580Y642920D02*
X157479Y643051D01*
G01X158016Y642166D02*
X158116Y642034D01*
G01X157915Y643740D02*
X158016Y643642D01*
G01X157513Y642756D02*
X157412Y642854D01*
G01X157915Y642001D02*
X157848Y642067D01*
G01X157245Y642329D02*
X157379Y642198D01*
G01X156809Y642723D02*
X156709Y642821D01*
G01X157513Y641312D02*
X157379Y641443D01*
G01X156809Y641509D02*
X156910Y641411D01*
G01X157077Y643675D02*
X157211Y643576D01*
G01X157881Y642264D02*
X158016Y642166D01*
G01X156977Y642821D02*
X156843Y642920D01*
G01X157747Y643642D02*
X157848Y643576D01*
G01X157680Y642854D02*
X157580Y642920D01*
G01X157178Y642132D02*
X157077Y642198D01*
G01X156876Y641214D02*
X156709Y641312D01*
G01X157647Y642690D02*
X157513Y642756D01*
G01X157848Y642067D02*
X157781Y642100D01*
G01X157111Y642395D02*
X157245Y642329D01*
G01X157747Y643806D02*
X157915Y643740D01*
G01X157077Y643839D02*
X157245Y643773D01*
G01X156977Y642658D02*
X156809Y642723D01*
G01X153543Y636496D02*
X156693Y635315D01*
G01X153543Y631496D02*
X156693Y630315D01*
G01X153543Y626496D02*
X156693Y625315D01*
G01X157781Y642297D02*
X157881Y642264D01*
G01X157580Y641509D02*
X157680Y641477D01*
G01X156910Y641411D02*
X157010Y641378D01*
G01X162992Y648091D02*
X160630Y647402D01*
G01X162992Y651240D02*
X160630Y650551D01*
G01X162992Y654390D02*
X160630Y653701D01*
G01X162992Y657540D02*
X160630Y656851D01*
G01X162992Y660689D02*
X160630Y660000D01*
G01X150336Y664488D02*
X150436Y664521D01*
G01X150403Y664718D02*
X150302Y664685D01*
G01D02*
X150168Y664587D01*
G01X150671Y664980D02*
X150905Y665177D01*
G01X150637D02*
X150403Y664980D01*
G01X150269Y664423D02*
X150336Y664488D01*
G01X150168Y664587D02*
X150067Y664455D01*
G01X150235Y664324D02*
X150269Y664423D01*
G01X150905Y665374D02*
X149330D01*
G01X165354Y665315D02*
X194685D01*
G01X161417D02*
X156693D01*
G01X165354Y665217D02*
X195756D01*
G01X146653D02*
X165354D01*
G01X149330Y665177D02*
X150637D01*
G01X150403Y664980D02*
X150671D01*
G01X150537Y664718D02*
X150403D01*
G01X150436Y664521D02*
X150537D01*
G01X165354Y664134D02*
X197638D01*
G01X150738Y663701D02*
X150235D01*
G01X150034D02*
X149330D01*
G01X165354Y663642D02*
X195756D01*
G01X146653D02*
X165354D01*
G01Y663543D02*
X194685D01*
G01X157283D02*
X161417D01*
G01X149330Y663504D02*
X150905D01*
G01X160630Y662953D02*
X157283D01*
G01X162992Y662067D02*
X165354D01*
G01X156102Y661969D02*
X168110D01*
G01X156102Y660788D02*
X168110D01*
G01X162992Y660689D02*
X165354D01*
G01X162992Y658917D02*
X165354D01*
G01X156102Y658819D02*
X168110D01*
G01X156102Y657638D02*
X168110D01*
G01X162992Y657540D02*
X165354D01*
G01X162992Y655768D02*
X165354D01*
G01X156102Y655669D02*
X168110D01*
G01X156102Y654488D02*
X168110D01*
G01X162992Y654390D02*
X165354D01*
G01X162992Y652618D02*
X165354D01*
G01X156102Y652520D02*
X168110D01*
G01X156102Y651339D02*
X168110D01*
G01X162992Y651240D02*
X165354D01*
G01X162992Y649469D02*
X165354D01*
G01X156102Y649370D02*
X168110D01*
G01X156102Y648189D02*
X168110D01*
G01X162992Y648091D02*
X165354D01*
G01X162992Y646319D02*
X165354D01*
G01X156102Y646221D02*
X168110D01*
G01X156102Y645040D02*
X168110D01*
G01X162992Y644941D02*
X165354D01*
G01X150067Y664455D02*
X150034Y664291D01*
G01X165354Y661969D02*
Y678642D01*
G01Y646221D02*
Y645040D01*
G01Y648189D02*
Y646221D01*
G01Y651339D02*
Y649370D01*
G01D02*
Y648189D01*
G01Y654488D02*
Y652520D01*
G01D02*
Y651339D01*
G01Y655669D02*
Y654488D01*
G01Y657638D02*
Y655669D01*
G01Y660788D02*
Y658819D01*
G01D02*
Y657638D01*
G01Y661969D02*
Y660788D01*
G01X163464D02*
Y661969D01*
G01Y657638D02*
Y658819D01*
G01Y654488D02*
Y655669D01*
G01Y651339D02*
Y652520D01*
G01Y648189D02*
Y649370D01*
G01Y645040D02*
Y646221D01*
G01X161890Y660788D02*
Y661969D01*
G01Y657638D02*
Y658819D01*
G01Y654488D02*
Y655669D01*
G01Y651339D02*
Y652520D01*
G01Y648189D02*
Y649370D01*
G01Y645040D02*
Y646221D01*
G01X161417Y665217D02*
Y665315D01*
G01Y663543D02*
Y663642D01*
G01D02*
Y665217D01*
G01X161102Y646221D02*
Y645040D01*
G01Y649370D02*
Y648189D01*
G01Y652520D02*
Y651339D01*
G01Y655669D02*
Y654488D01*
G01Y658819D02*
Y657638D01*
G01Y661969D02*
Y660788D01*
G01X160708Y646221D02*
Y645040D01*
G01Y649370D02*
Y648189D01*
G01Y655669D02*
Y654488D01*
G01Y652520D02*
Y651339D01*
G01Y658819D02*
Y657638D01*
G01Y661969D02*
Y660788D01*
G01X160630Y662756D02*
Y662953D01*
G01Y656457D02*
Y656851D01*
G01Y659606D02*
Y660000D01*
G01Y653307D02*
Y653701D01*
G01Y647008D02*
Y647402D01*
G01Y650158D02*
Y650551D01*
G01X157283Y662953D02*
Y663543D01*
G01X156102Y660788D02*
Y661969D01*
G01Y657638D02*
Y658819D01*
G01Y651339D02*
Y652520D01*
G01Y654488D02*
Y655669D01*
G01Y648189D02*
Y649370D01*
G01Y645040D02*
Y646221D01*
G01X155787Y663642D02*
Y665217D01*
G01X154212Y663642D02*
Y665217D01*
G01X153425D02*
Y663642D01*
G01X153031Y665217D02*
Y663642D01*
G01X150905Y665217D02*
Y665374D01*
G01Y663504D02*
Y663642D01*
G01Y665177D02*
Y665217D01*
G01Y663642D02*
Y664291D01*
G01X150738Y664324D02*
Y663701D01*
G01X150235D02*
Y664324D01*
G01X150034Y664291D02*
Y663701D01*
G01X149330Y665374D02*
Y665217D01*
G01Y663642D02*
Y663504D01*
G01Y665217D02*
Y665177D01*
G01Y663701D02*
Y663642D01*
G01X150905Y664291D02*
X150872Y664455D01*
G01X153543Y666496D02*
X156693Y665315D01*
G01X150637Y664685D02*
X150537Y664718D01*
G01Y664521D02*
X150637Y664488D01*
G01X160630Y662756D02*
X162992Y662067D01*
G01X160630Y659606D02*
X162992Y658917D01*
G01X160630Y656457D02*
X162992Y655768D01*
G01X160630Y653307D02*
X162992Y652618D01*
G01X160630Y650158D02*
X162992Y649469D01*
G01X160630Y647008D02*
X162992Y646319D01*
G01X146653Y663642D02*
Y665217D01*
G01X150704Y664423D02*
X150738Y664324D01*
G01X150872Y664455D02*
X150771Y664587D01*
G01X150637Y664488D02*
X150704Y664423D01*
G01X150771Y664587D02*
X150637Y664685D01*
G01X156693Y668543D02*
X153543Y667362D01*
G01X156693Y673543D02*
X153543Y672362D01*
G01X156693Y683543D02*
X153543Y682362D01*
G01X158661Y678543D02*
X153543Y677362D01*
G01X165354Y685315D02*
X197638D01*
G01X161417D02*
X156693D01*
G01X165354Y685217D02*
X195876D01*
G01X148110D02*
X165354D01*
G01Y683642D02*
X195876D01*
G01X165354D02*
X148110D01*
G01X165354Y683543D02*
X197638D01*
G01X156693D02*
X161417D01*
G01X166535Y681791D02*
X165354D01*
G01X163386Y680315D02*
X158661D01*
G01X197638D02*
X166535D01*
G01Y680217D02*
X195876D01*
G01X146653D02*
X166535D01*
G01Y678642D02*
X195876D01*
G01X146653D02*
X166535D01*
G01Y678543D02*
X197638D01*
G01X158661D02*
X163386D01*
G01X165354Y677067D02*
X166535D01*
G01X165354Y675315D02*
X197638D01*
G01X161417D02*
X156693D01*
G01X165354Y675217D02*
X195876D01*
G01X148110D02*
X165354D01*
G01Y673642D02*
X195876D01*
G01X165354D02*
X148110D01*
G01X165354Y673543D02*
X197638D01*
G01X156693D02*
X161417D01*
G01X165354Y670315D02*
X197638D01*
G01X161417D02*
X156693D01*
G01X165354Y670217D02*
X195876D01*
G01X148110D02*
X165354D01*
G01Y668642D02*
X148110D01*
G01X195876D02*
X165354D01*
G01Y668543D02*
X197638D01*
G01X156693D02*
X161417D01*
G01X158464Y668307D02*
X165354D01*
G01Y665551D02*
X158464D01*
G01X166535Y677067D02*
Y681791D01*
G01X165354Y680217D02*
Y718642D01*
G01Y680217D02*
Y678642D01*
G01X163386Y680217D02*
Y680315D01*
G01Y678642D02*
Y680217D01*
G01Y678543D02*
Y678642D01*
G01X161417Y685217D02*
Y685315D01*
G01Y683642D02*
Y685217D01*
G01Y683543D02*
Y683642D01*
G01Y675217D02*
Y675315D01*
G01Y673543D02*
Y673642D01*
G01D02*
Y675217D01*
G01Y670217D02*
Y670315D01*
G01Y668543D02*
Y668642D01*
G01D02*
Y670217D01*
G01X158464Y668307D02*
Y665551D01*
G01X155787Y683642D02*
Y685217D01*
G01Y678642D02*
Y680217D01*
G01Y673642D02*
Y675217D01*
G01Y668642D02*
Y670217D01*
G01X154212Y683642D02*
Y685217D01*
G01Y678642D02*
Y680217D01*
G01Y673642D02*
Y675217D01*
G01Y668642D02*
Y670217D01*
G01X153543Y686496D02*
Y687362D01*
G01Y681496D02*
Y682362D01*
G01Y676496D02*
Y677362D01*
G01Y671496D02*
Y672362D01*
G01Y666496D02*
Y667362D01*
G01X153425Y670217D02*
Y668642D01*
G01Y675217D02*
Y673642D01*
G01Y680217D02*
Y678642D01*
G01Y685217D02*
Y683642D01*
G01X153031Y670217D02*
Y668642D01*
G01Y675217D02*
Y673642D01*
G01Y680217D02*
Y678642D01*
G01Y685217D02*
Y683642D01*
G01X153543Y686496D02*
X156693Y685315D01*
G01X153543Y676496D02*
X156693Y675315D01*
G01X153543Y671496D02*
X156693Y670315D01*
G01X153543Y681496D02*
X158661Y680315D01*
G01X148110Y683642D02*
Y685217D01*
G01Y673642D02*
Y675217D01*
G01Y668642D02*
Y670217D01*
G01X146653Y678642D02*
Y680217D01*
G01X156693Y688543D02*
X153543Y687362D01*
G01X156693Y693543D02*
X153543Y692362D01*
G01X156693Y698543D02*
X153543Y697362D01*
G01X156693Y703543D02*
X153543Y702362D01*
G01X156693Y708543D02*
X153543Y707362D01*
G01X165354Y705315D02*
X197638D01*
G01X161417D02*
X156693D01*
G01X165354Y705217D02*
X195876D01*
G01X148110D02*
X165354D01*
G01Y703642D02*
X195876D01*
G01X165354D02*
X148110D01*
G01X165354Y703543D02*
X197638D01*
G01X156693D02*
X161417D01*
G01X165354Y700315D02*
X197638D01*
G01X161417D02*
X156693D01*
G01X165354Y700217D02*
X195876D01*
G01X148110D02*
X165354D01*
G01Y698642D02*
X195876D01*
G01X165354D02*
X148110D01*
G01X165354Y698543D02*
X197638D01*
G01X156693D02*
X161417D01*
G01X165354Y695315D02*
X197638D01*
G01X161417D02*
X156693D01*
G01X165354Y695217D02*
X195876D01*
G01X148110D02*
X165354D01*
G01Y693642D02*
X195876D01*
G01X165354D02*
X148110D01*
G01X165354Y693543D02*
X197638D01*
G01X156693D02*
X161417D01*
G01X158464Y693307D02*
X165354D01*
G01Y690551D02*
X158464D01*
G01X165354Y690315D02*
X197638D01*
G01X161417D02*
X156693D01*
G01X165354Y690217D02*
X195876D01*
G01X148110D02*
X165354D01*
G01Y688642D02*
X195876D01*
G01X165354D02*
X148110D01*
G01X165354Y688543D02*
X197638D01*
G01X156693D02*
X161417D01*
G01Y705217D02*
Y705315D01*
G01Y703543D02*
Y703642D01*
G01D02*
Y705217D01*
G01Y700217D02*
Y700315D01*
G01Y698642D02*
Y700217D01*
G01Y698543D02*
Y698642D01*
G01Y695217D02*
Y695315D01*
G01Y693642D02*
Y695217D01*
G01Y693543D02*
Y693642D01*
G01Y690217D02*
Y690315D01*
G01Y688642D02*
Y690217D01*
G01Y688543D02*
Y688642D01*
G01X158464Y693307D02*
Y690551D01*
G01X155787Y703642D02*
Y705217D01*
G01Y698642D02*
Y700217D01*
G01Y693642D02*
Y695217D01*
G01Y688642D02*
Y690217D01*
G01X154212Y703642D02*
Y705217D01*
G01Y698642D02*
Y700217D01*
G01Y693642D02*
Y695217D01*
G01Y688642D02*
Y690217D01*
G01X153543Y706496D02*
Y707362D01*
G01Y701496D02*
Y702362D01*
G01Y696496D02*
Y697362D01*
G01Y691496D02*
Y692362D01*
G01X153425Y690217D02*
Y688642D01*
G01Y695217D02*
Y693642D01*
G01Y700217D02*
Y698642D01*
G01Y705217D02*
Y703642D01*
G01X153031Y690217D02*
Y688642D01*
G01Y695217D02*
Y693642D01*
G01Y700217D02*
Y698642D01*
G01Y705217D02*
Y703642D01*
G01X153543Y706496D02*
X156693Y705315D01*
G01X153543Y701496D02*
X156693Y700315D01*
G01X153543Y696496D02*
X156693Y695315D01*
G01X153543Y691496D02*
X156693Y690315D01*
G01X148110Y703642D02*
Y705217D01*
G01Y698642D02*
Y700217D01*
G01Y693642D02*
Y695217D01*
G01Y688642D02*
Y690217D01*
G01X156693Y713543D02*
X153543Y712362D01*
G01X156693Y723543D02*
X153543Y722362D01*
G01X156693Y728543D02*
X153543Y727362D01*
G01X158661Y718543D02*
X153543Y717362D01*
G01X165354Y728642D02*
X195876D01*
G01X165354D02*
X148110D01*
G01X165354Y728543D02*
X197638D01*
G01X156693D02*
X161417D01*
G01X165354Y725315D02*
X197638D01*
G01X161417D02*
X156693D01*
G01X165354Y725217D02*
X195876D01*
G01X148110D02*
X165354D01*
G01Y723642D02*
X195876D01*
G01X165354D02*
X148110D01*
G01X165354Y723543D02*
X197638D01*
G01X156693D02*
X161417D01*
G01X166535Y721791D02*
X165354D01*
G01X163386Y720315D02*
X158661D01*
G01X197638D02*
X166535D01*
G01Y720217D02*
X195876D01*
G01X146653D02*
X166535D01*
G01Y718642D02*
X195876D01*
G01X146653D02*
X166535D01*
G01Y718543D02*
X197638D01*
G01X158661D02*
X163386D01*
G01X158464Y718307D02*
X165354D01*
G01Y717067D02*
X166535D01*
G01X165354Y715551D02*
X158464D01*
G01X165354Y715315D02*
X197638D01*
G01X161417D02*
X156693D01*
G01X165354Y715217D02*
X195876D01*
G01X148110D02*
X165354D01*
G01Y713642D02*
X195876D01*
G01X165354D02*
X148110D01*
G01X165354Y713543D02*
X197638D01*
G01X156693D02*
X161417D01*
G01X165354Y710315D02*
X197638D01*
G01X161417D02*
X156693D01*
G01X165354Y710217D02*
X195876D01*
G01X148110D02*
X165354D01*
G01Y708642D02*
X195876D01*
G01X165354D02*
X148110D01*
G01X165354Y708543D02*
X197638D01*
G01X156693D02*
X161417D01*
G01X153543Y721496D02*
X158661Y720315D01*
G01X166535Y717067D02*
Y721791D01*
G01X165354Y720217D02*
Y740020D01*
G01Y720217D02*
Y718642D01*
G01X163386Y720217D02*
Y720315D01*
G01Y718543D02*
Y718642D01*
G01D02*
Y720217D01*
G01X161417Y728543D02*
Y728642D01*
G01D02*
Y730217D01*
G01Y725217D02*
Y725315D01*
G01Y723543D02*
Y723642D01*
G01D02*
Y725217D01*
G01Y715217D02*
Y715315D01*
G01Y713543D02*
Y713642D01*
G01D02*
Y715217D01*
G01Y710217D02*
Y710315D01*
G01Y708543D02*
Y708642D01*
G01D02*
Y710217D01*
G01X158464Y718307D02*
Y715551D01*
G01X155787Y728642D02*
Y730217D01*
G01Y723642D02*
Y725217D01*
G01Y718642D02*
Y720217D01*
G01Y713642D02*
Y715217D01*
G01Y708642D02*
Y710217D01*
G01X154212Y728642D02*
Y730217D01*
G01Y723642D02*
Y725217D01*
G01Y718642D02*
Y720217D01*
G01Y713642D02*
Y715217D01*
G01Y708642D02*
Y710217D01*
G01X153543Y726496D02*
Y727362D01*
G01Y721496D02*
Y722362D01*
G01Y716496D02*
Y717362D01*
G01Y711496D02*
Y712362D01*
G01X153425Y710217D02*
Y708642D01*
G01Y715217D02*
Y713642D01*
G01Y720217D02*
Y718642D01*
G01Y725217D02*
Y723642D01*
G01Y730217D02*
Y728642D01*
G01X153031Y710217D02*
Y708642D01*
G01Y715217D02*
Y713642D01*
G01Y720217D02*
Y718642D01*
G01Y725217D02*
Y723642D01*
G01Y730217D02*
Y728642D01*
G01X153543Y726496D02*
X156693Y725315D01*
G01X153543Y716496D02*
X156693Y715315D01*
G01X153543Y711496D02*
X156693Y710315D01*
G01X148110Y728642D02*
Y730217D01*
G01Y723642D02*
Y725217D01*
G01Y713642D02*
Y715217D01*
G01Y708642D02*
Y710217D01*
G01X146653Y718642D02*
Y720217D01*
G01X160325Y744643D02*
X160441Y744370D01*
G01X160207Y744905D02*
X160325Y744643D01*
G01X160088Y745158D02*
X160207Y744905D01*
G01X155939Y748549D02*
X156054Y748307D01*
G01X155821Y748812D02*
X155939Y748549D01*
G01X155700Y749095D02*
X155821Y748812D01*
G01X155700Y744369D02*
Y744370D01*
G01X155698Y744365D02*
X155700Y744369D01*
G01X155674Y744306D02*
X155698Y744365D01*
G01X160442Y749096D02*
X160441Y749095D01*
G01X160443Y749100D02*
X160442Y749096D01*
G01X160467Y749158D02*
X160443Y749100D01*
G01X155934Y744905D02*
X156054Y745158D01*
G01X155816Y744643D02*
X155934Y744905D01*
G01X155700Y744370D02*
X155816Y744643D01*
G01X160321Y748812D02*
X160441Y749095D01*
G01X160203Y748549D02*
X160321Y748812D01*
G01X160088Y748307D02*
X160203Y748549D01*
G01X156054Y748307D02*
G03Y745158I2017J-1574D01*
G01X160088D02*
G03Y748307I-2017J1574D01*
G01X155700Y749095D02*
G03Y744370I2370J-2363D01*
G01X160441D02*
G03Y749095I-2370J2363D01*
G01X161575Y746732D02*
G03I-3504J0D01*
G01X160748Y743583D02*
G03Y749882I-2677J3149D01*
G01X155393D02*
G03Y743583I2678J-3150D01*
G01X156693Y733543D02*
X153543Y732362D01*
G01X155393Y749882D02*
X160748D01*
G01X160441Y749095D02*
X155700D01*
G01X156054Y748307D02*
X160088D01*
G01X166142Y746122D02*
X145669D01*
G01X177165D02*
X166142D01*
G01X156054Y745158D02*
X160088D01*
G01X155700Y744370D02*
X160441D01*
G01X160748Y743583D02*
X155393D01*
G01X195669Y743169D02*
X145669D01*
G01X165354Y740020D02*
X145669D01*
G01Y738248D02*
X165354D01*
G01D02*
X166634D01*
G01X161417Y735315D02*
X156693D01*
G01X197638D02*
X165354D01*
G01Y735217D02*
X195876D01*
G01X148110D02*
X165354D01*
G01Y733642D02*
X195876D01*
G01X165354D02*
X148110D01*
G01X165354Y733543D02*
X197638D01*
G01X156693D02*
X161417D01*
G01X165354Y730315D02*
X197638D01*
G01X161417D02*
X156693D01*
G01X165354Y730217D02*
X195876D01*
G01X148110D02*
X165354D01*
G01X160506Y749252D02*
X160467Y749158D01*
G01X155636Y744213D02*
X155674Y744306D01*
G01X160589Y749460D02*
X160506Y749252D01*
G01X155553Y744004D02*
X155636Y744213D01*
G01X160623Y749546D02*
X160589Y749460D01*
G01X155519Y743918D02*
X155553Y744004D01*
G01X160658Y749638D02*
X160623Y749546D01*
G01X155484Y743827D02*
X155519Y743918D01*
G01X160693Y749734D02*
X160658Y749638D01*
G01X155448Y743731D02*
X155484Y743827D01*
G01X160748Y749882D02*
X160693Y749734D01*
G01X155393Y743583D02*
X155448Y743731D01*
G01X166142Y743169D02*
Y751516D01*
G01X161417Y735217D02*
Y735315D01*
G01Y733543D02*
Y733642D01*
G01D02*
Y735217D01*
G01Y730217D02*
Y730315D01*
G01X155787Y733642D02*
Y735217D01*
G01X154212Y733642D02*
Y735217D01*
G01X153543Y736496D02*
Y738248D01*
G01Y731496D02*
Y732362D01*
G01X153425Y735217D02*
Y733642D01*
G01X153031Y735217D02*
Y733642D01*
G01X160693Y743731D02*
X160748Y743583D01*
G01X155448Y749734D02*
X155393Y749882D01*
G01X160658Y743827D02*
X160693Y743731D01*
G01X155484Y749638D02*
X155448Y749734D01*
G01X160623Y743918D02*
X160658Y743827D01*
G01X155519Y749547D02*
X155484Y749638D01*
G01X160589Y744004D02*
X160623Y743918D01*
G01X155552Y749460D02*
X155519Y749547D01*
G01X160517Y744183D02*
X160589Y744004D01*
G01X155624Y749281D02*
X155552Y749460D01*
G01X160484Y744264D02*
X160517Y744183D01*
G01X155657Y749200D02*
X155624Y749281D01*
G01X160441Y744370D02*
X160484Y744264D01*
G01X155700Y749095D02*
X155657Y749200D01*
G01X153543Y736496D02*
X156693Y735315D01*
G01X153543Y731496D02*
X156693Y730315D01*
G01X148110Y733642D02*
Y735217D01*
G01X145669Y738248D02*
Y751516D01*
G01X171063Y758543D02*
G03I-3740J0D01*
G01X153543Y768406D02*
X181102D01*
G01X177165Y764469D02*
X157480D01*
G01X177165Y762500D02*
X157480D01*
G01X177165Y760512D02*
X157480D01*
G01Y759528D02*
X177165D01*
G01X176968Y759331D02*
X157677D01*
G01X176968Y757756D02*
X157677D01*
G01X177165Y757559D02*
X157480D01*
G01Y756575D02*
X177165D01*
G01Y753484D02*
X157480D01*
G01X199606Y751516D02*
X145669D01*
G01X166142Y750335D02*
X199606D01*
G01X166142Y759331D02*
Y757756D01*
G01X164567D02*
Y759331D01*
G01X164370D02*
Y759528D01*
G01Y757756D02*
Y759331D01*
G01Y757756D02*
Y757559D01*
G01X163031Y757756D02*
Y759331D01*
G01X157677D02*
Y757756D01*
G01X157480Y751516D02*
Y764469D01*
G01X153543Y755453D02*
Y768406D01*
G01X164173Y973858D02*
G03Y975040I0J591D01*
G01Y971103D02*
G03Y972284I0J590D01*
G01X181102Y980965D02*
X153543D01*
G01X164173Y975630D02*
X170472D01*
G01X164173Y975335D02*
X162598D01*
G01X165748D02*
X164173D01*
G01X162598Y973366D02*
X164173D01*
G01D02*
X165748D01*
G01X162598Y972776D02*
X164173D01*
G01D02*
X165748D01*
G01X164173Y970807D02*
X162598D01*
G01X165748D02*
X164173D01*
G01Y970512D02*
X170472D01*
G01X165748Y973366D02*
Y975335D01*
G01Y972776D02*
Y970807D01*
G01X165354Y970512D02*
Y975630D01*
G01X165157D02*
Y970512D01*
G01X164173Y973858D02*
Y972284D01*
G01Y971103D02*
Y970512D01*
G01Y975630D02*
Y975040D01*
G01X162598Y970807D02*
Y972776D01*
G01Y975335D02*
Y973366D01*
G01X153543Y980965D02*
Y993917D01*
G01X160630Y1002638D02*
G03I-2559J0D01*
G01X161417D02*
G03I-3346J0D01*
G01X161575D02*
G03I-3504J0D01*
G01X158145Y998504D02*
G03X158071Y1006772I-74J4134D01*
G01X157996Y1006771D02*
G03X158071Y998504I73J-4133D01*
G01X171063Y990827D02*
G03I-3740J0D01*
G01X166142Y1003248D02*
X177165D01*
G01X145669D02*
X166142D01*
G01X199606Y999036D02*
X166142D01*
G01X199606Y997854D02*
X145669D01*
G01X157480Y995886D02*
X177165D01*
G01Y992795D02*
X157480D01*
G01Y991811D02*
X177165D01*
G01X176968Y991614D02*
X157677D01*
G01X176968Y990040D02*
X157677D01*
G01X177165Y989843D02*
X157480D01*
G01Y988858D02*
X177165D01*
G01X157480Y986870D02*
X177165D01*
G01X157480Y984902D02*
X177165D01*
G01X158145Y998504D02*
X158071D01*
G01X166142Y997854D02*
Y1006201D01*
G01Y991614D02*
Y990040D01*
G01X164567D02*
Y991614D01*
G01X164370D02*
Y991811D01*
G01Y990040D02*
Y991614D01*
G01Y990040D02*
Y989843D01*
G01X163031Y990040D02*
Y991614D01*
G01X157677D02*
Y990040D01*
G01X157480Y984902D02*
Y997854D01*
G01X145669D02*
Y1011122D01*
G01X150631Y1014108D02*
X150497Y1014075D01*
G01X165354Y1024154D02*
X195876D01*
G01X165354D02*
X148110D01*
G01X165354Y1024055D02*
X197638D01*
G01X156693D02*
X161417D01*
G01X165354Y1020827D02*
X197638D01*
G01X161417D02*
X156693D01*
G01X165354Y1020728D02*
X195876D01*
G01X148110D02*
X165354D01*
G01Y1019154D02*
X195876D01*
G01X165354D02*
X148110D01*
G01X165354Y1019055D02*
X197638D01*
G01X156693D02*
X161417D01*
G01X150866Y1015847D02*
X149291D01*
G01X165354Y1015827D02*
X197638D01*
G01X161417D02*
X156693D01*
G01X165354Y1015728D02*
X195876D01*
G01X148110D02*
X165354D01*
G01X149291Y1015650D02*
X150598D01*
G01X150364Y1015453D02*
X150631D01*
G01X149660Y1015190D02*
X149827D01*
G01X149794Y1014993D02*
X149693D01*
G01X150397Y1014272D02*
X150464D01*
G01X165354Y1014154D02*
X195876D01*
G01X165354D02*
X148110D01*
G01X150497Y1014075D02*
X150364D01*
G01X165354Y1014055D02*
X197638D01*
G01X156693D02*
X161417D01*
G01X165354Y1011122D02*
X166634D01*
G01X165354D02*
X145669D01*
G01Y1009351D02*
X165354D01*
G01X157996Y1006771D02*
X158071D01*
G01X145669Y1006201D02*
X195669D01*
G01X153543Y1022008D02*
X156693Y1020827D01*
G01X153543Y1017008D02*
X156693Y1015827D01*
G01X150497Y1015092D02*
X150598Y1015059D01*
G01X150296Y1014304D02*
X150397Y1014272D01*
G01X149626Y1014206D02*
X149727Y1014173D01*
G01X150364Y1014075D02*
X150229Y1014108D01*
G01X149727Y1013977D02*
X149593Y1014009D01*
G01X150464Y1014272D02*
X150564Y1014304D01*
G01X150598Y1015059D02*
X150732Y1014961D01*
G01X149894Y1014928D02*
X149794Y1014993D01*
G01X149593Y1014009D02*
X149425Y1014108D01*
G01X150564Y1014862D02*
X150497Y1014895D01*
G01X149827Y1015190D02*
X149961Y1015125D01*
G01X156693Y1014055D02*
X153543Y1012874D01*
G01X156693Y1019055D02*
X153543Y1017874D01*
G01X156693Y1024055D02*
X153543Y1022874D01*
G01X149526Y1015125D02*
X149660Y1015190D01*
G01X149693Y1014993D02*
X149593Y1014928D01*
G01X150732Y1014961D02*
X150832Y1014829D01*
G01X150631Y1014797D02*
X150564Y1014862D01*
G01X149961Y1015125D02*
X150095Y1014993D01*
G01X150229Y1014108D02*
X150182Y1014154D01*
G01D02*
X150095Y1014239D01*
G01X149526Y1014304D02*
X149626Y1014206D01*
G01X150631Y1015453D02*
X150866Y1015650D01*
G01X150598D02*
X150364Y1015453D01*
G01X150679Y1014154D02*
X150631Y1014108D01*
G01X150766Y1014239D02*
X150679Y1014154D01*
G01X149392Y1014993D02*
X149526Y1015125D01*
G01X150832Y1014829D02*
X150866Y1014666D01*
G01X150162Y1014862D02*
X150196Y1014698D01*
G01X149325Y1014272D02*
X149291Y1014436D01*
G01X149995Y1014698D02*
X149961Y1014829D01*
G01X150028Y1014370D02*
X149995Y1014501D01*
G01X149492Y1014436D02*
X149526Y1014304D01*
G01X150665Y1014698D02*
X150631Y1014797D01*
G01X150196Y1014501D02*
X150229Y1014403D01*
G01X150095Y1014993D02*
X150162Y1014862D01*
G01X150095Y1014239D02*
X150028Y1014370D01*
G01X149425Y1014108D02*
X149397Y1014154D01*
G01D02*
X149325Y1014272D01*
G01X149961Y1014829D02*
X149894Y1014928D01*
G01X150229Y1014403D02*
X150296Y1014304D01*
G01X150564D02*
X150631Y1014403D01*
G01X149593Y1014928D02*
X149526Y1014829D01*
G01X150832Y1014370D02*
X150766Y1014239D01*
G01X149325Y1014862D02*
X149392Y1014993D01*
G01X150631Y1014403D02*
X150665Y1014501D01*
G01X150866D02*
X150832Y1014370D01*
G01X149526Y1014829D02*
X149492Y1014698D01*
G01X149291D02*
X149325Y1014862D01*
G01X166634Y1143760D02*
Y1011122D01*
G01X165354Y1009351D02*
Y1047402D01*
G01X161417Y1024055D02*
Y1024154D01*
G01D02*
Y1025728D01*
G01Y1020728D02*
Y1020827D01*
G01Y1019055D02*
Y1019154D01*
G01D02*
Y1020728D01*
G01Y1015728D02*
Y1015827D01*
G01Y1014055D02*
Y1014154D01*
G01D02*
Y1015728D01*
G01X155787Y1024154D02*
Y1025728D01*
G01Y1019154D02*
Y1020728D01*
G01Y1014154D02*
Y1015728D01*
G01X154212Y1024154D02*
Y1025728D01*
G01Y1019154D02*
Y1020728D01*
G01Y1014154D02*
Y1015728D01*
G01X153543Y1022008D02*
Y1022874D01*
G01Y1017008D02*
Y1017874D01*
G01Y1011122D02*
Y1012874D01*
G01X153425Y1015728D02*
Y1014154D01*
G01Y1020728D02*
Y1019154D01*
G01Y1025728D02*
Y1024154D01*
G01X153031Y1015728D02*
Y1014154D01*
G01Y1020728D02*
Y1019154D01*
G01Y1025728D02*
Y1024154D01*
G01X150866Y1015728D02*
Y1015847D01*
G01Y1015650D02*
Y1015728D01*
G01Y1014666D02*
Y1014501D01*
G01X150665D02*
Y1014698D01*
G01X150497Y1014895D02*
Y1015092D01*
G01X150196Y1014698D02*
Y1014501D01*
G01X149995D02*
Y1014698D01*
G01X149727Y1014154D02*
Y1013977D01*
G01Y1014173D02*
Y1014154D01*
G01X149492Y1014698D02*
Y1014436D01*
G01X149291D02*
Y1014698D01*
G01Y1015847D02*
Y1015728D01*
G01D02*
Y1015650D01*
G01X148110Y1024154D02*
Y1025728D01*
G01Y1019154D02*
Y1020728D01*
G01Y1014154D02*
Y1015728D01*
G01X161417Y1045827D02*
X157283D01*
G01X194685D02*
X165354D01*
G01Y1045728D02*
X195756D01*
G01X148110D02*
X165354D01*
G01Y1045236D02*
X197638D01*
G01X165354Y1044154D02*
X148110D01*
G01X195756D02*
X165354D01*
G01Y1044055D02*
X194685D01*
G01X156693D02*
X161417D01*
G01Y1040827D02*
X156693D01*
G01X197638D02*
X165354D01*
G01Y1040728D02*
X195876D01*
G01X148110D02*
X165354D01*
G01Y1039154D02*
X195876D01*
G01X165354D02*
X148110D01*
G01X165354Y1039055D02*
X197638D01*
G01X156693D02*
X161417D01*
G01X158464Y1038819D02*
X165354D01*
G01Y1036063D02*
X158464D01*
G01X165354Y1035827D02*
X197638D01*
G01X161417D02*
X156693D01*
G01X165354Y1035728D02*
X195876D01*
G01X148110D02*
X165354D01*
G01Y1034154D02*
X195876D01*
G01X165354D02*
X148110D01*
G01X165354Y1034055D02*
X197638D01*
G01X156693D02*
X161417D01*
G01X165354Y1030827D02*
X197638D01*
G01X161417D02*
X156693D01*
G01X165354Y1030728D02*
X195876D01*
G01X148110D02*
X165354D01*
G01Y1029154D02*
X195876D01*
G01X165354D02*
X148110D01*
G01X165354Y1029055D02*
X197638D01*
G01X156693D02*
X161417D01*
G01X165354Y1025827D02*
X197638D01*
G01X161417D02*
X156693D01*
G01X165354Y1025728D02*
X195876D01*
G01X148110D02*
X165354D01*
G01X153543Y1042008D02*
X156693Y1040827D01*
G01X153543Y1037008D02*
X156693Y1035827D01*
G01X153543Y1032008D02*
X156693Y1030827D01*
G01X153543Y1027008D02*
X156693Y1025827D01*
G01Y1029055D02*
X153543Y1027874D01*
G01X156693Y1034055D02*
X153543Y1032874D01*
G01X156693Y1039055D02*
X153543Y1037874D01*
G01X156693Y1044055D02*
X153543Y1042874D01*
G01X161417Y1045728D02*
Y1045827D01*
G01Y1044154D02*
Y1045728D01*
G01Y1044055D02*
Y1044154D01*
G01Y1040728D02*
Y1040827D01*
G01Y1039154D02*
Y1040728D01*
G01Y1039055D02*
Y1039154D01*
G01Y1035728D02*
Y1035827D01*
G01Y1034055D02*
Y1034154D01*
G01D02*
Y1035728D01*
G01Y1030728D02*
Y1030827D01*
G01Y1029055D02*
Y1029154D01*
G01D02*
Y1030728D01*
G01Y1025728D02*
Y1025827D01*
G01X158464Y1038819D02*
Y1036063D01*
G01X157283Y1045827D02*
Y1046417D01*
G01X155787Y1044154D02*
Y1045728D01*
G01Y1039154D02*
Y1040728D01*
G01Y1034154D02*
Y1035728D01*
G01Y1029154D02*
Y1030728D01*
G01X154212Y1044154D02*
Y1045728D01*
G01Y1039154D02*
Y1040728D01*
G01Y1034154D02*
Y1035728D01*
G01Y1029154D02*
Y1030728D01*
G01X153543Y1042008D02*
Y1042874D01*
G01Y1037008D02*
Y1037874D01*
G01Y1032008D02*
Y1032874D01*
G01Y1027008D02*
Y1027874D01*
G01X153425Y1030728D02*
Y1029154D01*
G01Y1035728D02*
Y1034154D01*
G01Y1040728D02*
Y1039154D01*
G01Y1045728D02*
Y1044154D01*
G01X153031Y1030728D02*
Y1029154D01*
G01Y1035728D02*
Y1034154D01*
G01Y1040728D02*
Y1039154D01*
G01Y1045728D02*
Y1044154D01*
G01X148110D02*
Y1045728D01*
G01Y1039154D02*
Y1040728D01*
G01Y1034154D02*
Y1035728D01*
G01Y1029154D02*
Y1030728D01*
G01X157915Y1046824D02*
X157781Y1046791D01*
G01X156102Y1066299D02*
X168110D01*
G01X162992Y1066201D02*
X165354D01*
G01X162992Y1064429D02*
X165354D01*
G01X156102Y1064331D02*
X168110D01*
G01X156102Y1063150D02*
X168110D01*
G01X162992Y1063051D02*
X165354D01*
G01X162992Y1061280D02*
X165354D01*
G01X156102Y1061181D02*
X168110D01*
G01X156102Y1060000D02*
X168110D01*
G01X162992Y1059902D02*
X165354D01*
G01X162992Y1058130D02*
X165354D01*
G01X156102Y1058032D02*
X168110D01*
G01X156102Y1056851D02*
X168110D01*
G01X162992Y1056752D02*
X165354D01*
G01X162992Y1054980D02*
X165354D01*
G01X156102Y1054882D02*
X168110D01*
G01X156102Y1053701D02*
X168110D01*
G01X162992Y1053603D02*
X165354D01*
G01X162992Y1051831D02*
X165354D01*
G01X156102Y1051732D02*
X168110D01*
G01X156102Y1050551D02*
X168110D01*
G01X162992Y1050453D02*
X165354D01*
G01X156977Y1049351D02*
X157077D01*
G01X157647Y1049317D02*
X157747D01*
G01X156977Y1049186D02*
X157077D01*
G01X157680Y1049154D02*
X157747D01*
G01X162992Y1048681D02*
X165354D01*
G01X156102Y1048583D02*
X168110D01*
G01X157747Y1048366D02*
X157680D01*
G01X157077Y1048333D02*
X156977D01*
G01X157747Y1048202D02*
X157647D01*
G01X157077Y1048169D02*
X156977D01*
G01X156943Y1047907D02*
X157111D01*
G01X157077Y1047710D02*
X156977D01*
G01X156102Y1047402D02*
X168110D01*
G01X162992Y1047303D02*
X165354D01*
G01X157680Y1046988D02*
X157747D01*
G01X157781Y1046791D02*
X157647D01*
G01X157283Y1046417D02*
X160630D01*
G01X157781Y1047808D02*
X157881Y1047776D01*
G01X157580Y1047021D02*
X157680Y1046988D01*
G01X156910Y1046923D02*
X157010Y1046890D01*
G01X160630Y1065118D02*
X162992Y1064429D01*
G01X160630Y1061969D02*
X162992Y1061280D01*
G01X160630Y1058819D02*
X162992Y1058130D01*
G01X160630Y1055669D02*
X162992Y1054980D01*
G01X160630Y1052520D02*
X162992Y1051831D01*
G01X160630Y1049370D02*
X162992Y1048681D01*
G01X157647Y1046791D02*
X157513Y1046824D01*
G01X157010Y1046693D02*
X156876Y1046726D01*
G01D02*
X156709Y1046824D01*
G01X157647Y1048202D02*
X157513Y1048268D01*
G01X157848Y1047579D02*
X157781Y1047612D01*
G01X157111Y1047907D02*
X157245Y1047841D01*
G01X157747Y1049317D02*
X157915Y1049252D01*
G01X157077Y1049351D02*
X157245Y1049285D01*
G01X156977Y1048169D02*
X156809Y1048235D01*
G01X157915Y1049252D02*
X158016Y1049154D01*
G01X157513Y1048268D02*
X157412Y1048366D01*
G01X157915Y1047513D02*
X157848Y1047579D01*
G01X157245Y1047841D02*
X157379Y1047710D01*
G01X156809Y1048235D02*
X156709Y1048333D01*
G01X157513Y1046824D02*
X157379Y1046955D01*
G01X156809Y1047021D02*
X156910Y1046923D01*
G01X157077Y1049186D02*
X157211Y1049088D01*
G01X157881Y1047776D02*
X158016Y1047677D01*
G01X156977Y1048333D02*
X156843Y1048432D01*
G01X157747Y1049154D02*
X157848Y1049088D01*
G01X157680Y1048366D02*
X157580Y1048432D01*
G01X157178Y1047644D02*
X157077Y1047710D01*
G01X162992Y1047303D02*
X160630Y1046614D01*
G01X162992Y1050453D02*
X160630Y1049764D01*
G01X162992Y1053603D02*
X160630Y1052914D01*
G01X162992Y1056752D02*
X160630Y1056063D01*
G01X162992Y1059902D02*
X160630Y1059213D01*
G01X162992Y1063051D02*
X160630Y1062362D01*
G01X162992Y1066201D02*
X160630Y1065512D01*
G01X157747Y1046988D02*
X157848Y1047021D01*
G01X157915Y1048268D02*
X157747Y1048202D01*
G01X157245Y1048235D02*
X157077Y1048169D01*
G01X156809Y1049285D02*
X156977Y1049351D01*
G01X156809Y1047841D02*
X156943Y1047907D01*
G01X157513Y1049252D02*
X157647Y1049317D01*
G01X158016Y1049154D02*
X158116Y1048990D01*
G01X156709Y1048333D02*
X156608Y1048497D01*
G01X156709Y1046824D02*
X156608Y1046988D01*
G01X157245Y1047546D02*
X157178Y1047644D01*
G01X157513Y1047119D02*
X157580Y1047021D01*
G01X157848Y1049088D02*
X157948Y1048957D01*
G01X157245Y1049285D02*
X157345Y1049154D01*
G01X157580Y1048432D02*
X157479Y1048563D01*
G01X158016Y1047677D02*
X158116Y1047546D01*
G01X156977Y1047710D02*
X156876Y1047644D01*
G01X157848Y1048432D02*
X157747Y1048366D01*
G01X157580Y1049088D02*
X157680Y1049154D01*
G01X157211Y1048432D02*
X157077Y1048333D01*
G01X156843Y1049088D02*
X156977Y1049186D01*
G01X158049Y1046955D02*
X157915Y1046824D01*
G01X158016Y1048366D02*
X157915Y1048268D01*
G01X156675Y1047710D02*
X156809Y1047841D01*
G01X157412Y1049154D02*
X157513Y1049252D01*
G01X156709Y1049186D02*
X156809Y1049285D01*
G01X158116Y1048990D02*
X158149Y1048825D01*
G01X158145Y1047402D02*
X158149Y1047382D01*
G01X158116Y1047546D02*
X158145Y1047402D01*
G01X157446Y1047579D02*
X157479Y1047415D01*
G01X156591Y1048583D02*
X156575Y1048662D01*
G01X156608Y1048497D02*
X156591Y1048583D01*
G01X156608Y1046988D02*
X156575Y1047152D01*
G01X157948Y1048957D02*
X157982Y1048825D01*
G01X157474Y1048583D02*
X157446Y1048694D01*
G01X157479Y1048563D02*
X157474Y1048583D01*
G01X157278Y1048957D02*
X157312Y1048825D01*
G01X157278Y1047415D02*
X157245Y1047546D01*
G01X157312Y1047087D02*
X157278Y1047218D01*
G01X156771Y1048583D02*
X156742Y1048694D01*
G01X156776Y1048563D02*
X156771Y1048583D01*
G01X156776Y1047152D02*
X156809Y1047021D01*
G01X157948Y1047415D02*
X157915Y1047513D01*
G01X157479Y1047218D02*
X157513Y1047119D01*
G01X157345Y1049154D02*
X157379Y1049088D01*
G01X157211D02*
X157278Y1048957D01*
G01X157412Y1048366D02*
X157379Y1048432D01*
G01Y1047710D02*
X157446Y1047579D01*
G01X156843Y1048432D02*
X156776Y1048563D01*
G01X157379Y1046955D02*
X157312Y1047087D01*
G01X157948Y1048563D02*
X157848Y1048432D01*
G01X157345Y1048366D02*
X157245Y1048235D01*
G01X157479Y1048957D02*
X157580Y1049088D01*
G01X157848Y1047021D02*
X157915Y1047119D01*
G01X156876Y1047644D02*
X156809Y1047546D01*
G01X158116Y1048530D02*
X158016Y1048366D01*
G01X156608Y1049022D02*
X156709Y1049186D01*
G01X158116Y1047087D02*
X158049Y1046955D01*
G01X157379Y1048432D02*
X157345Y1048366D01*
G01X157278Y1048563D02*
X157211Y1048432D01*
G01X157379Y1049088D02*
X157412Y1049154D01*
G01X156608Y1047579D02*
X156675Y1047710D01*
G01X156776Y1048957D02*
X156843Y1049088D01*
G01X157915Y1047119D02*
X157948Y1047218D01*
G01X158149D02*
X158116Y1047087D01*
G01X157982Y1048694D02*
X157953Y1048583D01*
G01D02*
X157948Y1048563D01*
G01X157446Y1048825D02*
X157479Y1048957D01*
G01X157312Y1048694D02*
X157283Y1048583D01*
G01D02*
X157278Y1048563D01*
G01X156809Y1047546D02*
X156776Y1047415D01*
G01X156742Y1048825D02*
X156776Y1048957D01*
G01X158149Y1048694D02*
X158127Y1048583D01*
G01D02*
X158116Y1048530D01*
G01X156575Y1047415D02*
X156608Y1047579D01*
G01X156575Y1048858D02*
X156608Y1049022D01*
G01X165354Y1048583D02*
Y1047402D01*
G01Y1050551D02*
Y1048583D01*
G01Y1053701D02*
Y1051732D01*
G01D02*
Y1050551D01*
G01Y1056851D02*
Y1054882D01*
G01D02*
Y1053701D01*
G01Y1058032D02*
Y1056851D01*
G01Y1060000D02*
Y1058032D01*
G01Y1063150D02*
Y1061181D01*
G01D02*
Y1060000D01*
G01Y1066299D02*
Y1064331D01*
G01D02*
Y1063150D01*
G01Y1067480D02*
Y1066299D01*
G01X163464D02*
Y1067480D01*
G01Y1063150D02*
Y1064331D01*
G01Y1060000D02*
Y1061181D01*
G01Y1053701D02*
Y1054882D01*
G01Y1056851D02*
Y1058032D01*
G01Y1050551D02*
Y1051732D01*
G01Y1047402D02*
Y1048583D01*
G01X161890Y1066299D02*
Y1067480D01*
G01Y1063150D02*
Y1064331D01*
G01Y1060000D02*
Y1061181D01*
G01Y1056851D02*
Y1058032D01*
G01Y1053701D02*
Y1054882D01*
G01Y1050551D02*
Y1051732D01*
G01Y1047402D02*
Y1048583D01*
G01X161102D02*
Y1047402D01*
G01Y1051732D02*
Y1050551D01*
G01Y1054882D02*
Y1053701D01*
G01Y1058032D02*
Y1056851D01*
G01Y1061181D02*
Y1060000D01*
G01Y1064331D02*
Y1063150D01*
G01Y1067480D02*
Y1066299D01*
G01X160708Y1048583D02*
Y1047402D01*
G01Y1051732D02*
Y1050551D01*
G01Y1054882D02*
Y1053701D01*
G01Y1058032D02*
Y1056851D01*
G01Y1061181D02*
Y1060000D01*
G01Y1067480D02*
Y1066299D01*
G01Y1064331D02*
Y1063150D01*
G01X160630Y1065118D02*
Y1065512D01*
G01Y1061969D02*
Y1062362D01*
G01Y1055669D02*
Y1056063D01*
G01Y1058819D02*
Y1059213D01*
G01Y1052520D02*
Y1052914D01*
G01Y1046417D02*
Y1046614D01*
G01Y1049370D02*
Y1049764D01*
G01X158149Y1048825D02*
Y1048694D01*
G01Y1047382D02*
Y1047218D01*
G01X157982Y1048825D02*
Y1048694D01*
G01X157948Y1047218D02*
Y1047402D01*
G01D02*
Y1047415D01*
G01X157781Y1047612D02*
Y1047808D01*
G01X157479Y1047402D02*
Y1047218D01*
G01Y1047415D02*
Y1047402D01*
G01X157446Y1048694D02*
Y1048825D01*
G01X157312D02*
Y1048694D01*
G01X157278Y1047218D02*
Y1047402D01*
G01D02*
Y1047415D01*
G01X157010Y1046890D02*
Y1046693D01*
G01X156776Y1047402D02*
Y1047152D01*
G01Y1047415D02*
Y1047402D01*
G01X156742Y1048694D02*
Y1048825D01*
G01X156575Y1048662D02*
Y1048858D01*
G01Y1047152D02*
Y1047402D01*
G01D02*
Y1047415D01*
G01X156102Y1063150D02*
Y1064331D01*
G01Y1066299D02*
Y1067480D01*
G01Y1060000D02*
Y1061181D01*
G01Y1053701D02*
Y1054882D01*
G01Y1056851D02*
Y1058032D01*
G01Y1050551D02*
Y1051732D01*
G01Y1047402D02*
Y1048583D01*
G01X158661Y1084055D02*
X153543Y1082874D01*
G01X166535Y1087303D02*
X165354D01*
G01X163386Y1085827D02*
X158661D01*
G01X197638D02*
X166535D01*
G01Y1085728D02*
X195876D01*
G01X146653D02*
X166535D01*
G01Y1084154D02*
X195876D01*
G01X146653D02*
X166535D01*
G01Y1084055D02*
X197638D01*
G01X158661D02*
X163386D01*
G01X165354Y1082579D02*
X166535D01*
G01X165354Y1080827D02*
X197638D01*
G01X161417D02*
X156693D01*
G01X165354Y1080728D02*
X195876D01*
G01X148110D02*
X165354D01*
G01Y1079154D02*
X195876D01*
G01X165354D02*
X148110D01*
G01X165354Y1079055D02*
X197638D01*
G01X156693D02*
X161417D01*
G01X165354Y1075827D02*
X197638D01*
G01X161417D02*
X156693D01*
G01X165354Y1075728D02*
X195876D01*
G01X148110D02*
X165354D01*
G01Y1074154D02*
X148110D01*
G01X195876D02*
X165354D01*
G01Y1074055D02*
X197638D01*
G01X156693D02*
X161417D01*
G01X158464Y1073819D02*
X165354D01*
G01Y1071063D02*
X158464D01*
G01X150905Y1070886D02*
X149330D01*
G01X165354Y1070827D02*
X194685D01*
G01X161417D02*
X156693D01*
G01X165354Y1070728D02*
X195756D01*
G01X146653D02*
X165354D01*
G01X149330Y1070689D02*
X150637D01*
G01X150403Y1070492D02*
X150671D01*
G01X150537Y1070230D02*
X150403D01*
G01X150436Y1070033D02*
X150537D01*
G01X165354Y1069646D02*
X197638D01*
G01X150738Y1069213D02*
X150235D01*
G01X150034D02*
X149330D01*
G01X165354Y1069154D02*
X195756D01*
G01X146653D02*
X165354D01*
G01Y1069055D02*
X194685D01*
G01X157283D02*
X161417D01*
G01X149330Y1069016D02*
X150905D01*
G01X160630Y1068465D02*
X157283D01*
G01X162992Y1067579D02*
X165354D01*
G01X156102Y1067480D02*
X168110D01*
G01X153543Y1082008D02*
X156693Y1080827D01*
G01X153543Y1077008D02*
X156693Y1075827D01*
G01X153543Y1072008D02*
X156693Y1070827D01*
G01X150637Y1070197D02*
X150537Y1070230D01*
G01Y1070033D02*
X150637Y1070000D01*
G01X160630Y1068268D02*
X162992Y1067579D01*
G01X153543Y1087008D02*
X158661Y1085827D01*
G01X150637Y1070000D02*
X150704Y1069934D01*
G01X150771Y1070099D02*
X150637Y1070197D01*
G01X150336Y1070000D02*
X150436Y1070033D01*
G01X150403Y1070230D02*
X150302Y1070197D01*
G01X156693Y1074055D02*
X153543Y1072874D01*
G01X156693Y1079055D02*
X153543Y1077874D01*
G01X156693Y1089055D02*
X153543Y1087874D01*
G01X150872Y1069967D02*
X150771Y1070099D01*
G01X150302Y1070197D02*
X150168Y1070099D01*
G01X150671Y1070492D02*
X150905Y1070689D01*
G01Y1069803D02*
X150872Y1069967D01*
G01X150704Y1069934D02*
X150738Y1069836D01*
G01X150637Y1070689D02*
X150403Y1070492D01*
G01X150269Y1069934D02*
X150336Y1070000D01*
G01X150168Y1070099D02*
X150067Y1069967D01*
G01X166535Y1082579D02*
Y1087303D01*
G01X165354Y1085728D02*
Y1124154D01*
G01Y1067480D02*
Y1084154D01*
G01Y1085728D02*
Y1084154D01*
G01X163386Y1085728D02*
Y1085827D01*
G01Y1084055D02*
Y1084154D01*
G01D02*
Y1085728D01*
G01X161417Y1080728D02*
Y1080827D01*
G01Y1079055D02*
Y1079154D01*
G01D02*
Y1080728D01*
G01Y1075728D02*
Y1075827D01*
G01Y1074055D02*
Y1074154D01*
G01D02*
Y1075728D01*
G01Y1070728D02*
Y1070827D01*
G01Y1069055D02*
Y1069154D01*
G01D02*
Y1070728D01*
G01X160630Y1068268D02*
Y1068465D01*
G01X158464Y1073819D02*
Y1071063D01*
G01X157283Y1068465D02*
Y1069055D01*
G01X155787Y1084154D02*
Y1085728D01*
G01Y1079154D02*
Y1080728D01*
G01Y1074154D02*
Y1075728D01*
G01Y1069154D02*
Y1070728D01*
G01X154212Y1084154D02*
Y1085728D01*
G01Y1079154D02*
Y1080728D01*
G01Y1074154D02*
Y1075728D01*
G01Y1069154D02*
Y1070728D01*
G01X153543Y1087008D02*
Y1087874D01*
G01Y1082008D02*
Y1082874D01*
G01Y1077008D02*
Y1077874D01*
G01Y1072008D02*
Y1072874D01*
G01X153425Y1070728D02*
Y1069154D01*
G01Y1075728D02*
Y1074154D01*
G01Y1080728D02*
Y1079154D01*
G01Y1085728D02*
Y1084154D01*
G01X153031Y1070728D02*
Y1069154D01*
G01Y1075728D02*
Y1074154D01*
G01Y1080728D02*
Y1079154D01*
G01Y1085728D02*
Y1084154D01*
G01X150905Y1070728D02*
Y1070886D01*
G01Y1069016D02*
Y1069154D01*
G01Y1070689D02*
Y1070728D01*
G01Y1069154D02*
Y1069803D01*
G01X150738Y1069836D02*
Y1069213D01*
G01X150235D02*
Y1069836D01*
G01X150034Y1069803D02*
Y1069213D01*
G01X149330Y1070886D02*
Y1070728D01*
G01Y1069154D02*
Y1069016D01*
G01Y1070728D02*
Y1070689D01*
G01Y1069213D02*
Y1069154D01*
G01X150235Y1069836D02*
X150269Y1069934D01*
G01X150067Y1069967D02*
X150034Y1069803D01*
G01X148110Y1079154D02*
Y1080728D01*
G01Y1074154D02*
Y1075728D01*
G01X146653Y1084154D02*
Y1085728D01*
G01Y1069154D02*
Y1070728D01*
G01X165354Y1109154D02*
X195876D01*
G01X165354D02*
X148110D01*
G01X165354Y1109055D02*
X197638D01*
G01X156693D02*
X161417D01*
G01X165354Y1105827D02*
X197638D01*
G01X161417D02*
X156693D01*
G01X165354Y1105728D02*
X195876D01*
G01X148110D02*
X165354D01*
G01Y1104154D02*
X195876D01*
G01X165354D02*
X148110D01*
G01X165354Y1104055D02*
X197638D01*
G01X156693D02*
X161417D01*
G01X165354Y1100827D02*
X197638D01*
G01X161417D02*
X156693D01*
G01X165354Y1100728D02*
X195876D01*
G01X148110D02*
X165354D01*
G01Y1099154D02*
X195876D01*
G01X165354D02*
X148110D01*
G01X165354Y1099055D02*
X197638D01*
G01X156693D02*
X161417D01*
G01X158464Y1098819D02*
X165354D01*
G01Y1096063D02*
X158464D01*
G01X165354Y1095827D02*
X197638D01*
G01X161417D02*
X156693D01*
G01X165354Y1095728D02*
X195876D01*
G01X148110D02*
X165354D01*
G01Y1094154D02*
X195876D01*
G01X165354D02*
X148110D01*
G01X165354Y1094055D02*
X197638D01*
G01X156693D02*
X161417D01*
G01X165354Y1090827D02*
X197638D01*
G01X161417D02*
X156693D01*
G01X165354Y1090728D02*
X195876D01*
G01X148110D02*
X165354D01*
G01Y1089154D02*
X195876D01*
G01X165354D02*
X148110D01*
G01X165354Y1089055D02*
X197638D01*
G01X156693D02*
X161417D01*
G01X153543Y1107008D02*
X156693Y1105827D01*
G01X153543Y1102008D02*
X156693Y1100827D01*
G01X153543Y1097008D02*
X156693Y1095827D01*
G01X153543Y1092008D02*
X156693Y1090827D01*
G01Y1094055D02*
X153543Y1092874D01*
G01X156693Y1099055D02*
X153543Y1097874D01*
G01X156693Y1104055D02*
X153543Y1102874D01*
G01X156693Y1109055D02*
X153543Y1107874D01*
G01X161417Y1109055D02*
Y1109154D01*
G01D02*
Y1110728D01*
G01Y1105728D02*
Y1105827D01*
G01Y1104055D02*
Y1104154D01*
G01D02*
Y1105728D01*
G01Y1100728D02*
Y1100827D01*
G01Y1099055D02*
Y1099154D01*
G01D02*
Y1100728D01*
G01Y1095728D02*
Y1095827D01*
G01Y1094055D02*
Y1094154D01*
G01D02*
Y1095728D01*
G01Y1090728D02*
Y1090827D01*
G01Y1089055D02*
Y1089154D01*
G01D02*
Y1090728D01*
G01X158464Y1098819D02*
Y1096063D01*
G01X155787Y1109154D02*
Y1110728D01*
G01Y1104154D02*
Y1105728D01*
G01Y1099154D02*
Y1100728D01*
G01Y1094154D02*
Y1095728D01*
G01Y1089154D02*
Y1090728D01*
G01X154212Y1109154D02*
Y1110728D01*
G01Y1104154D02*
Y1105728D01*
G01Y1099154D02*
Y1100728D01*
G01Y1094154D02*
Y1095728D01*
G01Y1089154D02*
Y1090728D01*
G01X153543Y1107008D02*
Y1107874D01*
G01Y1102008D02*
Y1102874D01*
G01Y1097008D02*
Y1097874D01*
G01Y1092008D02*
Y1092874D01*
G01X153425Y1090728D02*
Y1089154D01*
G01Y1095728D02*
Y1094154D01*
G01Y1100728D02*
Y1099154D01*
G01Y1105728D02*
Y1104154D01*
G01Y1110728D02*
Y1109154D01*
G01X153031Y1090728D02*
Y1089154D01*
G01Y1095728D02*
Y1094154D01*
G01Y1100728D02*
Y1099154D01*
G01Y1105728D02*
Y1104154D01*
G01Y1110728D02*
Y1109154D01*
G01X148110D02*
Y1110728D01*
G01Y1104154D02*
Y1105728D01*
G01Y1099154D02*
Y1100728D01*
G01Y1094154D02*
Y1095728D01*
G01Y1089154D02*
Y1090728D01*
G01X158661Y1124055D02*
X153543Y1122874D01*
G01X165354Y1130728D02*
X195876D01*
G01X148110D02*
X165354D01*
G01Y1129154D02*
X195876D01*
G01X165354D02*
X148110D01*
G01X165354Y1129055D02*
X197638D01*
G01X156693D02*
X161417D01*
G01X166535Y1127303D02*
X165354D01*
G01X163386Y1125827D02*
X158661D01*
G01X197638D02*
X166535D01*
G01Y1125728D02*
X195876D01*
G01X146653D02*
X166535D01*
G01Y1124154D02*
X195876D01*
G01X146653D02*
X166535D01*
G01Y1124055D02*
X197638D01*
G01X158661D02*
X163386D01*
G01X158464Y1123819D02*
X165354D01*
G01Y1122579D02*
X166535D01*
G01X165354Y1121063D02*
X158464D01*
G01X165354Y1120827D02*
X197638D01*
G01X161417D02*
X156693D01*
G01X165354Y1120728D02*
X195876D01*
G01X148110D02*
X165354D01*
G01Y1119154D02*
X195876D01*
G01X165354D02*
X148110D01*
G01X165354Y1119055D02*
X197638D01*
G01X156693D02*
X161417D01*
G01X165354Y1115827D02*
X197638D01*
G01X161417D02*
X156693D01*
G01X165354Y1115728D02*
X195876D01*
G01X148110D02*
X165354D01*
G01Y1114154D02*
X195876D01*
G01X165354D02*
X148110D01*
G01X165354Y1114055D02*
X197638D01*
G01X156693D02*
X161417D01*
G01X165354Y1110827D02*
X197638D01*
G01X161417D02*
X156693D01*
G01X165354Y1110728D02*
X195876D01*
G01X148110D02*
X165354D01*
G01X153543Y1127008D02*
X158661Y1125827D01*
G01X153543Y1122008D02*
X156693Y1120827D01*
G01X153543Y1117008D02*
X156693Y1115827D01*
G01X153543Y1112008D02*
X156693Y1110827D01*
G01Y1114055D02*
X153543Y1112874D01*
G01X156693Y1119055D02*
X153543Y1117874D01*
G01X156693Y1129055D02*
X153543Y1127874D01*
G01X166535Y1122579D02*
Y1127303D01*
G01X165354Y1125728D02*
Y1145532D01*
G01Y1125728D02*
Y1124154D01*
G01X163386Y1125728D02*
Y1125827D01*
G01Y1124154D02*
Y1125728D01*
G01Y1124055D02*
Y1124154D01*
G01X161417Y1130728D02*
Y1130827D01*
G01Y1129154D02*
Y1130728D01*
G01Y1129055D02*
Y1129154D01*
G01Y1120728D02*
Y1120827D01*
G01Y1119154D02*
Y1120728D01*
G01Y1119055D02*
Y1119154D01*
G01Y1115728D02*
Y1115827D01*
G01Y1114154D02*
Y1115728D01*
G01Y1114055D02*
Y1114154D01*
G01Y1110728D02*
Y1110827D01*
G01X158464Y1123819D02*
Y1121063D01*
G01X155787Y1129154D02*
Y1130728D01*
G01Y1124154D02*
Y1125728D01*
G01Y1119154D02*
Y1120728D01*
G01Y1114154D02*
Y1115728D01*
G01X154212Y1129154D02*
Y1130728D01*
G01Y1124154D02*
Y1125728D01*
G01Y1119154D02*
Y1120728D01*
G01Y1114154D02*
Y1115728D01*
G01X153543Y1127008D02*
Y1127874D01*
G01Y1122008D02*
Y1122874D01*
G01Y1117008D02*
Y1117874D01*
G01Y1112008D02*
Y1112874D01*
G01X153425Y1115728D02*
Y1114154D01*
G01Y1120728D02*
Y1119154D01*
G01Y1125728D02*
Y1124154D01*
G01Y1130728D02*
Y1129154D01*
G01X153031Y1115728D02*
Y1114154D01*
G01Y1120728D02*
Y1119154D01*
G01Y1125728D02*
Y1124154D01*
G01Y1130728D02*
Y1129154D01*
G01X148110D02*
Y1130728D01*
G01Y1119154D02*
Y1120728D01*
G01Y1114154D02*
Y1115728D01*
G01X146653Y1124154D02*
Y1125728D01*
G01X155700Y1149880D02*
Y1149882D01*
G01X155698Y1149877D02*
X155700Y1149880D01*
G01X155666Y1149799D02*
X155698Y1149877D01*
G01X155934Y1150417D02*
X156054Y1150669D01*
G01X155816Y1150155D02*
X155934Y1150417D01*
G01X155700Y1149882D02*
X155816Y1150155D01*
G01X160325Y1150154D02*
X160441Y1149882D01*
G01X160207Y1150417D02*
X160325Y1150154D01*
G01X160088Y1150669D02*
X160207Y1150417D01*
G01X156054Y1153819D02*
G03Y1150669I2017J-1575D01*
G01X160088D02*
G03Y1153819I-2017J1575D01*
G01X155700Y1154606D02*
G03Y1149882I2371J-2362D01*
G01X160441D02*
G03Y1154606I-2370J2362D01*
G01X161575Y1152244D02*
G03I-3504J0D01*
G01X160748Y1149095D02*
G03Y1155394I-2677J3149D01*
G01X155393D02*
G03Y1149095I2678J-3150D01*
G01X166142Y1151634D02*
X145669D01*
G01X177165D02*
X166142D01*
G01X156054Y1150669D02*
X160088D01*
G01X155700Y1149882D02*
X160441D01*
G01X160748Y1149095D02*
X155393D01*
G01X195669Y1148681D02*
X145669D01*
G01X165354Y1145532D02*
X145669D01*
G01Y1143760D02*
X165354D01*
G01D02*
X166634D01*
G01X161417Y1140827D02*
X156693D01*
G01X197638D02*
X165354D01*
G01Y1140728D02*
X195876D01*
G01X148110D02*
X165354D01*
G01Y1139154D02*
X195876D01*
G01X165354D02*
X148110D01*
G01X165354Y1139055D02*
X197638D01*
G01X156693D02*
X161417D01*
G01X165354Y1135827D02*
X197638D01*
G01X161417D02*
X156693D01*
G01X165354Y1135728D02*
X195876D01*
G01X148110D02*
X165354D01*
G01Y1134154D02*
X195876D01*
G01X165354D02*
X148110D01*
G01X165354Y1134055D02*
X197638D01*
G01X156693D02*
X161417D01*
G01X165354Y1130827D02*
X197638D01*
G01X161417D02*
X156693D01*
G01X153543Y1142008D02*
X156693Y1140827D01*
G01X153543Y1137008D02*
X156693Y1135827D01*
G01X153543Y1132008D02*
X156693Y1130827D01*
G01X160693Y1149243D02*
X160748Y1149095D01*
G01X160658Y1149338D02*
X160693Y1149243D01*
G01X160623Y1149430D02*
X160658Y1149338D01*
G01X160589Y1149516D02*
X160623Y1149430D01*
G01X160517Y1149695D02*
X160589Y1149516D01*
G01X160484Y1149776D02*
X160517Y1149695D01*
G01X160441Y1149882D02*
X160484Y1149776D01*
G01X156693Y1134055D02*
X153543Y1132874D01*
G01X156693Y1139055D02*
X153543Y1137874D01*
G01X166142Y1148681D02*
Y1157028D01*
G01X161417Y1140728D02*
Y1140827D01*
G01Y1139055D02*
Y1139154D01*
G01D02*
Y1140728D01*
G01Y1135728D02*
Y1135827D01*
G01Y1134154D02*
Y1135728D01*
G01Y1134055D02*
Y1134154D01*
G01X155787Y1139154D02*
Y1140728D01*
G01Y1134154D02*
Y1135728D01*
G01X154212Y1139154D02*
Y1140728D01*
G01Y1134154D02*
Y1135728D01*
G01X153543Y1142008D02*
Y1143760D01*
G01Y1137008D02*
Y1137874D01*
G01Y1132008D02*
Y1132874D01*
G01X153425Y1135728D02*
Y1134154D01*
G01Y1140728D02*
Y1139154D01*
G01X153031Y1135728D02*
Y1134154D01*
G01Y1140728D02*
Y1139154D01*
G01X155624Y1149695D02*
X155666Y1149799D01*
G01X155553Y1149516D02*
X155624Y1149695D01*
G01X155519Y1149430D02*
X155553Y1149516D01*
G01X155484Y1149338D02*
X155519Y1149430D01*
G01X155448Y1149243D02*
X155484Y1149338D01*
G01X155393Y1149095D02*
X155448Y1149243D01*
G01X148110Y1139154D02*
Y1140728D01*
G01Y1134154D02*
Y1135728D01*
G01X145669Y1143760D02*
Y1157028D01*
G01X160442Y1154608D02*
X160441Y1154606D01*
G01X160443Y1154612D02*
X160442Y1154608D01*
G01X160475Y1154690D02*
X160443Y1154612D01*
G01X160321Y1154324D02*
X160441Y1154606D01*
G01X160203Y1154061D02*
X160321Y1154324D01*
G01X160088Y1153819D02*
X160203Y1154061D01*
G01X155939D02*
X156054Y1153819D01*
G01X155821Y1154323D02*
X155939Y1154061D01*
G01X155700Y1154606D02*
X155821Y1154323D01*
G01X171063Y1164055D02*
G03I-3740J0D01*
G01X177165Y1169980D02*
X157480D01*
G01X177165Y1168012D02*
X157480D01*
G01X177165Y1166024D02*
X157480D01*
G01Y1165040D02*
X177165D01*
G01X176968Y1164843D02*
X157677D01*
G01X176968Y1163268D02*
X157677D01*
G01X177165Y1163071D02*
X157480D01*
G01Y1162087D02*
X177165D01*
G01Y1158996D02*
X157480D01*
G01X199606Y1157028D02*
X145669D01*
G01X166142Y1155847D02*
X199606D01*
G01X155393Y1155394D02*
X160748D01*
G01X160441Y1154606D02*
X155700D01*
G01X156054Y1153819D02*
X160088D01*
G01X155448Y1155246D02*
X155393Y1155394D01*
G01X155484Y1155150D02*
X155448Y1155246D01*
G01X155519Y1155058D02*
X155484Y1155150D01*
G01X155552Y1154972D02*
X155519Y1155058D01*
G01X155624Y1154793D02*
X155552Y1154972D01*
G01X155657Y1154712D02*
X155624Y1154793D01*
G01X155700Y1154606D02*
X155657Y1154712D01*
G01X166142Y1164843D02*
Y1163268D01*
G01X164567D02*
Y1164843D01*
G01X164370D02*
Y1165040D01*
G01Y1163268D02*
Y1164843D01*
G01Y1163268D02*
Y1163071D01*
G01X163031Y1163268D02*
Y1164843D01*
G01X157677D02*
Y1163268D01*
G01X157480Y1157028D02*
Y1169980D01*
G01X153543Y1160965D02*
Y1173917D01*
G01X160517Y1154793D02*
X160475Y1154690D01*
G01X160589Y1154972D02*
X160517Y1154793D01*
G01X160623Y1155058D02*
X160589Y1154972D01*
G01X160658Y1155150D02*
X160623Y1155058D01*
G01X160693Y1155246D02*
X160658Y1155150D01*
G01X160748Y1155394D02*
X160693Y1155246D01*
G01X153543Y1173917D02*
X181102D01*
G01X164173Y1379370D02*
G03Y1380551I0J590D01*
G01Y1376614D02*
G03Y1377795I0J591D01*
G01Y1381142D02*
X170472D01*
G01X164173Y1380847D02*
X162598D01*
G01X165748D02*
X164173D01*
G01X162598Y1378878D02*
X164173D01*
G01D02*
X165748D01*
G01X162598Y1378288D02*
X164173D01*
G01D02*
X165748D01*
G01X164173Y1376319D02*
X162598D01*
G01X165748D02*
X164173D01*
G01Y1376024D02*
X170472D01*
G01X165748Y1378878D02*
Y1380847D01*
G01Y1378288D02*
Y1376319D01*
G01X165354Y1376024D02*
Y1381142D01*
G01X165157D02*
Y1376024D01*
G01X164173Y1376614D02*
Y1376024D01*
G01Y1379370D02*
Y1377795D01*
G01Y1381142D02*
Y1380551D01*
G01X162598Y1376319D02*
Y1378288D01*
G01Y1380847D02*
Y1378878D01*
G01X160630Y1408150D02*
G03I-2559J0D01*
G01X161417D02*
G03I-3346J0D01*
G01X161575D02*
G03I-3504J0D01*
G01X171063Y1396339D02*
G03I-3740J0D01*
G01X158145Y1404016D02*
G03X158071Y1412284I-74J4134D01*
G01X157996Y1412283D02*
G03X158071Y1404016I73J-4133D01*
G01X199606Y1404547D02*
X166142D01*
G01X199606Y1403366D02*
X145669D01*
G01X157480Y1401398D02*
X177165D01*
G01Y1398307D02*
X157480D01*
G01Y1397323D02*
X177165D01*
G01X176968Y1397126D02*
X157677D01*
G01X176968Y1395551D02*
X157677D01*
G01X177165Y1395354D02*
X157480D01*
G01Y1394370D02*
X177165D01*
G01X157480Y1392382D02*
X177165D01*
G01X157480Y1390414D02*
X177165D01*
G01X158145Y1404016D02*
X158071D01*
G01X181102Y1386477D02*
X153543D01*
G01X166142Y1403366D02*
Y1411713D01*
G01Y1397126D02*
Y1395551D01*
G01X164567D02*
Y1397126D01*
G01X164370D02*
Y1397323D01*
G01Y1395551D02*
Y1397126D01*
G01Y1395551D02*
Y1395354D01*
G01X163031Y1395551D02*
Y1397126D01*
G01X157677D02*
Y1395551D01*
G01X157480Y1390414D02*
Y1403366D01*
G01X153543Y1386477D02*
Y1399429D01*
G01X145669Y1403366D02*
Y1416634D01*
G01X150631Y1419619D02*
X150497Y1419587D01*
G01X165354Y1426339D02*
X197638D01*
G01X161417D02*
X156693D01*
G01X165354Y1426240D02*
X195876D01*
G01X148110D02*
X165354D01*
G01Y1424666D02*
X195876D01*
G01X165354D02*
X148110D01*
G01X165354Y1424567D02*
X197638D01*
G01X156693D02*
X161417D01*
G01X150866Y1421358D02*
X149291D01*
G01X165354Y1421339D02*
X197638D01*
G01X161417D02*
X156693D01*
G01X165354Y1421240D02*
X195876D01*
G01X148110D02*
X165354D01*
G01X149291Y1421162D02*
X150598D01*
G01X150364Y1420965D02*
X150631D01*
G01X149660Y1420702D02*
X149827D01*
G01X149794Y1420505D02*
X149693D01*
G01X150397Y1419784D02*
X150464D01*
G01X165354Y1419666D02*
X195876D01*
G01X165354D02*
X148110D01*
G01X150497Y1419587D02*
X150364D01*
G01X165354Y1419567D02*
X197638D01*
G01X156693D02*
X161417D01*
G01X165354Y1416634D02*
X166634D01*
G01X165354D02*
X145669D01*
G01Y1414862D02*
X165354D01*
G01X145669Y1411713D02*
X195669D01*
G01X166142Y1408760D02*
X177165D01*
G01X145669D02*
X166142D01*
G01X157996Y1412283D02*
X158071D01*
G01X150364Y1419587D02*
X150229Y1419619D01*
G01X149727Y1419488D02*
X149593Y1419521D01*
G01X153543Y1427520D02*
X156693Y1426339D01*
G01X153543Y1422520D02*
X156693Y1421339D01*
G01X150497Y1420604D02*
X150598Y1420571D01*
G01X150296Y1419816D02*
X150397Y1419784D01*
G01X149626Y1419718D02*
X149727Y1419685D01*
G01X149593Y1419521D02*
X149425Y1419619D01*
G01X150564Y1420374D02*
X150497Y1420407D01*
G01X149827Y1420702D02*
X149961Y1420636D01*
G01X150598Y1420571D02*
X150732Y1420473D01*
G01X149894Y1420440D02*
X149794Y1420505D01*
G01X150631Y1420308D02*
X150564Y1420374D01*
G01X149961Y1420636D02*
X150095Y1420505D01*
G01X150182Y1419666D02*
X150095Y1419751D01*
G01X150229Y1419619D02*
X150182Y1419666D01*
G01X149526Y1419816D02*
X149626Y1419718D01*
G01X150732Y1420473D02*
X150832Y1420341D01*
G01X150095Y1420505D02*
X150162Y1420374D01*
G01X150095Y1419751D02*
X150028Y1419882D01*
G01X149425Y1419619D02*
X149397Y1419666D01*
G01D02*
X149325Y1419784D01*
G01X149961Y1420341D02*
X149894Y1420440D01*
G01X150229Y1419915D02*
X150296Y1419816D01*
G01X150665Y1420210D02*
X150631Y1420308D01*
G01X150196Y1420013D02*
X150229Y1419915D01*
G01X150832Y1420341D02*
X150866Y1420177D01*
G01X150162Y1420374D02*
X150196Y1420210D01*
G01X149325Y1419784D02*
X149291Y1419947D01*
G01X149995Y1420210D02*
X149961Y1420341D01*
G01X150028Y1419882D02*
X149995Y1420013D01*
G01X149492Y1419947D02*
X149526Y1419816D01*
G01X166634Y1549272D02*
Y1416634D01*
G01X165354Y1414862D02*
Y1452914D01*
G01X161417Y1426240D02*
Y1426339D01*
G01Y1424567D02*
Y1424666D01*
G01D02*
Y1426240D01*
G01Y1421240D02*
Y1421339D01*
G01Y1419666D02*
Y1421240D01*
G01Y1419567D02*
Y1419666D01*
G01X155787Y1424666D02*
Y1426240D01*
G01Y1419666D02*
Y1421240D01*
G01X154212Y1424666D02*
Y1426240D01*
G01Y1419666D02*
Y1421240D01*
G01X153543Y1422520D02*
Y1423386D01*
G01Y1416634D02*
Y1418386D01*
G01X153425Y1421240D02*
Y1419666D01*
G01Y1426240D02*
Y1424666D01*
G01X153031Y1421240D02*
Y1419666D01*
G01Y1426240D02*
Y1424666D01*
G01X150866Y1421240D02*
Y1421358D01*
G01Y1421162D02*
Y1421240D01*
G01Y1420177D02*
Y1420013D01*
G01X150665D02*
Y1420210D01*
G01X150497Y1420407D02*
Y1420604D01*
G01X150196Y1420210D02*
Y1420013D01*
G01X149995D02*
Y1420210D01*
G01X149727Y1419666D02*
Y1419488D01*
G01Y1419685D02*
Y1419666D01*
G01X149492Y1420210D02*
Y1419947D01*
G01X149291D02*
Y1420210D01*
G01Y1421358D02*
Y1421240D01*
G01D02*
Y1421162D01*
G01X148110Y1424666D02*
Y1426240D01*
G01Y1419666D02*
Y1421240D01*
G01X150464Y1419784D02*
X150564Y1419816D01*
G01X150832Y1419882D02*
X150766Y1419751D01*
G01X150631Y1419915D02*
X150665Y1420013D01*
G01X150866D02*
X150832Y1419882D01*
G01X149526Y1420341D02*
X149492Y1420210D01*
G01X149291D02*
X149325Y1420374D01*
G01X156693Y1419567D02*
X153543Y1418386D01*
G01X156693Y1424567D02*
X153543Y1423386D01*
G01X149526Y1420636D02*
X149660Y1420702D01*
G01X149693Y1420505D02*
X149593Y1420440D01*
G01X150631Y1420965D02*
X150866Y1421162D01*
G01X150598D02*
X150364Y1420965D01*
G01X150679Y1419666D02*
X150631Y1419619D01*
G01X150766Y1419751D02*
X150679Y1419666D01*
G01X149392Y1420505D02*
X149526Y1420636D01*
G01X150564Y1419816D02*
X150631Y1419915D01*
G01X149593Y1420440D02*
X149526Y1420341D01*
G01X149325Y1420374D02*
X149392Y1420505D01*
G01X161417Y1446339D02*
X156693D01*
G01X197638D02*
X165354D01*
G01Y1446240D02*
X195876D01*
G01X148110D02*
X165354D01*
G01Y1444666D02*
X195876D01*
G01X165354D02*
X148110D01*
G01X165354Y1444567D02*
X197638D01*
G01X156693D02*
X161417D01*
G01X158464Y1444331D02*
X165354D01*
G01Y1441575D02*
X158464D01*
G01X165354Y1441339D02*
X197638D01*
G01X161417D02*
X156693D01*
G01X165354Y1441240D02*
X195876D01*
G01X148110D02*
X165354D01*
G01Y1439666D02*
X195876D01*
G01X165354D02*
X148110D01*
G01X165354Y1439567D02*
X197638D01*
G01X156693D02*
X161417D01*
G01X165354Y1436339D02*
X197638D01*
G01X161417D02*
X156693D01*
G01X165354Y1436240D02*
X195876D01*
G01X148110D02*
X165354D01*
G01Y1434666D02*
X195876D01*
G01X165354D02*
X148110D01*
G01X165354Y1434567D02*
X197638D01*
G01X156693D02*
X161417D01*
G01X165354Y1431339D02*
X197638D01*
G01X161417D02*
X156693D01*
G01X165354Y1431240D02*
X195876D01*
G01X148110D02*
X165354D01*
G01Y1429666D02*
X195876D01*
G01X165354D02*
X148110D01*
G01X165354Y1429567D02*
X197638D01*
G01X156693D02*
X161417D01*
G01X153543Y1447520D02*
X156693Y1446339D01*
G01X153543Y1442520D02*
X156693Y1441339D01*
G01X153543Y1437520D02*
X156693Y1436339D01*
G01X153543Y1432520D02*
X156693Y1431339D01*
G01X161417Y1446240D02*
Y1446339D01*
G01Y1444567D02*
Y1444666D01*
G01D02*
Y1446240D01*
G01Y1441240D02*
Y1441339D01*
G01Y1439567D02*
Y1439666D01*
G01D02*
Y1441240D01*
G01Y1436240D02*
Y1436339D01*
G01Y1434567D02*
Y1434666D01*
G01D02*
Y1436240D01*
G01Y1431240D02*
Y1431339D01*
G01Y1429567D02*
Y1429666D01*
G01D02*
Y1431240D01*
G01X158464Y1444331D02*
Y1441575D01*
G01X155787Y1444666D02*
Y1446240D01*
G01Y1439666D02*
Y1441240D01*
G01Y1434666D02*
Y1436240D01*
G01Y1429666D02*
Y1431240D01*
G01X154212Y1444666D02*
Y1446240D01*
G01Y1439666D02*
Y1441240D01*
G01Y1434666D02*
Y1436240D01*
G01Y1429666D02*
Y1431240D01*
G01X153543Y1447520D02*
Y1448386D01*
G01Y1442520D02*
Y1443386D01*
G01Y1437520D02*
Y1438386D01*
G01Y1432520D02*
Y1433386D01*
G01Y1427520D02*
Y1428386D01*
G01X153425Y1431240D02*
Y1429666D01*
G01Y1436240D02*
Y1434666D01*
G01Y1441240D02*
Y1439666D01*
G01Y1446240D02*
Y1444666D01*
G01X153031Y1431240D02*
Y1429666D01*
G01Y1436240D02*
Y1434666D01*
G01Y1441240D02*
Y1439666D01*
G01Y1446240D02*
Y1444666D01*
G01X148110D02*
Y1446240D01*
G01Y1439666D02*
Y1441240D01*
G01Y1434666D02*
Y1436240D01*
G01Y1429666D02*
Y1431240D01*
G01X156693Y1429567D02*
X153543Y1428386D01*
G01X156693Y1434567D02*
X153543Y1433386D01*
G01X156693Y1439567D02*
X153543Y1438386D01*
G01X156693Y1444567D02*
X153543Y1443386D01*
G01X156102Y1468662D02*
X168110D01*
G01X162992Y1468563D02*
X165354D01*
G01X162992Y1466791D02*
X165354D01*
G01X156102Y1466693D02*
X168110D01*
G01X156102Y1465512D02*
X168110D01*
G01X162992Y1465414D02*
X165354D01*
G01X162992Y1463642D02*
X165354D01*
G01X156102Y1463543D02*
X168110D01*
G01X157915Y1452336D02*
X157781Y1452303D01*
G01X156102Y1462362D02*
X168110D01*
G01X162992Y1462264D02*
X165354D01*
G01X162992Y1460492D02*
X165354D01*
G01X156102Y1460394D02*
X168110D01*
G01X156102Y1459213D02*
X168110D01*
G01X162992Y1459114D02*
X165354D01*
G01X162992Y1457343D02*
X165354D01*
G01X156102Y1457244D02*
X168110D01*
G01X156102Y1456063D02*
X168110D01*
G01X162992Y1455965D02*
X165354D01*
G01X156977Y1454862D02*
X157077D01*
G01X157647Y1454829D02*
X157747D01*
G01X156977Y1454698D02*
X157077D01*
G01X157680Y1454666D02*
X157747D01*
G01X162992Y1454193D02*
X165354D01*
G01X156102Y1454095D02*
X168110D01*
G01X157747Y1453878D02*
X157680D01*
G01X157077Y1453845D02*
X156977D01*
G01X157747Y1453714D02*
X157647D01*
G01X157077Y1453681D02*
X156977D01*
G01X156943Y1453419D02*
X157111D01*
G01X157077Y1453222D02*
X156977D01*
G01X156102Y1452914D02*
X168110D01*
G01X162992Y1452815D02*
X165354D01*
G01X157680Y1452500D02*
X157747D01*
G01X157781Y1452303D02*
X157647D01*
G01X157283Y1451929D02*
X160630D01*
G01X161417Y1451339D02*
X157283D01*
G01X194685D02*
X165354D01*
G01Y1451240D02*
X195756D01*
G01X148110D02*
X165354D01*
G01Y1450748D02*
X197638D01*
G01X165354Y1449666D02*
X148110D01*
G01X195756D02*
X165354D01*
G01Y1449567D02*
X194685D01*
G01X156693D02*
X161417D01*
G01X157781Y1453320D02*
X157881Y1453288D01*
G01X157580Y1452533D02*
X157680Y1452500D01*
G01X156910Y1452434D02*
X157010Y1452402D01*
G01X160630Y1467480D02*
X162992Y1466791D01*
G01X160630Y1464331D02*
X162992Y1463642D01*
G01X160630Y1461181D02*
X162992Y1460492D01*
G01X160630Y1458032D02*
X162992Y1457343D01*
G01X160630Y1454882D02*
X162992Y1454193D01*
G01X157647Y1452303D02*
X157513Y1452336D01*
G01X157010Y1452205D02*
X156876Y1452238D01*
G01X157647Y1453714D02*
X157513Y1453780D01*
G01X157848Y1453091D02*
X157781Y1453123D01*
G01X157111Y1453419D02*
X157245Y1453353D01*
G01X157747Y1454829D02*
X157915Y1454764D01*
G01X157077Y1454862D02*
X157245Y1454797D01*
G01X156977Y1453681D02*
X156809Y1453747D01*
G01X157747Y1454666D02*
X157848Y1454600D01*
G01X157680Y1453878D02*
X157580Y1453943D01*
G01X157178Y1453156D02*
X157077Y1453222D01*
G01X156876Y1452238D02*
X156709Y1452336D01*
G01X157077Y1454698D02*
X157211Y1454600D01*
G01X157881Y1453288D02*
X158016Y1453189D01*
G01X156977Y1453845D02*
X156843Y1453943D01*
G01X157915Y1454764D02*
X158016Y1454666D01*
G01X157513Y1453780D02*
X157412Y1453878D01*
G01X157915Y1453025D02*
X157848Y1453091D01*
G01X157245Y1453353D02*
X157379Y1453222D01*
G01X156809Y1453747D02*
X156709Y1453845D01*
G01X157513Y1452336D02*
X157379Y1452467D01*
G01X156809Y1452533D02*
X156910Y1452434D01*
G01X157245Y1453058D02*
X157178Y1453156D01*
G01X157513Y1452631D02*
X157580Y1452533D01*
G01X157848Y1454600D02*
X157948Y1454469D01*
G01X157245Y1454797D02*
X157345Y1454666D01*
G01X157580Y1453943D02*
X157479Y1454075D01*
G01X158016Y1453189D02*
X158116Y1453058D01*
G01X157345Y1454666D02*
X157379Y1454600D01*
G01X157211D02*
X157278Y1454469D01*
G01X157412Y1453878D02*
X157379Y1453943D01*
G01Y1453222D02*
X157446Y1453091D01*
G01X156843Y1453943D02*
X156776Y1454075D01*
G01X157379Y1452467D02*
X157312Y1452599D01*
G01X158016Y1454666D02*
X158116Y1454501D01*
G01X156709Y1453845D02*
X156608Y1454009D01*
G01X156709Y1452336D02*
X156608Y1452500D01*
G01X157948Y1452927D02*
X157915Y1453025D01*
G01X157479Y1452730D02*
X157513Y1452631D01*
G01X158116Y1454501D02*
X158149Y1454337D01*
G01X158145Y1452914D02*
X158149Y1452894D01*
G01X158116Y1453058D02*
X158145Y1452914D01*
G01X157446Y1453091D02*
X157479Y1452927D01*
G01X156591Y1454095D02*
X156575Y1454173D01*
G01X156608Y1454009D02*
X156591Y1454095D01*
G01X156608Y1452500D02*
X156575Y1452664D01*
G01X157948Y1454469D02*
X157982Y1454337D01*
G01X157474Y1454095D02*
X157446Y1454206D01*
G01X157479Y1454075D02*
X157474Y1454095D01*
G01X157278Y1454469D02*
X157312Y1454337D01*
G01X157278Y1452927D02*
X157245Y1453058D01*
G01X157312Y1452599D02*
X157278Y1452730D01*
G01X156771Y1454095D02*
X156742Y1454206D01*
G01X156776Y1454075D02*
X156771Y1454095D01*
G01X156776Y1452664D02*
X156809Y1452533D01*
G01X165354Y1456063D02*
Y1454095D01*
G01D02*
Y1452914D01*
G01Y1459213D02*
Y1457244D01*
G01D02*
Y1456063D01*
G01Y1460394D02*
Y1459213D01*
G01Y1462362D02*
Y1460394D01*
G01Y1465512D02*
Y1463543D01*
G01D02*
Y1462362D01*
G01Y1468662D02*
Y1466693D01*
G01D02*
Y1465512D01*
G01Y1469843D02*
Y1468662D01*
G01X163464Y1465512D02*
Y1466693D01*
G01Y1468662D02*
Y1469843D01*
G01Y1462362D02*
Y1463543D01*
G01Y1459213D02*
Y1460394D01*
G01Y1456063D02*
Y1457244D01*
G01Y1452914D02*
Y1454095D01*
G01X161890Y1468662D02*
Y1469843D01*
G01Y1465512D02*
Y1466693D01*
G01Y1462362D02*
Y1463543D01*
G01Y1459213D02*
Y1460394D01*
G01Y1456063D02*
Y1457244D01*
G01Y1452914D02*
Y1454095D01*
G01X161417Y1451240D02*
Y1451339D01*
G01Y1449567D02*
Y1449666D01*
G01D02*
Y1451240D01*
G01X161102Y1454095D02*
Y1452914D01*
G01Y1457244D02*
Y1456063D01*
G01Y1460394D02*
Y1459213D01*
G01Y1463543D02*
Y1462362D01*
G01Y1466693D02*
Y1465512D01*
G01Y1469843D02*
Y1468662D01*
G01X160708Y1454095D02*
Y1452914D01*
G01Y1460394D02*
Y1459213D01*
G01Y1457244D02*
Y1456063D01*
G01Y1463543D02*
Y1462362D01*
G01Y1466693D02*
Y1465512D01*
G01Y1469843D02*
Y1468662D01*
G01X160630Y1467480D02*
Y1467874D01*
G01Y1464331D02*
Y1464725D01*
G01Y1458032D02*
Y1458425D01*
G01Y1461181D02*
Y1461575D01*
G01Y1454882D02*
Y1455276D01*
G01Y1451929D02*
Y1452126D01*
G01X158149Y1454337D02*
Y1454206D01*
G01Y1452894D02*
Y1452730D01*
G01X157982Y1454337D02*
Y1454206D01*
G01X157948Y1452730D02*
Y1452914D01*
G01D02*
Y1452927D01*
G01X157781Y1453123D02*
Y1453320D01*
G01X157479Y1452914D02*
Y1452730D01*
G01Y1452927D02*
Y1452914D01*
G01X157446Y1454206D02*
Y1454337D01*
G01X157312D02*
Y1454206D01*
G01X157283Y1451339D02*
Y1451929D01*
G01X157278Y1452730D02*
Y1452914D01*
G01D02*
Y1452927D01*
G01X157010Y1452402D02*
Y1452205D01*
G01X156776Y1452914D02*
Y1452664D01*
G01Y1452927D02*
Y1452914D01*
G01X156742Y1454206D02*
Y1454337D01*
G01X156575Y1454173D02*
Y1454370D01*
G01Y1452664D02*
Y1452914D01*
G01D02*
Y1452927D01*
G01X156102Y1465512D02*
Y1466693D01*
G01Y1468662D02*
Y1469843D01*
G01Y1462362D02*
Y1463543D01*
G01Y1456063D02*
Y1457244D01*
G01Y1459213D02*
Y1460394D01*
G01Y1452914D02*
Y1454095D01*
G01X155787Y1449666D02*
Y1451240D01*
G01X154212Y1449666D02*
Y1451240D01*
G01X153425D02*
Y1449666D01*
G01X153031Y1451240D02*
Y1449666D01*
G01X158149Y1454206D02*
X158127Y1454095D01*
G01D02*
X158116Y1454042D01*
G01X148110Y1449666D02*
Y1451240D01*
G01X157915Y1452631D02*
X157948Y1452730D01*
G01X158149D02*
X158116Y1452599D01*
G01X157982Y1454206D02*
X157953Y1454095D01*
G01D02*
X157948Y1454075D01*
G01X157446Y1454337D02*
X157479Y1454469D01*
G01X157312Y1454206D02*
X157283Y1454095D01*
G01D02*
X157278Y1454075D01*
G01X156809Y1453058D02*
X156776Y1452927D01*
G01X156742Y1454337D02*
X156776Y1454469D01*
G01X156575Y1452927D02*
X156608Y1453091D01*
G01X156575Y1454370D02*
X156608Y1454534D01*
G01X162992Y1452815D02*
X160630Y1452126D01*
G01X162992Y1455965D02*
X160630Y1455276D01*
G01X162992Y1459114D02*
X160630Y1458425D01*
G01X162992Y1462264D02*
X160630Y1461575D01*
G01X162992Y1465414D02*
X160630Y1464725D01*
G01X162992Y1468563D02*
X160630Y1467874D01*
G01X157747Y1452500D02*
X157848Y1452533D01*
G01X156693Y1449567D02*
X153543Y1448386D01*
G01X157915Y1453780D02*
X157747Y1453714D01*
G01X157245Y1453747D02*
X157077Y1453681D01*
G01X156809Y1454797D02*
X156977Y1454862D01*
G01X156809Y1453353D02*
X156943Y1453419D01*
G01X157513Y1454764D02*
X157647Y1454829D01*
G01X156977Y1453222D02*
X156876Y1453156D01*
G01X157848Y1453943D02*
X157747Y1453878D01*
G01X157580Y1454600D02*
X157680Y1454666D01*
G01X157211Y1453943D02*
X157077Y1453845D01*
G01X156843Y1454600D02*
X156977Y1454698D01*
G01X158049Y1452467D02*
X157915Y1452336D01*
G01X158016Y1453878D02*
X157915Y1453780D01*
G01X156675Y1453222D02*
X156809Y1453353D01*
G01X157412Y1454666D02*
X157513Y1454764D01*
G01X156709Y1454698D02*
X156809Y1454797D01*
G01X157948Y1454075D02*
X157848Y1453943D01*
G01X157345Y1453878D02*
X157245Y1453747D01*
G01X157479Y1454469D02*
X157580Y1454600D01*
G01X157848Y1452533D02*
X157915Y1452631D01*
G01X156876Y1453156D02*
X156809Y1453058D01*
G01X158116Y1454042D02*
X158016Y1453878D01*
G01X156608Y1454534D02*
X156709Y1454698D01*
G01X158116Y1452599D02*
X158049Y1452467D01*
G01X157379Y1453943D02*
X157345Y1453878D01*
G01X157278Y1454075D02*
X157211Y1453943D01*
G01X156608Y1453091D02*
X156675Y1453222D01*
G01X157379Y1454600D02*
X157412Y1454666D01*
G01X156776Y1454469D02*
X156843Y1454600D01*
G01X158661Y1489567D02*
X153543Y1488386D01*
G01X166535Y1489666D02*
X195876D01*
G01X146653D02*
X166535D01*
G01Y1489567D02*
X197638D01*
G01X158661D02*
X163386D01*
G01X165354Y1488091D02*
X166535D01*
G01X165354Y1486339D02*
X197638D01*
G01X161417D02*
X156693D01*
G01X165354Y1486240D02*
X195876D01*
G01X148110D02*
X165354D01*
G01Y1484666D02*
X195876D01*
G01X165354D02*
X148110D01*
G01X165354Y1484567D02*
X197638D01*
G01X156693D02*
X161417D01*
G01X165354Y1481339D02*
X197638D01*
G01X161417D02*
X156693D01*
G01X165354Y1481240D02*
X195876D01*
G01X148110D02*
X165354D01*
G01Y1479666D02*
X148110D01*
G01X195876D02*
X165354D01*
G01Y1479567D02*
X197638D01*
G01X156693D02*
X161417D01*
G01X158464Y1479331D02*
X165354D01*
G01Y1476575D02*
X158464D01*
G01X150905Y1476398D02*
X149330D01*
G01X165354Y1476339D02*
X194685D01*
G01X161417D02*
X156693D01*
G01X165354Y1476240D02*
X195756D01*
G01X146653D02*
X165354D01*
G01X149330Y1476201D02*
X150637D01*
G01X150403Y1476004D02*
X150671D01*
G01X150537Y1475741D02*
X150403D01*
G01X150436Y1475545D02*
X150537D01*
G01X165354Y1475158D02*
X197638D01*
G01X150738Y1474725D02*
X150235D01*
G01X150034D02*
X149330D01*
G01X165354Y1474666D02*
X195756D01*
G01X146653D02*
X165354D01*
G01Y1474567D02*
X194685D01*
G01X157283D02*
X161417D01*
G01X149330Y1474528D02*
X150905D01*
G01X160630Y1473977D02*
X157283D01*
G01X162992Y1473091D02*
X165354D01*
G01X156102Y1472992D02*
X168110D01*
G01X156102Y1471811D02*
X168110D01*
G01X162992Y1471713D02*
X165354D01*
G01X162992Y1469941D02*
X165354D01*
G01X156102Y1469843D02*
X168110D01*
G01X153543Y1487520D02*
X156693Y1486339D01*
G01X153543Y1482520D02*
X156693Y1481339D01*
G01X153543Y1477520D02*
X156693Y1476339D01*
G01X150637Y1475709D02*
X150537Y1475741D01*
G01Y1475545D02*
X150637Y1475512D01*
G01X160630Y1473780D02*
X162992Y1473091D01*
G01X160630Y1470630D02*
X162992Y1469941D01*
G01X150771Y1475610D02*
X150637Y1475709D01*
G01Y1475512D02*
X150704Y1475446D01*
G01X150872Y1475479D02*
X150771Y1475610D01*
G01X150704Y1475446D02*
X150738Y1475348D01*
G01X150905Y1475315D02*
X150872Y1475479D01*
G01X166535Y1488091D02*
Y1492815D01*
G01X165354Y1472992D02*
Y1489666D01*
G01Y1471811D02*
Y1469843D01*
G01Y1472992D02*
Y1471811D01*
G01Y1491240D02*
Y1489666D01*
G01X163464Y1471811D02*
Y1472992D01*
G01X163386Y1489666D02*
Y1491240D01*
G01Y1489567D02*
Y1489666D01*
G01X161890Y1471811D02*
Y1472992D01*
G01X161417Y1486240D02*
Y1486339D01*
G01Y1484666D02*
Y1486240D01*
G01Y1484567D02*
Y1484666D01*
G01Y1481240D02*
Y1481339D01*
G01Y1479666D02*
Y1481240D01*
G01Y1479567D02*
Y1479666D01*
G01Y1476240D02*
Y1476339D01*
G01Y1474666D02*
Y1476240D01*
G01Y1474567D02*
Y1474666D01*
G01X161102Y1472992D02*
Y1471811D01*
G01X160708Y1472992D02*
Y1471811D01*
G01X160630Y1473780D02*
Y1473977D01*
G01Y1470630D02*
Y1471024D01*
G01X158464Y1479331D02*
Y1476575D01*
G01X157283Y1473977D02*
Y1474567D01*
G01X156102Y1471811D02*
Y1472992D01*
G01X155787Y1489666D02*
Y1491240D01*
G01Y1484666D02*
Y1486240D01*
G01Y1479666D02*
Y1481240D01*
G01Y1474666D02*
Y1476240D01*
G01X154212Y1489666D02*
Y1491240D01*
G01Y1484666D02*
Y1486240D01*
G01Y1479666D02*
Y1481240D01*
G01Y1474666D02*
Y1476240D01*
G01X153543Y1487520D02*
Y1488386D01*
G01Y1482520D02*
Y1483386D01*
G01Y1477520D02*
Y1478386D01*
G01X153425Y1476240D02*
Y1474666D01*
G01Y1481240D02*
Y1479666D01*
G01Y1486240D02*
Y1484666D01*
G01Y1491240D02*
Y1489666D01*
G01X153031Y1476240D02*
Y1474666D01*
G01Y1481240D02*
Y1479666D01*
G01Y1486240D02*
Y1484666D01*
G01Y1491240D02*
Y1489666D01*
G01X150905Y1476240D02*
Y1476398D01*
G01Y1476201D02*
Y1476240D01*
G01Y1474528D02*
Y1474666D01*
G01D02*
Y1475315D01*
G01X150738Y1475348D02*
Y1474725D01*
G01X150235D02*
Y1475348D01*
G01X150034Y1475315D02*
Y1474725D01*
G01X149330Y1474666D02*
Y1474528D01*
G01Y1474725D02*
Y1474666D01*
G01Y1476398D02*
Y1476240D01*
G01D02*
Y1476201D01*
G01X148110Y1484666D02*
Y1486240D01*
G01Y1479666D02*
Y1481240D01*
G01X146653Y1489666D02*
Y1491240D01*
G01Y1474666D02*
Y1476240D01*
G01X150235Y1475348D02*
X150269Y1475446D01*
G01X150067Y1475479D02*
X150034Y1475315D01*
G01X162992Y1471713D02*
X160630Y1471024D01*
G01X150336Y1475512D02*
X150436Y1475545D01*
G01X150403Y1475741D02*
X150302Y1475709D01*
G01X156693Y1479567D02*
X153543Y1478386D01*
G01X156693Y1484567D02*
X153543Y1483386D01*
G01X150168Y1475610D02*
X150067Y1475479D01*
G01X150302Y1475709D02*
X150168Y1475610D01*
G01X150671Y1476004D02*
X150905Y1476201D01*
G01X150637D02*
X150403Y1476004D01*
G01X150269Y1475446D02*
X150336Y1475512D01*
G01X165354Y1511339D02*
X197638D01*
G01X161417D02*
X156693D01*
G01X165354Y1511240D02*
X195876D01*
G01X148110D02*
X165354D01*
G01Y1509666D02*
X195876D01*
G01X165354D02*
X148110D01*
G01X165354Y1509567D02*
X197638D01*
G01X156693D02*
X161417D01*
G01X165354Y1506339D02*
X197638D01*
G01X161417D02*
X156693D01*
G01X165354Y1506240D02*
X195876D01*
G01X148110D02*
X165354D01*
G01Y1504666D02*
X195876D01*
G01X165354D02*
X148110D01*
G01X165354Y1504567D02*
X197638D01*
G01X156693D02*
X161417D01*
G01X158464Y1504331D02*
X165354D01*
G01Y1501575D02*
X158464D01*
G01X165354Y1501339D02*
X197638D01*
G01X161417D02*
X156693D01*
G01X165354Y1501240D02*
X195876D01*
G01X148110D02*
X165354D01*
G01Y1499666D02*
X195876D01*
G01X165354D02*
X148110D01*
G01X165354Y1499567D02*
X197638D01*
G01X156693D02*
X161417D01*
G01X165354Y1496339D02*
X197638D01*
G01X161417D02*
X156693D01*
G01X165354Y1496240D02*
X195876D01*
G01X148110D02*
X165354D01*
G01Y1494666D02*
X195876D01*
G01X165354D02*
X148110D01*
G01X165354Y1494567D02*
X197638D01*
G01X156693D02*
X161417D01*
G01X166535Y1492815D02*
X165354D01*
G01X163386Y1491339D02*
X158661D01*
G01X197638D02*
X166535D01*
G01Y1491240D02*
X195876D01*
G01X146653D02*
X166535D01*
G01X153543Y1492520D02*
X158661Y1491339D01*
G01X153543Y1512520D02*
X156693Y1511339D01*
G01X153543Y1507520D02*
X156693Y1506339D01*
G01X153543Y1502520D02*
X156693Y1501339D01*
G01X153543Y1497520D02*
X156693Y1496339D01*
G01X165354Y1491240D02*
Y1529666D01*
G01X163386Y1491240D02*
Y1491339D01*
G01X161417Y1511240D02*
Y1511339D01*
G01Y1509567D02*
Y1509666D01*
G01D02*
Y1511240D01*
G01Y1506240D02*
Y1506339D01*
G01Y1504567D02*
Y1504666D01*
G01D02*
Y1506240D01*
G01Y1501240D02*
Y1501339D01*
G01Y1499567D02*
Y1499666D01*
G01D02*
Y1501240D01*
G01Y1496240D02*
Y1496339D01*
G01Y1494567D02*
Y1494666D01*
G01D02*
Y1496240D01*
G01X158464Y1504331D02*
Y1501575D01*
G01X155787Y1509666D02*
Y1511240D01*
G01Y1504666D02*
Y1506240D01*
G01Y1499666D02*
Y1501240D01*
G01Y1494666D02*
Y1496240D01*
G01X154212Y1509666D02*
Y1511240D01*
G01Y1504666D02*
Y1506240D01*
G01Y1499666D02*
Y1501240D01*
G01Y1494666D02*
Y1496240D01*
G01X153543Y1507520D02*
Y1508386D01*
G01Y1502520D02*
Y1503386D01*
G01Y1497520D02*
Y1498386D01*
G01Y1492520D02*
Y1493386D01*
G01X153425Y1496240D02*
Y1494666D01*
G01Y1501240D02*
Y1499666D01*
G01Y1506240D02*
Y1504666D01*
G01Y1511240D02*
Y1509666D01*
G01X153031Y1496240D02*
Y1494666D01*
G01Y1501240D02*
Y1499666D01*
G01Y1506240D02*
Y1504666D01*
G01Y1511240D02*
Y1509666D01*
G01X148110D02*
Y1511240D01*
G01Y1504666D02*
Y1506240D01*
G01Y1499666D02*
Y1501240D01*
G01Y1494666D02*
Y1496240D01*
G01X156693Y1494567D02*
X153543Y1493386D01*
G01X156693Y1499567D02*
X153543Y1498386D01*
G01X156693Y1504567D02*
X153543Y1503386D01*
G01X156693Y1509567D02*
X153543Y1508386D01*
G01X158661Y1529567D02*
X153543Y1528386D01*
G01X163386Y1531339D02*
X158661D01*
G01X197638D02*
X166535D01*
G01Y1531240D02*
X195876D01*
G01X146653D02*
X166535D01*
G01Y1529666D02*
X195876D01*
G01X146653D02*
X166535D01*
G01Y1529567D02*
X197638D01*
G01X158661D02*
X163386D01*
G01X158464Y1529331D02*
X165354D01*
G01Y1528091D02*
X166535D01*
G01X165354Y1526575D02*
X158464D01*
G01X165354Y1526339D02*
X197638D01*
G01X161417D02*
X156693D01*
G01X165354Y1526240D02*
X195876D01*
G01X148110D02*
X165354D01*
G01Y1524666D02*
X195876D01*
G01X165354D02*
X148110D01*
G01X165354Y1524567D02*
X197638D01*
G01X156693D02*
X161417D01*
G01X165354Y1521339D02*
X197638D01*
G01X161417D02*
X156693D01*
G01X165354Y1521240D02*
X195876D01*
G01X148110D02*
X165354D01*
G01Y1519666D02*
X195876D01*
G01X165354D02*
X148110D01*
G01X165354Y1519567D02*
X197638D01*
G01X156693D02*
X161417D01*
G01X165354Y1516339D02*
X197638D01*
G01X161417D02*
X156693D01*
G01X165354Y1516240D02*
X195876D01*
G01X148110D02*
X165354D01*
G01Y1514666D02*
X195876D01*
G01X165354D02*
X148110D01*
G01X165354Y1514567D02*
X197638D01*
G01X156693D02*
X161417D01*
G01X153543Y1532520D02*
X158661Y1531339D01*
G01X153543Y1527520D02*
X156693Y1526339D01*
G01X153543Y1522520D02*
X156693Y1521339D01*
G01X153543Y1517520D02*
X156693Y1516339D01*
G01X166535Y1528091D02*
Y1532815D01*
G01X165354Y1531240D02*
Y1551043D01*
G01Y1531240D02*
Y1529666D01*
G01X163386Y1531240D02*
Y1531339D01*
G01Y1529567D02*
Y1529666D01*
G01D02*
Y1531240D01*
G01X161417Y1526240D02*
Y1526339D01*
G01Y1524567D02*
Y1524666D01*
G01D02*
Y1526240D01*
G01Y1521240D02*
Y1521339D01*
G01Y1519567D02*
Y1519666D01*
G01D02*
Y1521240D01*
G01Y1516240D02*
Y1516339D01*
G01Y1514567D02*
Y1514666D01*
G01D02*
Y1516240D01*
G01X158464Y1529331D02*
Y1526575D01*
G01X155787Y1529666D02*
Y1531240D01*
G01Y1524666D02*
Y1526240D01*
G01Y1519666D02*
Y1521240D01*
G01Y1514666D02*
Y1516240D01*
G01X154212Y1529666D02*
Y1531240D01*
G01Y1524666D02*
Y1526240D01*
G01Y1519666D02*
Y1521240D01*
G01Y1514666D02*
Y1516240D01*
G01X153543Y1532520D02*
Y1533386D01*
G01Y1527520D02*
Y1528386D01*
G01Y1522520D02*
Y1523386D01*
G01Y1517520D02*
Y1518386D01*
G01Y1512520D02*
Y1513386D01*
G01X153425Y1516240D02*
Y1514666D01*
G01Y1521240D02*
Y1519666D01*
G01Y1526240D02*
Y1524666D01*
G01Y1531240D02*
Y1529666D01*
G01X153031Y1516240D02*
Y1514666D01*
G01Y1521240D02*
Y1519666D01*
G01Y1526240D02*
Y1524666D01*
G01Y1531240D02*
Y1529666D01*
G01X148110Y1524666D02*
Y1526240D01*
G01Y1519666D02*
Y1521240D01*
G01Y1514666D02*
Y1516240D01*
G01X146653Y1529666D02*
Y1531240D01*
G01X156693Y1514567D02*
X153543Y1513386D01*
G01X156693Y1519567D02*
X153543Y1518386D01*
G01X156693Y1524567D02*
X153543Y1523386D01*
G01X165354Y1551043D02*
X145669D01*
G01Y1549272D02*
X165354D01*
G01D02*
X166634D01*
G01X161417Y1546339D02*
X156693D01*
G01X197638D02*
X165354D01*
G01Y1546240D02*
X195876D01*
G01X148110D02*
X165354D01*
G01Y1544666D02*
X195876D01*
G01X165354D02*
X148110D01*
G01X165354Y1544567D02*
X197638D01*
G01X156693D02*
X161417D01*
G01X165354Y1541339D02*
X197638D01*
G01X161417D02*
X156693D01*
G01X165354Y1541240D02*
X195876D01*
G01X148110D02*
X165354D01*
G01Y1539666D02*
X195876D01*
G01X165354D02*
X148110D01*
G01X165354Y1539567D02*
X197638D01*
G01X156693D02*
X161417D01*
G01X165354Y1536339D02*
X197638D01*
G01X161417D02*
X156693D01*
G01X165354Y1536240D02*
X195876D01*
G01X148110D02*
X165354D01*
G01Y1534666D02*
X195876D01*
G01X165354D02*
X148110D01*
G01X165354Y1534567D02*
X197638D01*
G01X156693D02*
X161417D01*
G01X166535Y1532815D02*
X165354D01*
G01X153543Y1547520D02*
X156693Y1546339D01*
G01X153543Y1542520D02*
X156693Y1541339D01*
G01X153543Y1537520D02*
X156693Y1536339D01*
G01X161417Y1546240D02*
Y1546339D01*
G01Y1544666D02*
Y1546240D01*
G01Y1544567D02*
Y1544666D01*
G01Y1541240D02*
Y1541339D01*
G01Y1539567D02*
Y1539666D01*
G01D02*
Y1541240D01*
G01Y1536240D02*
Y1536339D01*
G01Y1534567D02*
Y1534666D01*
G01D02*
Y1536240D01*
G01X155787Y1544666D02*
Y1546240D01*
G01Y1539666D02*
Y1541240D01*
G01Y1534666D02*
Y1536240D01*
G01X154212Y1544666D02*
Y1546240D01*
G01Y1539666D02*
Y1541240D01*
G01Y1534666D02*
Y1536240D01*
G01X153543Y1547520D02*
Y1549272D01*
G01Y1542520D02*
Y1543386D01*
G01Y1537520D02*
Y1538386D01*
G01X153425Y1536240D02*
Y1534666D01*
G01Y1541240D02*
Y1539666D01*
G01Y1546240D02*
Y1544666D01*
G01X153031Y1536240D02*
Y1534666D01*
G01Y1541240D02*
Y1539666D01*
G01Y1546240D02*
Y1544666D01*
G01X148110D02*
Y1546240D01*
G01Y1539666D02*
Y1541240D01*
G01Y1534666D02*
Y1536240D01*
G01X145669Y1549272D02*
Y1562540D01*
G01X156693Y1534567D02*
X153543Y1533386D01*
G01X156693Y1539567D02*
X153543Y1538386D01*
G01X156693Y1544567D02*
X153543Y1543386D01*
G01X155700Y1555392D02*
Y1555394D01*
G01X155687Y1555361D02*
X155700Y1555392D01*
G01X160442Y1560119D02*
X160441Y1560118D01*
G01X160455Y1560151D02*
X160442Y1560119D01*
G01X155934Y1555929D02*
X156054Y1556181D01*
G01X155816Y1555667D02*
X155934Y1555929D01*
G01X155700Y1555394D02*
X155816Y1555667D01*
G01X160321Y1559836D02*
X160441Y1560118D01*
G01X160203Y1559573D02*
X160321Y1559836D01*
G01X160088Y1559331D02*
X160203Y1559573D01*
G01X160325Y1555666D02*
X160441Y1555394D01*
G01X160207Y1555929D02*
X160325Y1555666D01*
G01X160088Y1556181D02*
X160207Y1555929D01*
G01X155939Y1559573D02*
X156054Y1559331D01*
G01X155821Y1559835D02*
X155939Y1559573D01*
G01X155700Y1560118D02*
X155821Y1559835D01*
G01X155484Y1560662D02*
X155466Y1560709D01*
G01X155519Y1560570D02*
X155484Y1560662D01*
G01X156054Y1559331D02*
G03Y1556181I2017J-1575D01*
G01X160088D02*
G03Y1559331I-2017J1575D01*
G01X155700Y1560118D02*
G03Y1555394I2371J-2362D01*
G01X160441D02*
G03Y1560118I-2370J2362D01*
G01X161575Y1557756D02*
G03I-3504J0D01*
G01X171063Y1569567D02*
G03I-3740J0D01*
G01X160748Y1554606D02*
G03Y1560906I-2677J3150D01*
G01X155393D02*
G03Y1554606I2677J-3150D01*
G01X177165Y1573524D02*
X157480D01*
G01X177165Y1571536D02*
X157480D01*
G01Y1570551D02*
X177165D01*
G01X176968Y1570354D02*
X157677D01*
G01X176968Y1568780D02*
X157677D01*
G01X177165Y1568583D02*
X157480D01*
G01Y1567599D02*
X177165D01*
G01Y1564508D02*
X157480D01*
G01X199606Y1562540D02*
X145669D01*
G01X166142Y1561358D02*
X199606D01*
G01X155393Y1560906D02*
X160748D01*
G01X160441Y1560118D02*
X155700D01*
G01X156054Y1559331D02*
X160088D01*
G01X166142Y1557146D02*
X145669D01*
G01X177165D02*
X166142D01*
G01X156054Y1556181D02*
X160088D01*
G01X155700Y1555394D02*
X160441D01*
G01X160748Y1554606D02*
X155393D01*
G01X195669Y1554193D02*
X145669D01*
G01X160658Y1554850D02*
X160693Y1554754D01*
G01X160623Y1554942D02*
X160658Y1554850D01*
G01X160589Y1555028D02*
X160623Y1554942D01*
G01X155552Y1560484D02*
X155519Y1560570D01*
G01X160517Y1555207D02*
X160589Y1555028D01*
G01X155624Y1560305D02*
X155552Y1560484D01*
G01X160484Y1555288D02*
X160517Y1555207D01*
G01X155657Y1560224D02*
X155624Y1560305D01*
G01X160441Y1555394D02*
X160484Y1555288D01*
G01X155700Y1560118D02*
X155657Y1560224D01*
G01X160693Y1554754D02*
X160748Y1554606D01*
G01X155430Y1560806D02*
X155393Y1560906D01*
G01X155466Y1560709D02*
X155430Y1560806D01*
G01X166142Y1554193D02*
Y1562540D01*
G01Y1570354D02*
Y1568780D01*
G01X164567D02*
Y1570354D01*
G01X164370D02*
Y1570551D01*
G01Y1568780D02*
Y1570354D01*
G01Y1568780D02*
Y1568583D01*
G01X163031Y1568780D02*
Y1570354D01*
G01X157677D02*
Y1568780D01*
G01X157480Y1562540D02*
Y1575492D01*
G01X153543Y1566477D02*
Y1579429D01*
G01X160495Y1560249D02*
X160455Y1560151D01*
G01X155647Y1555264D02*
X155687Y1555361D01*
G01X160530Y1560337D02*
X160495Y1560249D01*
G01X155611Y1555175D02*
X155647Y1555264D01*
G01X160589Y1560484D02*
X160530Y1560337D01*
G01X155553Y1555028D02*
X155611Y1555175D01*
G01X160623Y1560570D02*
X160589Y1560484D01*
G01X155519Y1554942D02*
X155553Y1555028D01*
G01X160658Y1560662D02*
X160623Y1560570D01*
G01X155484Y1554850D02*
X155519Y1554942D01*
G01X160693Y1560758D02*
X160658Y1560662D01*
G01X155448Y1554754D02*
X155484Y1554850D01*
G01X160748Y1560906D02*
X160693Y1560758D01*
G01X155393Y1554606D02*
X155448Y1554754D01*
G01X153543Y1579429D02*
X181102D01*
G01X177165Y1575492D02*
X157480D01*
G01X164173Y1784882D02*
G03Y1786063I0J590D01*
G01Y1782126D02*
G03Y1783307I0J591D01*
G01Y1786358D02*
X162598D01*
G01X165748D02*
X164173D01*
G01X162598Y1784390D02*
X164173D01*
G01D02*
X165748D01*
G01X162598Y1783799D02*
X164173D01*
G01D02*
X165748D01*
G01X164173Y1781831D02*
X162598D01*
G01X165748D02*
X164173D01*
G01Y1781536D02*
X170472D01*
G01X165748Y1784390D02*
Y1786358D01*
G01Y1783799D02*
Y1781831D01*
G01X165354Y1781536D02*
Y1786654D01*
G01X165157D02*
Y1781536D01*
G01X164173Y1782126D02*
Y1781536D01*
G01Y1784882D02*
Y1783307D01*
G01Y1786654D02*
Y1786063D01*
G01X162598Y1781831D02*
Y1783799D01*
G01Y1786358D02*
Y1784390D01*
G01X171063Y1801851D02*
G03I-3740J0D01*
G01X157480Y1806910D02*
X177165D01*
G01Y1803819D02*
X157480D01*
G01Y1802835D02*
X177165D01*
G01X176968Y1802638D02*
X157677D01*
G01X176968Y1801063D02*
X157677D01*
G01X177165Y1800866D02*
X157480D01*
G01Y1799882D02*
X177165D01*
G01X157480Y1797894D02*
X177165D01*
G01X157480Y1795925D02*
X177165D01*
G01X181102Y1791988D02*
X153543D01*
G01X164173Y1786654D02*
X170472D01*
G01X166142Y1802638D02*
Y1801063D01*
G01X164567D02*
Y1802638D01*
G01X164370D02*
Y1802835D01*
G01Y1801063D02*
Y1802638D01*
G01Y1801063D02*
Y1800866D01*
G01X163031Y1801063D02*
Y1802638D01*
G01X157677D02*
Y1801063D01*
G01X157480Y1795925D02*
Y1808878D01*
G01X153543Y1791988D02*
Y1804941D01*
G01X160630Y1813662D02*
G03I-2559J0D01*
G01X161417D02*
G03I-3346J0D01*
G01X161575D02*
G03I-3504J0D01*
G01X158145Y1809528D02*
G03X158071Y1817795I-74J4133D01*
G01X157996D02*
G03X158071Y1809528I73J-4133D01*
G01X150631Y1825131D02*
X150497Y1825099D01*
G01X150866Y1826870D02*
X149291D01*
G01X165354Y1826851D02*
X197638D01*
G01X161417D02*
X156693D01*
G01X165354Y1826752D02*
X195876D01*
G01X148110D02*
X165354D01*
G01X149291Y1826673D02*
X150598D01*
G01X150364Y1826477D02*
X150631D01*
G01X149660Y1826214D02*
X149827D01*
G01X149794Y1826017D02*
X149693D01*
G01X150397Y1825295D02*
X150464D01*
G01X165354Y1825177D02*
X195876D01*
G01X165354D02*
X148110D01*
G01X150497Y1825099D02*
X150364D01*
G01X165354Y1825079D02*
X197638D01*
G01X156693D02*
X161417D01*
G01X165354Y1822146D02*
X166634D01*
G01X165354D02*
X145669D01*
G01Y1820374D02*
X165354D01*
G01X145669Y1817225D02*
X195669D01*
G01X166142Y1814272D02*
X177165D01*
G01X145669D02*
X166142D01*
G01X199606Y1810059D02*
X166142D01*
G01X199606Y1808878D02*
X145669D01*
G01X157996Y1817795D02*
X158071D01*
G01X158145Y1809528D02*
X158071D01*
G01X150364Y1825099D02*
X150229Y1825131D01*
G01X149727Y1825000D02*
X149593Y1825033D01*
G01X153543Y1828032D02*
X156693Y1826851D01*
G01X150497Y1826116D02*
X150598Y1826083D01*
G01X150296Y1825328D02*
X150397Y1825295D01*
G01X149626Y1825230D02*
X149727Y1825197D01*
G01X150564Y1825886D02*
X150497Y1825919D01*
G01X149827Y1826214D02*
X149961Y1826148D01*
G01X149894Y1825951D02*
X149794Y1826017D01*
G01X149593Y1825033D02*
X149425Y1825131D01*
G01X150598Y1826083D02*
X150732Y1825984D01*
G01X150631Y1825820D02*
X150564Y1825886D01*
G01X149961Y1826148D02*
X150095Y1826017D01*
G01X150229Y1825131D02*
X150182Y1825177D01*
G01D02*
X150095Y1825262D01*
G01X149526Y1825328D02*
X149626Y1825230D01*
G01X150732Y1825984D02*
X150832Y1825853D01*
G01X149397Y1825177D02*
X149325Y1825295D01*
G01X149425Y1825131D02*
X149397Y1825177D01*
G01X149961Y1825853D02*
X149894Y1825951D01*
G01X150229Y1825427D02*
X150296Y1825328D01*
G01X150095Y1826017D02*
X150162Y1825886D01*
G01X150095Y1825262D02*
X150028Y1825394D01*
G01X150665Y1825722D02*
X150631Y1825820D01*
G01X150196Y1825525D02*
X150229Y1825427D01*
G01X150832Y1825853D02*
X150866Y1825689D01*
G01X150162Y1825886D02*
X150196Y1825722D01*
G01X149325Y1825295D02*
X149291Y1825459D01*
G01X149995Y1825722D02*
X149961Y1825853D01*
G01X150028Y1825394D02*
X149995Y1825525D01*
G01X149492Y1825459D02*
X149526Y1825328D01*
G01X166634Y1954784D02*
Y1822146D01*
G01X166142Y1808878D02*
Y1817225D01*
G01X165354Y1820374D02*
Y1858425D01*
G01X161417Y1826752D02*
Y1826851D01*
G01Y1825079D02*
Y1825177D01*
G01D02*
Y1826752D01*
G01X155787Y1825177D02*
Y1826752D01*
G01X154212Y1825177D02*
Y1826752D01*
G01X153543Y1828032D02*
Y1828898D01*
G01Y1822146D02*
Y1823898D01*
G01X153425Y1826752D02*
Y1825177D01*
G01X153031Y1826752D02*
Y1825177D01*
G01X150866Y1826752D02*
Y1826870D01*
G01Y1826673D02*
Y1826752D01*
G01Y1825689D02*
Y1825525D01*
G01X150665D02*
Y1825722D01*
G01X150497Y1825919D02*
Y1826116D01*
G01X150196Y1825722D02*
Y1825525D01*
G01X149995D02*
Y1825722D01*
G01X149727Y1825177D02*
Y1825000D01*
G01Y1825197D02*
Y1825177D01*
G01X149492Y1825722D02*
Y1825459D01*
G01X149291D02*
Y1825722D01*
G01Y1826870D02*
Y1826752D01*
G01D02*
Y1826673D01*
G01X148110Y1825177D02*
Y1826752D01*
G01X145669Y1808878D02*
Y1822146D01*
G01X150866Y1825525D02*
X150832Y1825394D01*
G01X149526Y1825853D02*
X149492Y1825722D01*
G01X149291D02*
X149325Y1825886D01*
G01X150631Y1825427D02*
X150665Y1825525D01*
G01X150832Y1825394D02*
X150766Y1825262D01*
G01X149325Y1825886D02*
X149392Y1826017D01*
G01X150564Y1825328D02*
X150631Y1825427D01*
G01X149593Y1825951D02*
X149526Y1825853D01*
G01X150464Y1825295D02*
X150564Y1825328D01*
G01X149693Y1826017D02*
X149593Y1825951D01*
G01X150631Y1826477D02*
X150866Y1826673D01*
G01X150598D02*
X150364Y1826477D01*
G01X150679Y1825177D02*
X150631Y1825131D01*
G01X150766Y1825262D02*
X150679Y1825177D01*
G01X149392Y1826017D02*
X149526Y1826148D01*
G01X156693Y1825079D02*
X153543Y1823898D01*
G01X149526Y1826148D02*
X149660Y1826214D01*
G01X158464Y1849843D02*
X165354D01*
G01Y1847087D02*
X158464D01*
G01X165354Y1846851D02*
X197638D01*
G01X161417D02*
X156693D01*
G01X165354Y1846752D02*
X195876D01*
G01X148110D02*
X165354D01*
G01Y1845177D02*
X195876D01*
G01X165354D02*
X148110D01*
G01X165354Y1845079D02*
X197638D01*
G01X156693D02*
X161417D01*
G01X165354Y1841851D02*
X197638D01*
G01X161417D02*
X156693D01*
G01X165354Y1841752D02*
X195876D01*
G01X148110D02*
X165354D01*
G01Y1840177D02*
X195876D01*
G01X165354D02*
X148110D01*
G01X165354Y1840079D02*
X197638D01*
G01X156693D02*
X161417D01*
G01X165354Y1836851D02*
X197638D01*
G01X161417D02*
X156693D01*
G01X165354Y1836752D02*
X195876D01*
G01X148110D02*
X165354D01*
G01Y1835177D02*
X195876D01*
G01X165354D02*
X148110D01*
G01X165354Y1835079D02*
X197638D01*
G01X156693D02*
X161417D01*
G01X165354Y1831851D02*
X197638D01*
G01X161417D02*
X156693D01*
G01X165354Y1831752D02*
X195876D01*
G01X148110D02*
X165354D01*
G01Y1830177D02*
X195876D01*
G01X165354D02*
X148110D01*
G01X165354Y1830079D02*
X197638D01*
G01X156693D02*
X161417D01*
G01X153543Y1848032D02*
X156693Y1846851D01*
G01X153543Y1843032D02*
X156693Y1841851D01*
G01X153543Y1838032D02*
X156693Y1836851D01*
G01X153543Y1833032D02*
X156693Y1831851D01*
G01X161417Y1846752D02*
Y1846851D01*
G01Y1845177D02*
Y1846752D01*
G01Y1845079D02*
Y1845177D01*
G01Y1841752D02*
Y1841851D01*
G01Y1840177D02*
Y1841752D01*
G01Y1840079D02*
Y1840177D01*
G01Y1836752D02*
Y1836851D01*
G01Y1835177D02*
Y1836752D01*
G01Y1835079D02*
Y1835177D01*
G01Y1831752D02*
Y1831851D01*
G01Y1830177D02*
Y1831752D01*
G01Y1830079D02*
Y1830177D01*
G01X158464Y1849843D02*
Y1847087D01*
G01X155787Y1845177D02*
Y1846752D01*
G01Y1840177D02*
Y1841752D01*
G01Y1835177D02*
Y1836752D01*
G01Y1830177D02*
Y1831752D01*
G01X154212Y1845177D02*
Y1846752D01*
G01Y1840177D02*
Y1841752D01*
G01Y1835177D02*
Y1836752D01*
G01Y1830177D02*
Y1831752D01*
G01X153543Y1848032D02*
Y1848898D01*
G01Y1843032D02*
Y1843898D01*
G01Y1838032D02*
Y1838898D01*
G01Y1833032D02*
Y1833898D01*
G01X153425Y1831752D02*
Y1830177D01*
G01Y1836752D02*
Y1835177D01*
G01Y1841752D02*
Y1840177D01*
G01Y1846752D02*
Y1845177D01*
G01X153031Y1831752D02*
Y1830177D01*
G01Y1836752D02*
Y1835177D01*
G01Y1841752D02*
Y1840177D01*
G01Y1846752D02*
Y1845177D01*
G01X148110D02*
Y1846752D01*
G01Y1840177D02*
Y1841752D01*
G01Y1835177D02*
Y1836752D01*
G01Y1830177D02*
Y1831752D01*
G01X156693Y1830079D02*
X153543Y1828898D01*
G01X156693Y1835079D02*
X153543Y1833898D01*
G01X156693Y1840079D02*
X153543Y1838898D01*
G01X156693Y1845079D02*
X153543Y1843898D01*
G01X156693Y1850079D02*
X153543Y1848898D01*
G01X156102Y1871024D02*
X168110D01*
G01X162992Y1870925D02*
X165354D01*
G01X162992Y1869154D02*
X165354D01*
G01X156102Y1869055D02*
X168110D01*
G01X156102Y1867874D02*
X168110D01*
G01X162992Y1867776D02*
X165354D01*
G01X162992Y1866004D02*
X165354D01*
G01X156102Y1865906D02*
X168110D01*
G01X156102Y1864725D02*
X168110D01*
G01X162992Y1864626D02*
X165354D01*
G01X162992Y1862854D02*
X165354D01*
G01X156102Y1862756D02*
X168110D01*
G01X156102Y1861575D02*
X168110D01*
G01X162992Y1861477D02*
X165354D01*
G01X156977Y1860374D02*
X157077D01*
G01X157647Y1860341D02*
X157747D01*
G01X156977Y1860210D02*
X157077D01*
G01X157680Y1860177D02*
X157747D01*
G01X162992Y1859705D02*
X165354D01*
G01X156102Y1859606D02*
X168110D01*
G01X157747Y1859390D02*
X157680D01*
G01X157077Y1859357D02*
X156977D01*
G01X157747Y1859226D02*
X157647D01*
G01X157077Y1859193D02*
X156977D01*
G01X156943Y1858930D02*
X157111D01*
G01X157077Y1858734D02*
X156977D01*
G01X156102Y1858425D02*
X168110D01*
G01X162992Y1858327D02*
X165354D01*
G01X157680Y1858012D02*
X157747D01*
G01X157781Y1857815D02*
X157647D01*
G01X157283Y1857441D02*
X160630D01*
G01X161417Y1856851D02*
X157283D01*
G01X194685D02*
X165354D01*
G01Y1856752D02*
X195756D01*
G01X148110D02*
X165354D01*
G01Y1856260D02*
X197638D01*
G01X165354Y1855177D02*
X148110D01*
G01X195756D02*
X165354D01*
G01Y1855079D02*
X194685D01*
G01X156693D02*
X161417D01*
G01Y1851851D02*
X156693D01*
G01X197638D02*
X165354D01*
G01Y1851752D02*
X195876D01*
G01X148110D02*
X165354D01*
G01Y1850177D02*
X195876D01*
G01X165354D02*
X148110D01*
G01X165354Y1850079D02*
X197638D01*
G01X156693D02*
X161417D01*
G01X157915Y1857848D02*
X157781Y1857815D01*
G01Y1858832D02*
X157881Y1858799D01*
G01X157580Y1858045D02*
X157680Y1858012D01*
G01X156910Y1857946D02*
X157010Y1857914D01*
G01X160630Y1869843D02*
X162992Y1869154D01*
G01X160630Y1866693D02*
X162992Y1866004D01*
G01X160630Y1863543D02*
X162992Y1862854D01*
G01X160630Y1860394D02*
X162992Y1859705D01*
G01X157647Y1857815D02*
X157513Y1857848D01*
G01X157010Y1857717D02*
X156876Y1857749D01*
G01X157747Y1860341D02*
X157915Y1860276D01*
G01X157077Y1860374D02*
X157245Y1860308D01*
G01X156977Y1859193D02*
X156809Y1859258D01*
G01X153543Y1853032D02*
X156693Y1851851D01*
G01X156876Y1857749D02*
X156709Y1857848D01*
G01X157647Y1859226D02*
X157513Y1859291D01*
G01X157848Y1858603D02*
X157781Y1858635D01*
G01X157111Y1858930D02*
X157245Y1858865D01*
G01X157077Y1860210D02*
X157211Y1860112D01*
G01X157881Y1858799D02*
X158016Y1858701D01*
G01X156977Y1859357D02*
X156843Y1859455D01*
G01X157747Y1860177D02*
X157848Y1860112D01*
G01X157680Y1859390D02*
X157580Y1859455D01*
G01X157178Y1858668D02*
X157077Y1858734D01*
G01X157915Y1860276D02*
X158016Y1860177D01*
G01X157513Y1859291D02*
X157412Y1859390D01*
G01X157915Y1858537D02*
X157848Y1858603D01*
G01X157245Y1858865D02*
X157379Y1858734D01*
G01X156809Y1859258D02*
X156709Y1859357D01*
G01X157513Y1857848D02*
X157379Y1857979D01*
G01X156809Y1858045D02*
X156910Y1857946D01*
G01X157245Y1858569D02*
X157178Y1858668D01*
G01X157513Y1858143D02*
X157580Y1858045D01*
G01X157848Y1860112D02*
X157948Y1859980D01*
G01X157245Y1860308D02*
X157345Y1860177D01*
G01X157580Y1859455D02*
X157479Y1859587D01*
G01X158016Y1858701D02*
X158116Y1858569D01*
G01X158016Y1860177D02*
X158116Y1860013D01*
G01X156709Y1859357D02*
X156608Y1859521D01*
G01X156709Y1857848D02*
X156608Y1858012D01*
G01X157345Y1860177D02*
X157379Y1860112D01*
G01X157211D02*
X157278Y1859980D01*
G01X157412Y1859390D02*
X157379Y1859455D01*
G01Y1858734D02*
X157446Y1858603D01*
G01X156843Y1859455D02*
X156776Y1859587D01*
G01X157379Y1857979D02*
X157312Y1858110D01*
G01X157948Y1858438D02*
X157915Y1858537D01*
G01X157479Y1858241D02*
X157513Y1858143D01*
G01X157948Y1859980D02*
X157982Y1859849D01*
G01X157474Y1859606D02*
X157446Y1859718D01*
G01X157479Y1859587D02*
X157474Y1859606D01*
G01X157278Y1859980D02*
X157312Y1859849D01*
G01X157278Y1858438D02*
X157245Y1858569D01*
G01X157312Y1858110D02*
X157278Y1858241D01*
G01X156771Y1859606D02*
X156742Y1859718D01*
G01X156776Y1859587D02*
X156771Y1859606D01*
G01X156776Y1858176D02*
X156809Y1858045D01*
G01X158116Y1860013D02*
X158149Y1859849D01*
G01X158145Y1858425D02*
X158149Y1858406D01*
G01X158116Y1858569D02*
X158145Y1858425D01*
G01X157446Y1858603D02*
X157479Y1858438D01*
G01X156591Y1859606D02*
X156575Y1859685D01*
G01X156608Y1859521D02*
X156591Y1859606D01*
G01X156608Y1858012D02*
X156575Y1858176D01*
G01X165354Y1859606D02*
Y1858425D01*
G01Y1861575D02*
Y1859606D01*
G01Y1862756D02*
Y1861575D01*
G01Y1864725D02*
Y1862756D01*
G01Y1867874D02*
Y1865906D01*
G01D02*
Y1864725D01*
G01Y1869055D02*
Y1867874D01*
G01Y1871024D02*
Y1869055D01*
G01Y1872205D02*
Y1871024D01*
G01X163464D02*
Y1872205D01*
G01Y1864725D02*
Y1865906D01*
G01Y1867874D02*
Y1869055D01*
G01Y1861575D02*
Y1862756D01*
G01Y1858425D02*
Y1859606D01*
G01X161890Y1871024D02*
Y1872205D01*
G01Y1867874D02*
Y1869055D01*
G01Y1864725D02*
Y1865906D01*
G01Y1861575D02*
Y1862756D01*
G01Y1858425D02*
Y1859606D01*
G01X161417Y1856752D02*
Y1856851D01*
G01Y1855079D02*
Y1855177D01*
G01D02*
Y1856752D01*
G01Y1851752D02*
Y1851851D01*
G01Y1850177D02*
Y1851752D01*
G01Y1850079D02*
Y1850177D01*
G01X161102Y1859606D02*
Y1858425D01*
G01Y1862756D02*
Y1861575D01*
G01Y1865906D02*
Y1864725D01*
G01Y1869055D02*
Y1867874D01*
G01Y1872205D02*
Y1871024D01*
G01X160708Y1859606D02*
Y1858425D01*
G01Y1862756D02*
Y1861575D01*
G01Y1865906D02*
Y1864725D01*
G01Y1869055D02*
Y1867874D01*
G01Y1872205D02*
Y1871024D01*
G01X160630Y1869843D02*
Y1870236D01*
G01Y1866693D02*
Y1867087D01*
G01Y1860394D02*
Y1860788D01*
G01Y1863543D02*
Y1863937D01*
G01Y1857441D02*
Y1857638D01*
G01X158149Y1858406D02*
Y1858241D01*
G01Y1859849D02*
Y1859718D01*
G01X157982Y1859849D02*
Y1859718D01*
G01X157948Y1858241D02*
Y1858425D01*
G01D02*
Y1858438D01*
G01X157781Y1858635D02*
Y1858832D01*
G01X157479Y1858425D02*
Y1858241D01*
G01Y1858438D02*
Y1858425D01*
G01X157446Y1859718D02*
Y1859849D01*
G01X157312D02*
Y1859718D01*
G01X157283Y1856851D02*
Y1857441D01*
G01X157278Y1858241D02*
Y1858425D01*
G01D02*
Y1858438D01*
G01X157010Y1857914D02*
Y1857717D01*
G01X156776Y1858425D02*
Y1858176D01*
G01Y1858438D02*
Y1858425D01*
G01X156742Y1859718D02*
Y1859849D01*
G01X156575Y1859685D02*
Y1859882D01*
G01Y1858176D02*
Y1858425D01*
G01D02*
Y1858438D01*
G01X156102Y1871024D02*
Y1872205D01*
G01Y1864725D02*
Y1865906D01*
G01Y1867874D02*
Y1869055D01*
G01Y1861575D02*
Y1862756D01*
G01Y1858425D02*
Y1859606D01*
G01X155787Y1855177D02*
Y1856752D01*
G01Y1850177D02*
Y1851752D01*
G01X154212Y1855177D02*
Y1856752D01*
G01Y1850177D02*
Y1851752D01*
G01X153543Y1853032D02*
Y1853898D01*
G01X153425Y1851752D02*
Y1850177D01*
G01Y1856752D02*
Y1855177D01*
G01X153031Y1851752D02*
Y1850177D01*
G01Y1856752D02*
Y1855177D01*
G01X148110D02*
Y1856752D01*
G01Y1850177D02*
Y1851752D01*
G01X158149Y1858241D02*
X158116Y1858110D01*
G01X157982Y1859718D02*
X157953Y1859606D01*
G01D02*
X157948Y1859587D01*
G01X157446Y1859849D02*
X157479Y1859980D01*
G01X157312Y1859718D02*
X157283Y1859606D01*
G01D02*
X157278Y1859587D01*
G01X156809Y1858569D02*
X156776Y1858438D01*
G01X156742Y1859849D02*
X156776Y1859980D01*
G01X158149Y1859718D02*
X158127Y1859606D01*
G01D02*
X158116Y1859554D01*
G01X156575Y1858438D02*
X156608Y1858603D01*
G01X156575Y1859882D02*
X156608Y1860046D01*
G01X157915Y1858143D02*
X157948Y1858241D01*
G01X158116Y1858110D02*
X158049Y1857979D01*
G01X157379Y1859455D02*
X157345Y1859390D01*
G01X157278Y1859587D02*
X157211Y1859455D01*
G01X156608Y1858603D02*
X156675Y1858734D01*
G01X157379Y1860112D02*
X157412Y1860177D01*
G01X156776Y1859980D02*
X156843Y1860112D01*
G01X157948Y1859587D02*
X157848Y1859455D01*
G01X157345Y1859390D02*
X157245Y1859258D01*
G01X157479Y1859980D02*
X157580Y1860112D01*
G01X157848Y1858045D02*
X157915Y1858143D01*
G01X156876Y1858668D02*
X156809Y1858569D01*
G01X158116Y1859554D02*
X158016Y1859390D01*
G01X156608Y1860046D02*
X156709Y1860210D01*
G01X158049Y1857979D02*
X157915Y1857848D01*
G01X158016Y1859390D02*
X157915Y1859291D01*
G01X156675Y1858734D02*
X156809Y1858865D01*
G01X157412Y1860177D02*
X157513Y1860276D01*
G01X156709Y1860210D02*
X156809Y1860308D01*
G01X162992Y1858327D02*
X160630Y1857638D01*
G01X162992Y1861477D02*
X160630Y1860788D01*
G01X162992Y1864626D02*
X160630Y1863937D01*
G01X162992Y1867776D02*
X160630Y1867087D01*
G01X162992Y1870925D02*
X160630Y1870236D01*
G01X157747Y1858012D02*
X157848Y1858045D01*
G01X156693Y1855079D02*
X153543Y1853898D01*
G01X157915Y1859291D02*
X157747Y1859226D01*
G01X157245Y1859258D02*
X157077Y1859193D01*
G01X156809Y1860308D02*
X156977Y1860374D01*
G01X156809Y1858865D02*
X156943Y1858930D01*
G01X157513Y1860276D02*
X157647Y1860341D01*
G01X156977Y1858734D02*
X156876Y1858668D01*
G01X157848Y1859455D02*
X157747Y1859390D01*
G01X157580Y1860112D02*
X157680Y1860177D01*
G01X157211Y1859455D02*
X157077Y1859357D01*
G01X156843Y1860112D02*
X156977Y1860210D01*
G01X165354Y1891851D02*
X197638D01*
G01X161417D02*
X156693D01*
G01X165354Y1891752D02*
X195876D01*
G01X148110D02*
X165354D01*
G01Y1890177D02*
X195876D01*
G01X165354D02*
X148110D01*
G01X165354Y1890079D02*
X197638D01*
G01X156693D02*
X161417D01*
G01X165354Y1886851D02*
X197638D01*
G01X161417D02*
X156693D01*
G01X165354Y1886752D02*
X195876D01*
G01X148110D02*
X165354D01*
G01Y1885177D02*
X148110D01*
G01X195876D02*
X165354D01*
G01Y1885079D02*
X197638D01*
G01X156693D02*
X161417D01*
G01X158464Y1884843D02*
X165354D01*
G01Y1882087D02*
X158464D01*
G01X150905Y1881910D02*
X149330D01*
G01X165354Y1881851D02*
X194685D01*
G01X161417D02*
X156693D01*
G01X165354Y1881752D02*
X195756D01*
G01X146653D02*
X165354D01*
G01X149330Y1881713D02*
X150637D01*
G01X150403Y1881516D02*
X150671D01*
G01X150537Y1881253D02*
X150403D01*
G01X150436Y1881056D02*
X150537D01*
G01X165354Y1880669D02*
X197638D01*
G01X150738Y1880236D02*
X150235D01*
G01X150034D02*
X149330D01*
G01X165354Y1880177D02*
X195756D01*
G01X146653D02*
X165354D01*
G01Y1880079D02*
X194685D01*
G01X157283D02*
X161417D01*
G01X149330Y1880040D02*
X150905D01*
G01X160630Y1879488D02*
X157283D01*
G01X162992Y1878603D02*
X165354D01*
G01X156102Y1878504D02*
X168110D01*
G01X156102Y1877323D02*
X168110D01*
G01X162992Y1877225D02*
X165354D01*
G01X162992Y1875453D02*
X165354D01*
G01X156102Y1875354D02*
X168110D01*
G01X156102Y1874173D02*
X168110D01*
G01X162992Y1874075D02*
X165354D01*
G01X162992Y1872303D02*
X165354D01*
G01X156102Y1872205D02*
X168110D01*
G01X153543Y1893032D02*
X156693Y1891851D01*
G01X153543Y1888032D02*
X156693Y1886851D01*
G01X153543Y1883032D02*
X156693Y1881851D01*
G01X150637Y1881221D02*
X150537Y1881253D01*
G01Y1881056D02*
X150637Y1881024D01*
G01X160630Y1879291D02*
X162992Y1878603D01*
G01X160630Y1876142D02*
X162992Y1875453D01*
G01X160630Y1872992D02*
X162992Y1872303D01*
G01X150771Y1881122D02*
X150637Y1881221D01*
G01Y1881024D02*
X150704Y1880958D01*
G01X150872Y1880991D02*
X150771Y1881122D01*
G01X150704Y1880958D02*
X150738Y1880860D01*
G01X150905Y1880827D02*
X150872Y1880991D01*
G01X165354Y1878504D02*
Y1895177D01*
G01Y1874173D02*
Y1872205D01*
G01Y1877323D02*
Y1875354D01*
G01D02*
Y1874173D01*
G01Y1878504D02*
Y1877323D01*
G01X163464D02*
Y1878504D01*
G01Y1874173D02*
Y1875354D01*
G01X161890Y1877323D02*
Y1878504D01*
G01Y1874173D02*
Y1875354D01*
G01X161417Y1891752D02*
Y1891851D01*
G01Y1890079D02*
Y1890177D01*
G01D02*
Y1891752D01*
G01Y1886752D02*
Y1886851D01*
G01Y1885079D02*
Y1885177D01*
G01D02*
Y1886752D01*
G01Y1881752D02*
Y1881851D01*
G01Y1880079D02*
Y1880177D01*
G01D02*
Y1881752D01*
G01X161102Y1875354D02*
Y1874173D01*
G01Y1878504D02*
Y1877323D01*
G01X160708Y1875354D02*
Y1874173D01*
G01Y1878504D02*
Y1877323D01*
G01X160630Y1879291D02*
Y1879488D01*
G01Y1876142D02*
Y1876536D01*
G01Y1872992D02*
Y1873386D01*
G01X158464Y1884843D02*
Y1882087D01*
G01X157283Y1879488D02*
Y1880079D01*
G01X156102Y1877323D02*
Y1878504D01*
G01Y1874173D02*
Y1875354D01*
G01X155787Y1890177D02*
Y1891752D01*
G01Y1885177D02*
Y1886752D01*
G01Y1880177D02*
Y1881752D01*
G01X154212Y1890177D02*
Y1891752D01*
G01Y1885177D02*
Y1886752D01*
G01Y1880177D02*
Y1881752D01*
G01X153543Y1888032D02*
Y1888898D01*
G01Y1883032D02*
Y1883898D01*
G01X153425Y1881752D02*
Y1880177D01*
G01Y1886752D02*
Y1885177D01*
G01Y1891752D02*
Y1890177D01*
G01X153031Y1881752D02*
Y1880177D01*
G01Y1886752D02*
Y1885177D01*
G01Y1891752D02*
Y1890177D01*
G01X150905Y1881752D02*
Y1881910D01*
G01Y1880040D02*
Y1880177D01*
G01Y1881713D02*
Y1881752D01*
G01Y1880177D02*
Y1880827D01*
G01X150738Y1880860D02*
Y1880236D01*
G01X150235D02*
Y1880860D01*
G01X150034Y1880827D02*
Y1880236D01*
G01X149330Y1881910D02*
Y1881752D01*
G01Y1880177D02*
Y1880040D01*
G01Y1881752D02*
Y1881713D01*
G01Y1880236D02*
Y1880177D01*
G01X148110Y1890177D02*
Y1891752D01*
G01Y1885177D02*
Y1886752D01*
G01X146653Y1880177D02*
Y1881752D01*
G01X150067Y1880991D02*
X150034Y1880827D01*
G01X150235Y1880860D02*
X150269Y1880958D01*
G01D02*
X150336Y1881024D01*
G01X150168Y1881122D02*
X150067Y1880991D01*
G01X162992Y1874075D02*
X160630Y1873386D01*
G01X162992Y1877225D02*
X160630Y1876536D01*
G01X150336Y1881024D02*
X150436Y1881056D01*
G01X150403Y1881253D02*
X150302Y1881221D01*
G01X156693Y1885079D02*
X153543Y1883898D01*
G01X156693Y1890079D02*
X153543Y1888898D01*
G01X150302Y1881221D02*
X150168Y1881122D01*
G01X150671Y1881516D02*
X150905Y1881713D01*
G01X150637D02*
X150403Y1881516D01*
G01X158661Y1895079D02*
X153543Y1893898D01*
G01X165354Y1911851D02*
X197638D01*
G01X161417D02*
X156693D01*
G01X165354Y1911752D02*
X195876D01*
G01X148110D02*
X165354D01*
G01Y1910177D02*
X195876D01*
G01X165354D02*
X148110D01*
G01X165354Y1910079D02*
X197638D01*
G01X156693D02*
X161417D01*
G01X158464Y1909843D02*
X165354D01*
G01Y1907087D02*
X158464D01*
G01X165354Y1906851D02*
X197638D01*
G01X161417D02*
X156693D01*
G01X165354Y1906752D02*
X195876D01*
G01X148110D02*
X165354D01*
G01Y1905177D02*
X195876D01*
G01X165354D02*
X148110D01*
G01X165354Y1905079D02*
X197638D01*
G01X156693D02*
X161417D01*
G01X165354Y1901851D02*
X197638D01*
G01X161417D02*
X156693D01*
G01X165354Y1901752D02*
X195876D01*
G01X148110D02*
X165354D01*
G01Y1900177D02*
X195876D01*
G01X165354D02*
X148110D01*
G01X165354Y1900079D02*
X197638D01*
G01X156693D02*
X161417D01*
G01X166535Y1898327D02*
X165354D01*
G01X163386Y1896851D02*
X158661D01*
G01X197638D02*
X166535D01*
G01Y1896752D02*
X195876D01*
G01X146653D02*
X166535D01*
G01Y1895177D02*
X195876D01*
G01X146653D02*
X166535D01*
G01Y1895079D02*
X197638D01*
G01X158661D02*
X163386D01*
G01X165354Y1893603D02*
X166535D01*
G01X153543Y1898032D02*
X158661Y1896851D01*
G01X153543Y1913032D02*
X156693Y1911851D01*
G01X153543Y1908032D02*
X156693Y1906851D01*
G01X153543Y1903032D02*
X156693Y1901851D01*
G01X166535Y1893603D02*
Y1898327D01*
G01X165354Y1896752D02*
Y1935177D01*
G01Y1896752D02*
Y1895177D01*
G01X163386Y1896752D02*
Y1896851D01*
G01Y1895079D02*
Y1895177D01*
G01D02*
Y1896752D01*
G01X161417Y1911752D02*
Y1911851D01*
G01Y1910177D02*
Y1911752D01*
G01Y1910079D02*
Y1910177D01*
G01Y1906752D02*
Y1906851D01*
G01Y1905177D02*
Y1906752D01*
G01Y1905079D02*
Y1905177D01*
G01Y1901752D02*
Y1901851D01*
G01Y1900079D02*
Y1900177D01*
G01D02*
Y1901752D01*
G01X158464Y1909843D02*
Y1907087D01*
G01X155787Y1910177D02*
Y1911752D01*
G01Y1905177D02*
Y1906752D01*
G01Y1900177D02*
Y1901752D01*
G01Y1895177D02*
Y1896752D01*
G01X154212Y1910177D02*
Y1911752D01*
G01Y1905177D02*
Y1906752D01*
G01Y1900177D02*
Y1901752D01*
G01Y1895177D02*
Y1896752D01*
G01X153543Y1913032D02*
Y1913898D01*
G01Y1908032D02*
Y1908898D01*
G01Y1903032D02*
Y1903898D01*
G01Y1898032D02*
Y1898898D01*
G01Y1893032D02*
Y1893898D01*
G01X153425Y1896752D02*
Y1895177D01*
G01Y1901752D02*
Y1900177D01*
G01Y1906752D02*
Y1905177D01*
G01Y1911752D02*
Y1910177D01*
G01X153031Y1896752D02*
Y1895177D01*
G01Y1901752D02*
Y1900177D01*
G01Y1906752D02*
Y1905177D01*
G01Y1911752D02*
Y1910177D01*
G01X148110D02*
Y1911752D01*
G01Y1905177D02*
Y1906752D01*
G01Y1900177D02*
Y1901752D01*
G01X146653Y1895177D02*
Y1896752D01*
G01X156693Y1900079D02*
X153543Y1898898D01*
G01X156693Y1905079D02*
X153543Y1903898D01*
G01X156693Y1910079D02*
X153543Y1908898D01*
G01X165354Y1933603D02*
X166535D01*
G01X165354Y1932087D02*
X158464D01*
G01X165354Y1931851D02*
X197638D01*
G01X161417D02*
X156693D01*
G01X165354Y1931752D02*
X195876D01*
G01X148110D02*
X165354D01*
G01Y1930177D02*
X195876D01*
G01X165354D02*
X148110D01*
G01X165354Y1930079D02*
X197638D01*
G01X156693D02*
X161417D01*
G01X165354Y1926851D02*
X197638D01*
G01X161417D02*
X156693D01*
G01X165354Y1926752D02*
X195876D01*
G01X148110D02*
X165354D01*
G01Y1925177D02*
X195876D01*
G01X165354D02*
X148110D01*
G01X165354Y1925079D02*
X197638D01*
G01X156693D02*
X161417D01*
G01X165354Y1921851D02*
X197638D01*
G01X161417D02*
X156693D01*
G01X165354Y1921752D02*
X195876D01*
G01X148110D02*
X165354D01*
G01X158661Y1935079D02*
X153543Y1933898D01*
G01X165354Y1920177D02*
X195876D01*
G01X165354D02*
X148110D01*
G01X165354Y1920079D02*
X197638D01*
G01X156693D02*
X161417D01*
G01X165354Y1916851D02*
X197638D01*
G01X161417D02*
X156693D01*
G01X165354Y1916752D02*
X195876D01*
G01X148110D02*
X165354D01*
G01Y1915177D02*
X195876D01*
G01X165354D02*
X148110D01*
G01X165354Y1915079D02*
X197638D01*
G01X156693D02*
X161417D01*
G01X153543Y1933032D02*
X156693Y1931851D01*
G01X153543Y1928032D02*
X156693Y1926851D01*
G01X153543Y1923032D02*
X156693Y1921851D01*
G01X153543Y1918032D02*
X156693Y1916851D01*
G01X166535Y1933603D02*
Y1938327D01*
G01X161417Y1931752D02*
Y1931851D01*
G01Y1930079D02*
Y1930177D01*
G01D02*
Y1931752D01*
G01Y1926752D02*
Y1926851D01*
G01Y1925177D02*
Y1926752D01*
G01Y1925079D02*
Y1925177D01*
G01Y1921752D02*
Y1921851D01*
G01Y1920177D02*
Y1921752D01*
G01Y1920079D02*
Y1920177D01*
G01Y1916752D02*
Y1916851D01*
G01Y1915177D02*
Y1916752D01*
G01Y1915079D02*
Y1915177D01*
G01X158464Y1934843D02*
Y1932087D01*
G01X155787Y1930177D02*
Y1931752D01*
G01Y1925177D02*
Y1926752D01*
G01Y1920177D02*
Y1921752D01*
G01Y1915177D02*
Y1916752D01*
G01X154212Y1930177D02*
Y1931752D01*
G01Y1925177D02*
Y1926752D01*
G01Y1920177D02*
Y1921752D01*
G01Y1915177D02*
Y1916752D01*
G01X153543Y1933032D02*
Y1933898D01*
G01Y1928032D02*
Y1928898D01*
G01Y1923032D02*
Y1923898D01*
G01Y1918032D02*
Y1918898D01*
G01X153425Y1916752D02*
Y1915177D01*
G01Y1921752D02*
Y1920177D01*
G01Y1926752D02*
Y1925177D01*
G01Y1931752D02*
Y1930177D01*
G01X153031Y1916752D02*
Y1915177D01*
G01Y1921752D02*
Y1920177D01*
G01Y1926752D02*
Y1925177D01*
G01Y1931752D02*
Y1930177D01*
G01X148110D02*
Y1931752D01*
G01Y1925177D02*
Y1926752D01*
G01Y1920177D02*
Y1921752D01*
G01Y1915177D02*
Y1916752D01*
G01X156693Y1915079D02*
X153543Y1913898D01*
G01X156693Y1920079D02*
X153543Y1918898D01*
G01X156693Y1925079D02*
X153543Y1923898D01*
G01X156693Y1930079D02*
X153543Y1928898D01*
G01X145669Y1954784D02*
X165354D01*
G01D02*
X166634D01*
G01X161417Y1951851D02*
X156693D01*
G01X197638D02*
X165354D01*
G01Y1951752D02*
X195876D01*
G01X148110D02*
X165354D01*
G01Y1950177D02*
X195876D01*
G01X165354D02*
X148110D01*
G01X165354Y1950079D02*
X197638D01*
G01X156693D02*
X161417D01*
G01X165354Y1946851D02*
X197638D01*
G01X161417D02*
X156693D01*
G01X165354Y1946752D02*
X195876D01*
G01X148110D02*
X165354D01*
G01Y1945177D02*
X195876D01*
G01X165354D02*
X148110D01*
G01X165354Y1945079D02*
X197638D01*
G01X156693D02*
X161417D01*
G01X165354Y1941851D02*
X197638D01*
G01X161417D02*
X156693D01*
G01X165354Y1941752D02*
X195876D01*
G01X148110D02*
X165354D01*
G01Y1940177D02*
X195876D01*
G01X165354D02*
X148110D01*
G01X165354Y1940079D02*
X197638D01*
G01X156693D02*
X161417D01*
G01X166535Y1938327D02*
X165354D01*
G01X163386Y1936851D02*
X158661D01*
G01X197638D02*
X166535D01*
G01Y1936752D02*
X195876D01*
G01X146653D02*
X166535D01*
G01Y1935177D02*
X195876D01*
G01X146653D02*
X166535D01*
G01Y1935079D02*
X197638D01*
G01X158661D02*
X163386D01*
G01X158464Y1934843D02*
X165354D01*
G01X153543Y1938032D02*
X158661Y1936851D01*
G01X153543Y1953032D02*
X156693Y1951851D01*
G01X153543Y1948032D02*
X156693Y1946851D01*
G01X153543Y1943032D02*
X156693Y1941851D01*
G01X165354Y1936752D02*
Y1956555D01*
G01Y1936752D02*
Y1935177D01*
G01X163386Y1936752D02*
Y1936851D01*
G01Y1935079D02*
Y1935177D01*
G01D02*
Y1936752D01*
G01X161417Y1951752D02*
Y1951851D01*
G01Y1950079D02*
Y1950177D01*
G01D02*
Y1951752D01*
G01Y1946752D02*
Y1946851D01*
G01Y1945079D02*
Y1945177D01*
G01D02*
Y1946752D01*
G01Y1941752D02*
Y1941851D01*
G01Y1940079D02*
Y1940177D01*
G01D02*
Y1941752D01*
G01X155787Y1950177D02*
Y1951752D01*
G01Y1945177D02*
Y1946752D01*
G01Y1940177D02*
Y1941752D01*
G01Y1935177D02*
Y1936752D01*
G01X154212Y1950177D02*
Y1951752D01*
G01Y1945177D02*
Y1946752D01*
G01Y1940177D02*
Y1941752D01*
G01Y1935177D02*
Y1936752D01*
G01X153543Y1953032D02*
Y1954784D01*
G01Y1948032D02*
Y1948898D01*
G01Y1943032D02*
Y1943898D01*
G01Y1938032D02*
Y1938898D01*
G01X153425Y1936752D02*
Y1935177D01*
G01Y1941752D02*
Y1940177D01*
G01Y1946752D02*
Y1945177D01*
G01Y1951752D02*
Y1950177D01*
G01X153031Y1936752D02*
Y1935177D01*
G01Y1941752D02*
Y1940177D01*
G01Y1946752D02*
Y1945177D01*
G01Y1951752D02*
Y1950177D01*
G01X148110D02*
Y1951752D01*
G01Y1945177D02*
Y1946752D01*
G01Y1940177D02*
Y1941752D01*
G01X146653Y1935177D02*
Y1936752D01*
G01X145669Y1954784D02*
Y1968051D01*
G01X156693Y1940079D02*
X153543Y1938898D01*
G01X156693Y1945079D02*
X153543Y1943898D01*
G01X156693Y1950079D02*
X153543Y1948898D01*
G01X155700Y1960904D02*
Y1960906D01*
G01X155687Y1960873D02*
X155700Y1960904D01*
G01X160442Y1965631D02*
X160441Y1965630D01*
G01X160455Y1965662D02*
X160442Y1965631D01*
G01X155934Y1961441D02*
X156054Y1961693D01*
G01X155816Y1961178D02*
X155934Y1961441D01*
G01X155700Y1960906D02*
X155816Y1961178D01*
G01X160321Y1965347D02*
X160441Y1965630D01*
G01X160203Y1965085D02*
X160321Y1965347D01*
G01X160088Y1964843D02*
X160203Y1965085D01*
G01X155939Y1965084D02*
X156054Y1964843D01*
G01X155821Y1965347D02*
X155939Y1965084D01*
G01X155700Y1965630D02*
X155821Y1965347D01*
G01X160325Y1961178D02*
X160441Y1960906D01*
G01X160207Y1961441D02*
X160325Y1961178D01*
G01X160088Y1961693D02*
X160207Y1961441D01*
G01X171063Y1975079D02*
G03I-3740J0D01*
G01X156054Y1964843D02*
G03Y1961693I2017J-1575D01*
G01X160088D02*
G03Y1964843I-2017J1575D01*
G01X155700Y1965630D02*
G03Y1960906I2371J-2362D01*
G01X160441D02*
G03Y1965630I-2370J2362D01*
G01X161575Y1963268D02*
G03I-3504J0D01*
G01X160748Y1960118D02*
G03Y1966417I-2677J3149D01*
G01X155393D02*
G03Y1960118I2678J-3149D01*
G01X157480Y1976063D02*
X177165D01*
G01X176968Y1975866D02*
X157677D01*
G01X176968Y1974291D02*
X157677D01*
G01X177165Y1974095D02*
X157480D01*
G01Y1973110D02*
X177165D01*
G01Y1970020D02*
X157480D01*
G01X199606Y1968051D02*
X145669D01*
G01X166142Y1966870D02*
X199606D01*
G01X155393Y1966417D02*
X160748D01*
G01X160441Y1965630D02*
X155700D01*
G01X156054Y1964843D02*
X160088D01*
G01X166142Y1962658D02*
X145669D01*
G01X177165D02*
X166142D01*
G01X156054Y1961693D02*
X160088D01*
G01X155700Y1960906D02*
X160441D01*
G01X160748Y1960118D02*
X155393D01*
G01X195669Y1959705D02*
X145669D01*
G01X165354Y1956555D02*
X145669D01*
G01X160589Y1960540D02*
X160623Y1960454D01*
G01X155552Y1965996D02*
X155519Y1966082D01*
G01X160517Y1960719D02*
X160589Y1960540D01*
G01X155624Y1965817D02*
X155552Y1965996D01*
G01X160484Y1960800D02*
X160517Y1960719D01*
G01X155657Y1965736D02*
X155624Y1965817D01*
G01X160441Y1960906D02*
X160484Y1960800D01*
G01X155700Y1965630D02*
X155657Y1965736D01*
G01X160693Y1960266D02*
X160748Y1960118D01*
G01X155448Y1966269D02*
X155393Y1966417D01*
G01X160658Y1960362D02*
X160693Y1960266D01*
G01X155484Y1966173D02*
X155448Y1966269D01*
G01X160623Y1960454D02*
X160658Y1960362D01*
G01X155519Y1966082D02*
X155484Y1966173D01*
G01X166142Y1959705D02*
Y1968051D01*
G01Y1975866D02*
Y1974291D01*
G01X164567D02*
Y1975866D01*
G01X164370D02*
Y1976063D01*
G01Y1974291D02*
Y1975866D01*
G01Y1974291D02*
Y1974095D01*
G01X163031Y1974291D02*
Y1975866D01*
G01X157677D02*
Y1974291D01*
G01X157480Y1968051D02*
Y1981004D01*
G01X153543Y1971988D02*
Y1984941D01*
G01X160748Y1966417D02*
X160693Y1966269D01*
G01X155393Y1960118D02*
X155430Y1960217D01*
G01X160495Y1965760D02*
X160455Y1965662D01*
G01X155647Y1960775D02*
X155687Y1960873D01*
G01X160530Y1965849D02*
X160495Y1965760D01*
G01X155611Y1960687D02*
X155647Y1960775D01*
G01X160589Y1965996D02*
X160530Y1965849D01*
G01X155568Y1960580D02*
X155611Y1960687D01*
G01X155536Y1960497D02*
X155568Y1960580D01*
G01X160623Y1966082D02*
X160589Y1965996D01*
G01X155501Y1960409D02*
X155536Y1960497D01*
G01X160658Y1966173D02*
X160623Y1966082D01*
G01X155466Y1960315D02*
X155501Y1960409D01*
G01X160693Y1966269D02*
X160658Y1966173D01*
G01X155430Y1960217D02*
X155466Y1960315D01*
G01X153543Y1984941D02*
X181102D01*
G01X177165Y1981004D02*
X157480D01*
G01X177165Y1979036D02*
X157480D01*
G01X177165Y1977047D02*
X157480D01*
G01X170472Y164016D02*
G03Y162835I0J-590D01*
G01Y161260D02*
G03Y160079I0J-591D01*
G01X170555Y163198D02*
X170462Y163087D01*
G01Y163214D02*
X170555Y163325D01*
G01X181102Y182894D02*
Y169941D01*
G01X177165Y173878D02*
Y186831D01*
G01X172047Y159784D02*
Y161752D01*
G01Y164311D02*
Y162343D01*
G01X170555Y163325D02*
Y163198D01*
G01X170472Y164016D02*
Y164606D01*
G01Y161260D02*
Y162835D01*
G01Y159488D02*
Y160079D01*
G01X170462Y163835D02*
Y163214D01*
G01X170368Y163087D02*
Y163835D01*
G01X170275Y178819D02*
Y179016D01*
G01X169488Y164606D02*
Y159488D01*
G01X169291D02*
Y164606D01*
G01X168897Y162343D02*
Y164311D01*
G01Y161752D02*
Y159784D01*
G01X170472Y164311D02*
X172047D01*
G01X168897D02*
X170472D01*
G01X170368Y163835D02*
X170462D01*
G01Y163087D02*
X170368D01*
G01X172047Y162343D02*
X170472D01*
G01D02*
X168897D01*
G01X172047Y161752D02*
X170472D01*
G01D02*
X168897D01*
G01X170472Y159784D02*
X172047D01*
G01X168897D02*
X170472D01*
G01X177165Y186831D02*
Y346004D01*
G01X176968Y179016D02*
Y180591D01*
G01X171614D02*
Y179016D01*
G01X170275Y180591D02*
Y180788D01*
G01Y180591D02*
Y179016D01*
G01X170079Y180591D02*
Y179016D01*
G01X169291Y332736D02*
Y200099D01*
G01X168504Y180591D02*
Y179016D01*
G01X168012Y200099D02*
Y332736D01*
G01Y200099D02*
X196456D01*
G01X208267Y182894D02*
X181102D01*
G01X187421Y239528D02*
Y240709D01*
G01Y236378D02*
Y237559D01*
G01X185181D02*
Y236378D01*
G01Y240709D02*
Y239528D01*
G01X168110Y234213D02*
Y258622D01*
G01Y240807D02*
X197441D01*
G01X168110Y240709D02*
X194214D01*
G01Y239528D02*
X168110D01*
G01Y239429D02*
X197441D01*
G01Y237658D02*
X168110D01*
G01Y237559D02*
X194214D01*
G01X195669Y236654D02*
X177165D01*
G01X194214Y236378D02*
X168110D01*
G01X197441Y236280D02*
X168110D01*
G01X187421Y255276D02*
Y256457D01*
G01Y252126D02*
Y253307D01*
G01Y248977D02*
Y250158D01*
G01Y245827D02*
Y247008D01*
G01Y242677D02*
Y243858D01*
G01X185181D02*
Y242677D01*
G01Y247008D02*
Y245827D01*
G01Y250158D02*
Y248977D01*
G01Y253307D02*
Y252126D01*
G01Y256457D02*
Y255276D01*
G01X168110Y256555D02*
X197441D01*
G01X168110Y256457D02*
X194214D01*
G01X177165Y256181D02*
X195669D01*
G01X194214Y255276D02*
X168110D01*
G01Y255177D02*
X197441D01*
G01X168110Y253406D02*
X197441D01*
G01X168110Y253307D02*
X194214D01*
G01Y252126D02*
X168110D01*
G01Y252028D02*
X197441D01*
G01X168110Y250256D02*
X197441D01*
G01X168110Y250158D02*
X194214D01*
G01Y248977D02*
X168110D01*
G01Y248878D02*
X197441D01*
G01X168110Y247106D02*
X197441D01*
G01X168110Y247008D02*
X194214D01*
G01Y245827D02*
X168110D01*
G01Y245728D02*
X197441D01*
G01X168110Y243957D02*
X197441D01*
G01X168110Y243858D02*
X194214D01*
G01Y242677D02*
X168110D01*
G01Y242579D02*
X197441D01*
G01X177165Y346004D02*
Y358957D01*
G01X196456Y332736D02*
X168012D01*
G01X181102Y362894D02*
Y349941D01*
G01X176968Y352244D02*
Y353819D01*
G01X171614D02*
Y352244D01*
G01X170275Y353819D02*
Y354016D01*
G01Y352047D02*
Y352244D01*
G01Y353819D02*
Y352244D01*
G01X170079Y353819D02*
Y352244D01*
G01X168504Y353819D02*
Y352244D01*
G01X181102Y349941D02*
X208267D01*
G01X177756Y528091D02*
Y554666D01*
G01X173819Y535669D02*
Y547087D01*
G01X172047Y532028D02*
Y535669D01*
G01X171063Y532028D02*
Y535669D01*
G01X169488Y532028D02*
Y535669D01*
G01X168504Y532028D02*
Y535669D01*
G01X166929Y532028D02*
Y535669D01*
G01X169488Y535473D02*
X168504D01*
G01X172047D02*
X171063D01*
G01X169488Y535391D02*
X168504D01*
G01X172047D02*
X171063D01*
G01X169488Y533996D02*
X168504D01*
G01X172047D02*
X171063D01*
G01X169488Y533915D02*
X168504D01*
G01X172047D02*
X171063D01*
G01X169488Y532028D02*
X168504D01*
G01X172047D02*
X171063D01*
G01X172244Y545315D02*
G03I-591J0D01*
G01Y548416D02*
Y548366D01*
G01X172047Y547087D02*
Y550728D01*
G01X171850Y548366D02*
Y548416D01*
G01X171063Y547087D02*
Y550728D01*
G01X169488Y547087D02*
Y550728D01*
G01X168504Y547087D02*
Y550728D01*
G01X166929Y547087D02*
Y550728D01*
G01X169488D02*
X168504D01*
G01X172047D02*
X171063D01*
G01X169488Y548841D02*
X168504D01*
G01X172047D02*
X171063D01*
G01X169488Y548760D02*
X168504D01*
G01X172047D02*
X171063D01*
G01X172118Y548465D02*
X172185D01*
G01X172047Y548416D02*
X172177D01*
G01X171850D02*
X172047D01*
G01X172244Y548366D02*
X172047D01*
G01D02*
X171850D01*
G01X169488Y547365D02*
X168504D01*
G01X172047D02*
X171063D01*
G01X169488Y547284D02*
X168504D01*
G01X172047D02*
X171063D01*
G01X172185Y548465D02*
X172244Y548416D01*
G01X172177D02*
X172118Y548465D01*
G01X170472Y569528D02*
G03Y568347I0J-590D01*
G01Y566772D02*
G03Y565591I0J-591D01*
G01X170555Y568710D02*
X170462Y568599D01*
G01Y568726D02*
X170555Y568837D01*
G01X181102Y588406D02*
Y575453D01*
G01X177165Y579390D02*
Y592343D01*
G01X172047Y565295D02*
Y567264D01*
G01Y569823D02*
Y567854D01*
G01X170555Y568837D02*
Y568710D01*
G01X170472Y569528D02*
Y570118D01*
G01Y566772D02*
Y568347D01*
G01Y565000D02*
Y565591D01*
G01X170462Y569347D02*
Y568726D01*
G01X170368Y568599D02*
Y569347D01*
G01X169488Y570118D02*
Y565000D01*
G01X169291D02*
Y570118D01*
G01X168897Y567854D02*
Y569823D01*
G01Y567264D02*
Y565295D01*
G01X170472Y569823D02*
X172047D01*
G01X168897D02*
X170472D01*
G01X170368Y569347D02*
X170462D01*
G01Y568599D02*
X170368D01*
G01X172047Y567854D02*
X170472D01*
G01D02*
X168897D01*
G01X172047Y567264D02*
X170472D01*
G01D02*
X168897D01*
G01X170472Y565295D02*
X172047D01*
G01X168897D02*
X170472D01*
G01X177165Y592343D02*
Y751516D01*
G01X176968Y584528D02*
Y586103D01*
G01X171614D02*
Y584528D01*
G01X170275Y586103D02*
Y586299D01*
G01Y584331D02*
Y584528D01*
G01Y586103D02*
Y584528D01*
G01X170079Y586103D02*
Y584528D01*
G01X168504Y586103D02*
Y584528D01*
G01X208267Y588406D02*
X181102D01*
G01X169291Y738248D02*
Y605610D01*
G01X168012D02*
Y738248D01*
G01Y605610D02*
X196456D01*
G01X197441Y643169D02*
X168110D01*
G01Y643071D02*
X194214D01*
G01X195669Y642166D02*
X177165D01*
G01X194214Y641890D02*
X168110D01*
G01X197441Y641791D02*
X168110D01*
G01X187421Y641890D02*
Y643071D01*
G01X185181D02*
Y641890D01*
G01X168110Y639725D02*
Y664134D01*
G01Y662067D02*
X197441D01*
G01X168110Y661969D02*
X194214D01*
G01X177165Y661693D02*
X195669D01*
G01X194214Y660788D02*
X168110D01*
G01Y660689D02*
X197441D01*
G01X168110Y658917D02*
X197441D01*
G01X168110Y658819D02*
X194214D01*
G01Y657638D02*
X168110D01*
G01Y657540D02*
X197441D01*
G01X168110Y655768D02*
X197441D01*
G01X168110Y655669D02*
X194214D01*
G01Y654488D02*
X168110D01*
G01Y654390D02*
X197441D01*
G01X168110Y652618D02*
X197441D01*
G01X168110Y652520D02*
X194214D01*
G01Y651339D02*
X168110D01*
G01Y651240D02*
X197441D01*
G01X168110Y649469D02*
X197441D01*
G01X168110Y649370D02*
X194214D01*
G01Y648189D02*
X168110D01*
G01Y648091D02*
X197441D01*
G01X168110Y646319D02*
X197441D01*
G01X168110Y646221D02*
X194214D01*
G01Y645040D02*
X168110D01*
G01Y644941D02*
X197441D01*
G01X187421Y660788D02*
Y661969D01*
G01Y657638D02*
Y658819D01*
G01Y654488D02*
Y655669D01*
G01Y651339D02*
Y652520D01*
G01Y648189D02*
Y649370D01*
G01Y645040D02*
Y646221D01*
G01X185181D02*
Y645040D01*
G01Y649370D02*
Y648189D01*
G01Y652520D02*
Y651339D01*
G01Y655669D02*
Y654488D01*
G01Y658819D02*
Y657638D01*
G01Y661969D02*
Y660788D01*
G01X196456Y738248D02*
X168012D01*
G01X181102Y755453D02*
X208267D01*
G01X181102Y768406D02*
Y755453D01*
G01X177165Y751516D02*
Y764469D01*
G01X176968Y757756D02*
Y759331D01*
G01X171614D02*
Y757756D01*
G01X170275Y757559D02*
Y757756D01*
G01Y759331D02*
Y759528D01*
G01Y759331D02*
Y757756D01*
G01X170079Y759331D02*
Y757756D01*
G01X168504Y759331D02*
Y757756D01*
G01X170472Y975040D02*
G03Y973858I0J-591D01*
G01Y972284D02*
G03Y971103I0J-591D01*
G01Y975335D02*
X172047D01*
G01X168897D02*
X170472D01*
G01X170368Y974858D02*
X170462D01*
G01Y974110D02*
X170368D01*
G01X172047Y973366D02*
X170472D01*
G01D02*
X168897D01*
G01X172047Y972776D02*
X170472D01*
G01D02*
X168897D01*
G01X170472Y970807D02*
X172047D01*
G01X168897D02*
X170472D01*
G01X170555Y974222D02*
X170462Y974110D01*
G01Y974238D02*
X170555Y974349D01*
G01X181102Y993917D02*
Y980965D01*
G01X172047Y970807D02*
Y972776D01*
G01Y975335D02*
Y973366D01*
G01X170555Y974349D02*
Y974222D01*
G01X170472Y975040D02*
Y975630D01*
G01Y972284D02*
Y973858D01*
G01Y970512D02*
Y971103D01*
G01X170462Y974858D02*
Y974238D01*
G01X170368Y974110D02*
Y974858D01*
G01X169488Y975630D02*
Y970512D01*
G01X169291D02*
Y975630D01*
G01X168897Y973366D02*
Y975335D01*
G01Y972776D02*
Y970807D01*
G01X208267Y993917D02*
X181102D01*
G01X177165Y997854D02*
Y1157028D01*
G01Y984902D02*
Y997854D01*
G01X176968Y990040D02*
Y991614D01*
G01X171614D02*
Y990040D01*
G01X170275Y991614D02*
Y991811D01*
G01Y989843D02*
Y990040D01*
G01Y991614D02*
Y990040D01*
G01X170079Y991614D02*
Y990040D01*
G01X168504Y991614D02*
Y990040D01*
G01X168012Y1011122D02*
X196456D01*
G01X169291Y1143760D02*
Y1011122D01*
G01X168012D02*
Y1143760D01*
G01X168110Y1045236D02*
Y1069646D01*
G01X177165Y1067205D02*
X195669D01*
G01X194214Y1066299D02*
X168110D01*
G01Y1066201D02*
X197441D01*
G01X168110Y1064429D02*
X197441D01*
G01X168110Y1064331D02*
X194214D01*
G01Y1063150D02*
X168110D01*
G01Y1063051D02*
X197441D01*
G01X168110Y1061280D02*
X197441D01*
G01X168110Y1061181D02*
X194214D01*
G01Y1060000D02*
X168110D01*
G01Y1059902D02*
X197441D01*
G01X168110Y1058130D02*
X197441D01*
G01X168110Y1058032D02*
X194214D01*
G01Y1056851D02*
X168110D01*
G01Y1056752D02*
X197441D01*
G01X168110Y1054980D02*
X197441D01*
G01X168110Y1054882D02*
X194214D01*
G01Y1053701D02*
X168110D01*
G01Y1053603D02*
X197441D01*
G01X168110Y1051831D02*
X197441D01*
G01X168110Y1051732D02*
X194214D01*
G01Y1050551D02*
X168110D01*
G01Y1050453D02*
X197441D01*
G01Y1048681D02*
X168110D01*
G01Y1048583D02*
X194214D01*
G01X195669Y1047677D02*
X177165D01*
G01X194214Y1047402D02*
X168110D01*
G01X197441Y1047303D02*
X168110D01*
G01X187421Y1066299D02*
Y1067480D01*
G01Y1063150D02*
Y1064331D01*
G01Y1060000D02*
Y1061181D01*
G01Y1056851D02*
Y1058032D01*
G01Y1053701D02*
Y1054882D01*
G01Y1050551D02*
Y1051732D01*
G01Y1047402D02*
Y1048583D01*
G01X185181D02*
Y1047402D01*
G01Y1051732D02*
Y1050551D01*
G01Y1054882D02*
Y1053701D01*
G01Y1058032D02*
Y1056851D01*
G01Y1061181D02*
Y1060000D01*
G01Y1064331D02*
Y1063150D01*
G01Y1067480D02*
Y1066299D01*
G01X168110Y1067579D02*
X197441D01*
G01X168110Y1067480D02*
X194214D01*
G01X196456Y1143760D02*
X168012D01*
G01X181102Y1160965D02*
X208267D01*
G01X181102Y1173917D02*
Y1160965D01*
G01X177165Y1157028D02*
Y1169980D01*
G01X176968Y1163268D02*
Y1164843D01*
G01X171614D02*
Y1163268D01*
G01X170275Y1163071D02*
Y1163268D01*
G01Y1164843D02*
Y1165040D01*
G01Y1164843D02*
Y1163268D01*
G01X170079Y1164843D02*
Y1163268D01*
G01X168504Y1164843D02*
Y1163268D01*
G01X170472Y1380551D02*
G03Y1379370I0J-591D01*
G01Y1377795D02*
G03Y1376614I0J-591D01*
G01Y1380847D02*
X172047D01*
G01X168897D02*
X170472D01*
G01X170368Y1380370D02*
X170462D01*
G01Y1379622D02*
X170368D01*
G01X172047Y1378878D02*
X170472D01*
G01D02*
X168897D01*
G01X172047Y1378288D02*
X170472D01*
G01D02*
X168897D01*
G01X170472Y1376319D02*
X172047D01*
G01X168897D02*
X170472D01*
G01X172047D02*
Y1378288D01*
G01Y1380847D02*
Y1378878D01*
G01X170555Y1379861D02*
Y1379734D01*
G01X170472Y1380551D02*
Y1381142D01*
G01Y1377795D02*
Y1379370D01*
G01Y1376024D02*
Y1376614D01*
G01X170462Y1380370D02*
Y1379749D01*
G01X170368Y1379622D02*
Y1380370D01*
G01X169488Y1381142D02*
Y1376024D01*
G01X169291D02*
Y1381142D01*
G01X168897Y1378878D02*
Y1380847D01*
G01Y1378288D02*
Y1376319D01*
G01X170555Y1379734D02*
X170462Y1379622D01*
G01Y1379749D02*
X170555Y1379861D01*
G01X208267Y1399429D02*
X181102D01*
G01D02*
Y1386477D01*
G01X177165Y1403366D02*
Y1562540D01*
G01Y1390414D02*
Y1403366D01*
G01X176968Y1395551D02*
Y1397126D01*
G01X171614D02*
Y1395551D01*
G01X170275Y1397126D02*
Y1397323D01*
G01Y1395354D02*
Y1395551D01*
G01Y1397126D02*
Y1395551D01*
G01X170079Y1397126D02*
Y1395551D01*
G01X168504Y1397126D02*
Y1395551D01*
G01X168012Y1416634D02*
X196456D01*
G01X169291Y1549272D02*
Y1416634D01*
G01X168012D02*
Y1549272D01*
G01X194214Y1468662D02*
X168110D01*
G01Y1468563D02*
X197441D01*
G01X168110Y1466791D02*
X197441D01*
G01X168110Y1466693D02*
X194214D01*
G01Y1465512D02*
X168110D01*
G01Y1465414D02*
X197441D01*
G01X168110Y1463642D02*
X197441D01*
G01X168110Y1463543D02*
X194214D01*
G01Y1462362D02*
X168110D01*
G01Y1462264D02*
X197441D01*
G01X168110Y1460492D02*
X197441D01*
G01X168110Y1460394D02*
X194214D01*
G01Y1459213D02*
X168110D01*
G01Y1459114D02*
X197441D01*
G01X168110Y1457343D02*
X197441D01*
G01X168110Y1457244D02*
X194214D01*
G01Y1456063D02*
X168110D01*
G01Y1455965D02*
X197441D01*
G01Y1454193D02*
X168110D01*
G01Y1454095D02*
X194214D01*
G01X195669Y1453189D02*
X177165D01*
G01X194214Y1452914D02*
X168110D01*
G01X197441Y1452815D02*
X168110D01*
G01X187421Y1468662D02*
Y1469843D01*
G01Y1465512D02*
Y1466693D01*
G01Y1462362D02*
Y1463543D01*
G01Y1459213D02*
Y1460394D01*
G01Y1456063D02*
Y1457244D01*
G01Y1452914D02*
Y1454095D01*
G01X185181D02*
Y1452914D01*
G01Y1457244D02*
Y1456063D01*
G01Y1460394D02*
Y1459213D01*
G01Y1463543D02*
Y1462362D01*
G01Y1466693D02*
Y1465512D01*
G01Y1469843D02*
Y1468662D01*
G01X168110Y1450748D02*
Y1475158D01*
G01Y1473091D02*
X197441D01*
G01X168110Y1472992D02*
X194214D01*
G01X177165Y1472717D02*
X195669D01*
G01X194214Y1471811D02*
X168110D01*
G01Y1471713D02*
X197441D01*
G01X168110Y1469941D02*
X197441D01*
G01X168110Y1469843D02*
X194214D01*
G01X187421Y1471811D02*
Y1472992D01*
G01X185181D02*
Y1471811D01*
G01X196456Y1549272D02*
X168012D01*
G01X181102Y1566477D02*
X208267D01*
G01X181102Y1579429D02*
Y1566477D01*
G01X177165Y1562540D02*
Y1575492D01*
G01X176968Y1568780D02*
Y1570354D01*
G01X171614D02*
Y1568780D01*
G01X170275Y1570354D02*
Y1570551D01*
G01Y1568583D02*
Y1568780D01*
G01Y1570354D02*
Y1568780D01*
G01X170079Y1570354D02*
Y1568780D01*
G01X168504Y1570354D02*
Y1568780D01*
G01X170472Y1786063D02*
G03Y1784882I0J-591D01*
G01Y1783307D02*
G03Y1782126I0J-590D01*
G01Y1786358D02*
X172047D01*
G01X168897D02*
X170472D01*
G01X170368Y1785882D02*
X170462D01*
G01Y1785134D02*
X170368D01*
G01X172047Y1784390D02*
X170472D01*
G01D02*
X168897D01*
G01X172047Y1783799D02*
X170472D01*
G01D02*
X168897D01*
G01X170472Y1781831D02*
X172047D01*
G01X168897D02*
X170472D01*
G01X172047D02*
Y1783799D01*
G01Y1786358D02*
Y1784390D01*
G01X170555Y1785373D02*
Y1785245D01*
G01X170472Y1786063D02*
Y1786654D01*
G01Y1783307D02*
Y1784882D01*
G01Y1781536D02*
Y1782126D01*
G01X170462Y1785882D02*
Y1785261D01*
G01X170368Y1785134D02*
Y1785882D01*
G01X169488Y1786654D02*
Y1781536D01*
G01X169291D02*
Y1786654D01*
G01X168897Y1784390D02*
Y1786358D01*
G01Y1783799D02*
Y1781831D01*
G01X170555Y1785245D02*
X170462Y1785134D01*
G01Y1785261D02*
X170555Y1785373D01*
G01X208267Y1804941D02*
X181102D01*
G01D02*
Y1791988D01*
G01X177165Y1795925D02*
Y1808878D01*
G01X176968Y1801063D02*
Y1802638D01*
G01X171614D02*
Y1801063D01*
G01X170275Y1802638D02*
Y1802835D01*
G01Y1800866D02*
Y1801063D01*
G01Y1802638D02*
Y1801063D01*
G01X170079Y1802638D02*
Y1801063D01*
G01X168504Y1802638D02*
Y1801063D01*
G01X168012Y1822146D02*
X196456D01*
G01X177165Y1808878D02*
Y1968051D01*
G01X169291Y1954784D02*
Y1822146D01*
G01X168012D02*
Y1954784D01*
G01X194214Y1871024D02*
X168110D01*
G01Y1870925D02*
X197441D01*
G01X168110Y1869154D02*
X197441D01*
G01X168110Y1869055D02*
X194214D01*
G01Y1867874D02*
X168110D01*
G01Y1867776D02*
X197441D01*
G01X168110Y1866004D02*
X197441D01*
G01X168110Y1865906D02*
X194214D01*
G01Y1864725D02*
X168110D01*
G01Y1864626D02*
X197441D01*
G01X168110Y1862854D02*
X197441D01*
G01X168110Y1862756D02*
X194214D01*
G01Y1861575D02*
X168110D01*
G01Y1861477D02*
X197441D01*
G01Y1859705D02*
X168110D01*
G01Y1859606D02*
X194214D01*
G01X195669Y1858701D02*
X177165D01*
G01X194214Y1858425D02*
X168110D01*
G01X197441Y1858327D02*
X168110D01*
G01X187421Y1871024D02*
Y1872205D01*
G01Y1867874D02*
Y1869055D01*
G01Y1864725D02*
Y1865906D01*
G01Y1861575D02*
Y1862756D01*
G01Y1858425D02*
Y1859606D01*
G01X185181D02*
Y1858425D01*
G01Y1862756D02*
Y1861575D01*
G01Y1865906D02*
Y1864725D01*
G01Y1869055D02*
Y1867874D01*
G01Y1872205D02*
Y1871024D01*
G01X168110Y1856260D02*
Y1880669D01*
G01Y1878603D02*
X197441D01*
G01X168110Y1878504D02*
X194214D01*
G01X177165Y1878228D02*
X195669D01*
G01X194214Y1877323D02*
X168110D01*
G01Y1877225D02*
X197441D01*
G01X168110Y1875453D02*
X197441D01*
G01X168110Y1875354D02*
X194214D01*
G01Y1874173D02*
X168110D01*
G01Y1874075D02*
X197441D01*
G01X168110Y1872303D02*
X197441D01*
G01X168110Y1872205D02*
X194214D01*
G01X187421Y1877323D02*
Y1878504D01*
G01Y1874173D02*
Y1875354D01*
G01X185181D02*
Y1874173D01*
G01Y1878504D02*
Y1877323D01*
G01X196456Y1954784D02*
X168012D01*
G01X181102Y1971988D02*
X208267D01*
G01X181102Y1984941D02*
Y1971988D01*
G01X177165Y1968051D02*
Y1981004D01*
G01X176968Y1974291D02*
Y1975866D01*
G01X171614D02*
Y1974291D01*
G01X170275Y1974095D02*
Y1974291D01*
G01Y1975866D02*
Y1976063D01*
G01Y1975866D02*
Y1974291D01*
G01X170079Y1975866D02*
Y1974291D01*
G01X168504Y1975866D02*
Y1974291D01*
G01X199651Y186877D02*
X199638Y186862D01*
G01X199663Y186896D02*
X199651Y186877D01*
G01X199673Y186917D02*
X199663Y186896D01*
G01X199682Y186941D02*
X199673Y186917D01*
G01X199689Y186969D02*
X199682Y186941D01*
G01X199695Y186999D02*
X199689Y186969D01*
G01X199699Y187032D02*
X199695Y186999D01*
G01X199702Y187067D02*
X199699Y187032D01*
G01X199704Y187106D02*
X199702Y187067D01*
G01X199704Y187147D02*
Y187106D01*
G01X199703Y187190D02*
X199704Y187147D01*
G01X199701Y187236D02*
X199703Y187190D01*
G01X199697Y187285D02*
X199701Y187236D01*
G01X199693Y187336D02*
X199697Y187285D01*
G01X199687Y187389D02*
X199693Y187336D01*
G01X199680Y187444D02*
X199687Y187389D01*
G01X199673Y187502D02*
X199680Y187444D01*
G01X199664Y187561D02*
X199673Y187502D01*
G01X199627Y187812D02*
X199664Y187561D01*
G01X199618Y187875D02*
X199627Y187812D01*
G01X199610Y187938D02*
X199618Y187875D01*
G01X199664Y187561D02*
X199655Y187622D01*
G01X199673Y187502D02*
X199664Y187561D01*
G01X199680Y187444D02*
X199673Y187502D01*
G01X199687Y187389D02*
X199680Y187444D01*
G01X199693Y187336D02*
X199687Y187389D01*
G01X199697Y187285D02*
X199693Y187336D01*
G01X199701Y187236D02*
X199697Y187285D01*
G01X199703Y187190D02*
X199701Y187236D01*
G01X199704Y187147D02*
X199703Y187190D01*
G01X199704Y187106D02*
Y187147D01*
G01X199702Y187068D02*
X199704Y187106D01*
G01X204330Y191477D02*
X199606Y186831D01*
G01X199610Y187938D02*
X204330Y192580D01*
G01X195669Y195177D02*
X197638Y197146D01*
G01X199651Y186877D02*
X199663Y186896D01*
G01X208267Y182894D02*
Y349941D01*
G01X204330Y191477D02*
Y193209D01*
G01X199606Y195177D02*
Y188012D01*
G01X197638Y195177D02*
Y337658D01*
G01X196456Y200099D02*
Y332736D01*
G01X199636Y187748D02*
X199627Y187812D01*
G01X196456Y200099D02*
X197638Y198917D01*
G01Y195177D02*
X200921D01*
G01X204330Y193209D02*
X200921Y195177D01*
G01X195876Y218130D02*
Y219705D01*
G01Y213130D02*
Y214705D01*
G01Y208130D02*
Y209705D01*
G01Y203130D02*
Y204705D01*
G01X195194D02*
Y203130D01*
G01Y209705D02*
Y208130D01*
G01Y214705D02*
Y213130D01*
G01Y219705D02*
Y218130D01*
G01X194685Y218032D02*
Y219803D01*
G01Y213032D02*
Y214803D01*
G01Y208032D02*
Y209803D01*
G01Y203032D02*
Y204803D01*
G01X191019Y218130D02*
Y219705D01*
G01Y213130D02*
Y214705D01*
G01Y208130D02*
Y209705D01*
G01Y203130D02*
Y204705D01*
G01X190773Y218130D02*
Y219705D01*
G01Y213130D02*
Y214705D01*
G01Y208130D02*
Y209705D01*
G01Y203130D02*
Y204705D01*
G01X189667D02*
Y203130D01*
G01Y209705D02*
Y208130D01*
G01Y214705D02*
Y213130D01*
G01Y219705D02*
Y218130D01*
G01X197441Y237658D02*
Y236280D01*
G01Y240807D02*
Y239429D01*
G01X195876Y228130D02*
Y229705D01*
G01Y223130D02*
Y224705D01*
G01X195756Y233130D02*
Y234705D01*
G01X195669Y258622D02*
Y234213D01*
G01X195194Y224705D02*
Y223130D01*
G01Y229705D02*
Y228130D01*
G01X194767Y234705D02*
Y233130D01*
G01X194685Y233032D02*
Y234803D01*
G01Y228032D02*
Y229803D01*
G01Y223032D02*
Y224803D01*
G01X194214Y237559D02*
Y236378D01*
G01Y240709D02*
Y239528D01*
G01X193477D02*
Y240709D01*
G01Y236378D02*
Y237559D01*
G01X191019Y228130D02*
Y229705D01*
G01Y223130D02*
Y224705D01*
G01Y234705D02*
Y233130D01*
G01X190773D02*
Y234705D01*
G01Y228130D02*
Y229705D01*
G01Y223130D02*
Y224705D01*
G01X189667D02*
Y223130D01*
G01Y229705D02*
Y228130D01*
G01Y234705D02*
Y233130D01*
G01X188661Y239429D02*
Y240807D01*
G01Y237658D02*
Y236280D01*
G01X187918Y237559D02*
Y236378D01*
G01Y240709D02*
Y239528D01*
G01X197638Y234685D02*
X195669Y236654D01*
G01X197638Y240807D02*
X197441D01*
G01Y239429D02*
X197638D01*
G01Y237658D02*
X197441D01*
G01Y236280D02*
X197638D01*
G01X195669Y256181D02*
X197638Y258150D01*
G01X197441Y255177D02*
Y256555D01*
G01Y243957D02*
Y242579D01*
G01Y247106D02*
Y245728D01*
G01Y253406D02*
Y252028D01*
G01Y250256D02*
Y248878D01*
G01X195876Y263130D02*
Y264705D01*
G01X195756Y258130D02*
Y259705D01*
G01X195194Y264705D02*
Y263130D01*
G01X194767Y259705D02*
Y258130D01*
G01X194685Y263032D02*
Y264803D01*
G01Y258032D02*
Y259803D01*
G01X194214Y243858D02*
Y242677D01*
G01Y247008D02*
Y245827D01*
G01Y250158D02*
Y248977D01*
G01Y253307D02*
Y252126D01*
G01Y256457D02*
Y255276D01*
G01X193477D02*
Y256457D01*
G01Y248977D02*
Y250158D01*
G01Y252126D02*
Y253307D01*
G01Y245827D02*
Y247008D01*
G01Y242677D02*
Y243858D01*
G01X191019Y263130D02*
Y264705D01*
G01Y259705D02*
Y258130D01*
G01X190773Y263130D02*
Y264705D01*
G01Y258130D02*
Y259705D01*
G01X189667D02*
Y258130D01*
G01Y264705D02*
Y263130D01*
G01X188661Y248878D02*
Y250256D01*
G01Y252028D02*
Y253406D01*
G01Y245728D02*
Y247106D01*
G01Y242579D02*
Y243957D01*
G01Y256555D02*
Y255177D01*
G01X187918Y243858D02*
Y242677D01*
G01Y247008D02*
Y245827D01*
G01Y250158D02*
Y248977D01*
G01Y253307D02*
Y252126D01*
G01Y256457D02*
Y255276D01*
G01X197638Y256555D02*
X197441D01*
G01Y255177D02*
X197638D01*
G01Y253406D02*
X197441D01*
G01Y252028D02*
X197638D01*
G01Y250256D02*
X197441D01*
G01Y248878D02*
X197638D01*
G01Y247106D02*
X197441D01*
G01Y245728D02*
X197638D01*
G01Y243957D02*
X197441D01*
G01Y242579D02*
X197638D01*
G01X195876Y283130D02*
Y284705D01*
G01Y278130D02*
Y279705D01*
G01Y273130D02*
Y274705D01*
G01Y268130D02*
Y269705D01*
G01X195194D02*
Y268130D01*
G01Y274705D02*
Y273130D01*
G01Y279705D02*
Y278130D01*
G01Y284705D02*
Y283130D01*
G01X194685Y283032D02*
Y284803D01*
G01Y278032D02*
Y279803D01*
G01Y273032D02*
Y274803D01*
G01Y268032D02*
Y269803D01*
G01X191019Y283130D02*
Y284705D01*
G01Y278130D02*
Y279705D01*
G01Y273130D02*
Y274705D01*
G01Y268130D02*
Y269705D01*
G01X190773Y283130D02*
Y284705D01*
G01Y278130D02*
Y279705D01*
G01Y273130D02*
Y274705D01*
G01Y268130D02*
Y269705D01*
G01X189667D02*
Y268130D01*
G01Y274705D02*
Y273130D01*
G01Y279705D02*
Y278130D01*
G01Y284705D02*
Y283130D01*
G01X195876Y303130D02*
Y304705D01*
G01Y298130D02*
Y299705D01*
G01Y293130D02*
Y294705D01*
G01Y288130D02*
Y289705D01*
G01X195194D02*
Y288130D01*
G01Y294705D02*
Y293130D01*
G01Y299705D02*
Y298130D01*
G01Y304705D02*
Y303130D01*
G01X194685Y303032D02*
Y304803D01*
G01Y298032D02*
Y299803D01*
G01Y293032D02*
Y294803D01*
G01Y288032D02*
Y289803D01*
G01X191019Y303130D02*
Y304705D01*
G01Y298130D02*
Y299705D01*
G01Y293130D02*
Y294705D01*
G01Y288130D02*
Y289705D01*
G01X190773Y303130D02*
Y304705D01*
G01Y298130D02*
Y299705D01*
G01Y293130D02*
Y294705D01*
G01Y288130D02*
Y289705D01*
G01X189667D02*
Y288130D01*
G01Y294705D02*
Y293130D01*
G01Y299705D02*
Y298130D01*
G01Y304705D02*
Y303130D01*
G01X195876Y323130D02*
Y324705D01*
G01Y318130D02*
Y319705D01*
G01Y313130D02*
Y314705D01*
G01Y308130D02*
Y309705D01*
G01X195194D02*
Y308130D01*
G01Y314705D02*
Y313130D01*
G01Y319705D02*
Y318130D01*
G01Y324705D02*
Y323130D01*
G01X194685Y323032D02*
Y324803D01*
G01Y318032D02*
Y319803D01*
G01Y313032D02*
Y314803D01*
G01Y308032D02*
Y309803D01*
G01X191019Y323130D02*
Y324705D01*
G01Y318130D02*
Y319705D01*
G01Y313130D02*
Y314705D01*
G01Y308130D02*
Y309705D01*
G01X190773Y323130D02*
Y324705D01*
G01Y318130D02*
Y319705D01*
G01Y313130D02*
Y314705D01*
G01Y308130D02*
Y309705D01*
G01X189667D02*
Y308130D01*
G01Y314705D02*
Y313130D01*
G01Y319705D02*
Y318130D01*
G01Y324705D02*
Y323130D01*
G01X199673Y345333D02*
X199664Y345274D01*
G01X199680Y345390D02*
X199673Y345333D01*
G01X199687Y345446D02*
X199680Y345390D01*
G01X199693Y345499D02*
X199687Y345446D01*
G01X199697Y345550D02*
X199693Y345499D01*
G01X199701Y345598D02*
X199697Y345550D01*
G01X199703Y345644D02*
X199701Y345598D01*
G01X199704Y345688D02*
X199703Y345644D01*
G01X199704Y345729D02*
Y345688D01*
G01X199702Y345767D02*
X199704Y345729D01*
G01X199699Y345803D02*
X199702Y345767D01*
G01X199695Y345836D02*
X199699Y345803D01*
G01X199689Y345866D02*
X199695Y345836D01*
G01X199682Y345893D02*
X199689Y345866D01*
G01X199673Y345917D02*
X199682Y345893D01*
G01X199663Y345939D02*
X199673Y345917D01*
G01X199651Y345957D02*
X199663Y345939D01*
G01X199638Y345973D02*
X199651Y345957D01*
G01X199618Y344960D02*
X199610Y344897D01*
G01X199627Y345023D02*
X199618Y344960D01*
G01X199703Y345644D02*
X199704Y345688D01*
G01X199701Y345598D02*
X199703Y345644D01*
G01X199697Y345550D02*
X199701Y345598D01*
G01X199693Y345499D02*
X199697Y345550D01*
G01X199687Y345446D02*
X199693Y345499D01*
G01X199680Y345391D02*
X199687Y345446D01*
G01X199673Y345333D02*
X199680Y345391D01*
G01X199664Y345274D02*
X199673Y345333D01*
G01X200921Y337658D02*
X204330Y339626D01*
G01X196456Y332736D02*
X197638Y333917D01*
G01X199664Y345274D02*
X199627Y345023D01*
G01X199646Y345150D02*
X199655Y345213D01*
G01X204330Y339626D02*
Y341358D01*
G01X199606Y344823D02*
Y337658D01*
G01X195876Y328130D02*
Y329705D01*
G01X195194D02*
Y328130D01*
G01X194685Y328032D02*
Y329803D01*
G01X191019Y328130D02*
Y329705D01*
G01X190773Y328130D02*
Y329705D01*
G01X189667D02*
Y328130D01*
G01X199702Y345767D02*
X199699Y345803D01*
G01X199673Y345917D02*
X199663Y345939D01*
G01X199651Y345957D02*
X199638Y345973D01*
G01X197638Y337658D02*
X200921D01*
G01X197638Y335689D02*
X195669Y337658D01*
G01X199606Y346004D02*
X204330Y341358D01*
G01Y340255D02*
X199610Y344897D01*
G01X199651Y592389D02*
X199638Y592374D01*
G01X199663Y592408D02*
X199651Y592389D01*
G01X199673Y592429D02*
X199663Y592408D01*
G01X199682Y592453D02*
X199673Y592429D01*
G01X199689Y592481D02*
X199682Y592453D01*
G01X199695Y592511D02*
X199689Y592481D01*
G01X199699Y592544D02*
X199695Y592511D01*
G01X199702Y592579D02*
X199699Y592544D01*
G01X199704Y592618D02*
X199702Y592579D01*
G01X199704Y592659D02*
Y592618D01*
G01X199703Y592702D02*
X199704Y592659D01*
G01X199701Y592748D02*
X199703Y592702D01*
G01X199697Y592797D02*
X199701Y592748D01*
G01X199693Y592848D02*
X199697Y592797D01*
G01X199687Y592901D02*
X199693Y592848D01*
G01X199680Y592956D02*
X199687Y592901D01*
G01X199673Y593014D02*
X199680Y592956D01*
G01X199664Y593073D02*
X199673Y593014D01*
G01X199664Y593073D02*
X199655Y593134D01*
G01X199673Y593014D02*
X199664Y593073D01*
G01X199680Y592956D02*
X199673Y593014D01*
G01X199687Y592901D02*
X199680Y592956D01*
G01X199693Y592848D02*
X199687Y592901D01*
G01X199697Y592797D02*
X199693Y592848D01*
G01X199701Y592748D02*
X199697Y592797D01*
G01X199703Y592702D02*
X199701Y592748D01*
G01X199704Y592659D02*
X199703Y592702D01*
G01X199704Y592618D02*
Y592659D01*
G01X199702Y592580D02*
X199704Y592618D01*
G01X199627Y593323D02*
X199664Y593073D01*
G01X199618Y593387D02*
X199627Y593323D01*
G01X199610Y593450D02*
X199618Y593387D01*
G01X204330Y596988D02*
X199606Y592343D01*
G01X199610Y593450D02*
X204330Y598091D01*
G01X195669Y600689D02*
X197638Y602658D01*
G01X199651Y592389D02*
X199663Y592408D01*
G01X208267Y588406D02*
Y755453D01*
G01X204330Y596988D02*
Y598721D01*
G01X199606Y600689D02*
Y593524D01*
G01X197638Y600689D02*
Y743169D01*
G01Y600689D02*
X200921D01*
G01X204330Y598721D02*
X200921Y600689D01*
G01X196456Y605610D02*
Y738248D01*
G01X195876Y618642D02*
Y620217D01*
G01Y613642D02*
Y615217D01*
G01Y608642D02*
Y610217D01*
G01X195194D02*
Y608642D01*
G01Y615217D02*
Y613642D01*
G01Y620217D02*
Y618642D01*
G01X194685Y618543D02*
Y620315D01*
G01Y613543D02*
Y615315D01*
G01Y608543D02*
Y610315D01*
G01X191019Y618642D02*
Y620217D01*
G01Y613642D02*
Y615217D01*
G01Y608642D02*
Y610217D01*
G01X190773Y618642D02*
Y620217D01*
G01Y613642D02*
Y615217D01*
G01Y608642D02*
Y610217D01*
G01X189667D02*
Y608642D01*
G01Y615217D02*
Y613642D01*
G01Y620217D02*
Y618642D01*
G01X196456Y605610D02*
X197638Y604429D01*
G01Y643169D02*
X197441D01*
G01Y641791D02*
X197638D01*
G01X197441Y643169D02*
Y641791D01*
G01X195876Y633642D02*
Y635217D01*
G01Y628642D02*
Y630217D01*
G01Y623642D02*
Y625217D01*
G01X195756Y638642D02*
Y640217D01*
G01X195669Y664134D02*
Y639725D01*
G01X195194Y625217D02*
Y623642D01*
G01Y630217D02*
Y628642D01*
G01Y635217D02*
Y633642D01*
G01X194767Y640217D02*
Y638642D01*
G01X194685Y638543D02*
Y640315D01*
G01Y633543D02*
Y635315D01*
G01Y628543D02*
Y630315D01*
G01Y623543D02*
Y625315D01*
G01X194214Y643071D02*
Y641890D01*
G01X193477D02*
Y643071D01*
G01X191019Y633642D02*
Y635217D01*
G01Y628642D02*
Y630217D01*
G01Y623642D02*
Y625217D01*
G01Y640217D02*
Y638642D01*
G01X190773D02*
Y640217D01*
G01Y633642D02*
Y635217D01*
G01Y628642D02*
Y630217D01*
G01Y623642D02*
Y625217D01*
G01X189667D02*
Y623642D01*
G01Y630217D02*
Y628642D01*
G01Y635217D02*
Y633642D01*
G01Y640217D02*
Y638642D01*
G01X188661Y643169D02*
Y641791D01*
G01X187918Y643071D02*
Y641890D01*
G01X197638Y640197D02*
X195669Y642166D01*
G01Y661693D02*
X197638Y663662D01*
G01Y662067D02*
X197441D01*
G01Y660689D02*
X197638D01*
G01Y658917D02*
X197441D01*
G01Y657540D02*
X197638D01*
G01Y655768D02*
X197441D01*
G01Y654390D02*
X197638D01*
G01Y652618D02*
X197441D01*
G01Y651240D02*
X197638D01*
G01Y649469D02*
X197441D01*
G01Y648091D02*
X197638D01*
G01Y646319D02*
X197441D01*
G01Y644941D02*
X197638D01*
G01X197441Y660689D02*
Y662067D01*
G01Y646319D02*
Y644941D01*
G01Y649469D02*
Y648091D01*
G01Y655768D02*
Y654390D01*
G01Y652618D02*
Y651240D01*
G01Y658917D02*
Y657540D01*
G01X195756Y663642D02*
Y665217D01*
G01X194767D02*
Y663642D01*
G01X194685Y663543D02*
Y665315D01*
G01X194214Y646221D02*
Y645040D01*
G01Y649370D02*
Y648189D01*
G01Y652520D02*
Y651339D01*
G01Y655669D02*
Y654488D01*
G01Y658819D02*
Y657638D01*
G01Y661969D02*
Y660788D01*
G01X193477D02*
Y661969D01*
G01Y657638D02*
Y658819D01*
G01Y651339D02*
Y652520D01*
G01Y654488D02*
Y655669D01*
G01Y648189D02*
Y649370D01*
G01Y645040D02*
Y646221D01*
G01X191019Y665217D02*
Y663642D01*
G01X190773D02*
Y665217D01*
G01X189667D02*
Y663642D01*
G01X188661Y657540D02*
Y658917D01*
G01Y651240D02*
Y652618D01*
G01Y654390D02*
Y655768D01*
G01Y648091D02*
Y649469D01*
G01Y644941D02*
Y646319D01*
G01Y662067D02*
Y660689D01*
G01X187918Y646221D02*
Y645040D01*
G01Y649370D02*
Y648189D01*
G01Y652520D02*
Y651339D01*
G01Y655669D02*
Y654488D01*
G01Y658819D02*
Y657638D01*
G01Y661969D02*
Y660788D01*
G01X195876Y683642D02*
Y685217D01*
G01Y678642D02*
Y680217D01*
G01Y673642D02*
Y675217D01*
G01Y668642D02*
Y670217D01*
G01X195194D02*
Y668642D01*
G01Y675217D02*
Y673642D01*
G01Y680217D02*
Y678642D01*
G01Y685217D02*
Y683642D01*
G01X194685Y683543D02*
Y685315D01*
G01Y678543D02*
Y680315D01*
G01Y673543D02*
Y675315D01*
G01Y668543D02*
Y670315D01*
G01X191019Y683642D02*
Y685217D01*
G01Y678642D02*
Y680217D01*
G01Y673642D02*
Y675217D01*
G01Y668642D02*
Y670217D01*
G01X190773Y683642D02*
Y685217D01*
G01Y678642D02*
Y680217D01*
G01Y673642D02*
Y675217D01*
G01Y668642D02*
Y670217D01*
G01X189667D02*
Y668642D01*
G01Y675217D02*
Y673642D01*
G01Y680217D02*
Y678642D01*
G01Y685217D02*
Y683642D01*
G01X195876Y703642D02*
Y705217D01*
G01Y698642D02*
Y700217D01*
G01Y693642D02*
Y695217D01*
G01Y688642D02*
Y690217D01*
G01X195194D02*
Y688642D01*
G01Y695217D02*
Y693642D01*
G01Y700217D02*
Y698642D01*
G01Y705217D02*
Y703642D01*
G01X194685Y703543D02*
Y705315D01*
G01Y698543D02*
Y700315D01*
G01Y693543D02*
Y695315D01*
G01Y688543D02*
Y690315D01*
G01X191019Y703642D02*
Y705217D01*
G01Y698642D02*
Y700217D01*
G01Y693642D02*
Y695217D01*
G01Y688642D02*
Y690217D01*
G01X190773Y703642D02*
Y705217D01*
G01Y698642D02*
Y700217D01*
G01Y693642D02*
Y695217D01*
G01Y688642D02*
Y690217D01*
G01X189667D02*
Y688642D01*
G01Y695217D02*
Y693642D01*
G01Y700217D02*
Y698642D01*
G01Y705217D02*
Y703642D01*
G01X195876Y728642D02*
Y730217D01*
G01Y723642D02*
Y725217D01*
G01Y718642D02*
Y720217D01*
G01Y713642D02*
Y715217D01*
G01Y708642D02*
Y710217D01*
G01X195194D02*
Y708642D01*
G01Y715217D02*
Y713642D01*
G01Y720217D02*
Y718642D01*
G01Y725217D02*
Y723642D01*
G01Y730217D02*
Y728642D01*
G01X194685Y728543D02*
Y730315D01*
G01Y723543D02*
Y725315D01*
G01Y718543D02*
Y720315D01*
G01Y713543D02*
Y715315D01*
G01Y708543D02*
Y710315D01*
G01X191019Y728642D02*
Y730217D01*
G01Y723642D02*
Y725217D01*
G01Y718642D02*
Y720217D01*
G01Y713642D02*
Y715217D01*
G01Y708642D02*
Y710217D01*
G01X190773Y728642D02*
Y730217D01*
G01Y723642D02*
Y725217D01*
G01Y718642D02*
Y720217D01*
G01Y713642D02*
Y715217D01*
G01Y708642D02*
Y710217D01*
G01X189667D02*
Y708642D01*
G01Y715217D02*
Y713642D01*
G01Y720217D02*
Y718642D01*
G01Y725217D02*
Y723642D01*
G01Y730217D02*
Y728642D01*
G01X200921Y743169D02*
X204330Y745138D01*
G01X196456Y738248D02*
X197638Y739429D01*
G01Y743169D02*
X200921D01*
G01X204330Y745138D02*
Y746870D01*
G01X199606Y750335D02*
Y743169D01*
G01X195876Y733642D02*
Y735217D01*
G01X195194D02*
Y733642D01*
G01X194685Y733543D02*
Y735315D01*
G01X191019Y733642D02*
Y735217D01*
G01X190773Y733642D02*
Y735217D01*
G01X189667D02*
Y733642D01*
G01X197638Y741201D02*
X195669Y743169D01*
G01X199606Y751516D02*
X204330Y746870D01*
G01Y745767D02*
X199610Y750408D01*
G01X199673Y750845D02*
X199664Y750786D01*
G01X199680Y750902D02*
X199673Y750845D01*
G01X199687Y750958D02*
X199680Y750902D01*
G01X199693Y751011D02*
X199687Y750958D01*
G01X199697Y751062D02*
X199693Y751011D01*
G01X199701Y751110D02*
X199697Y751062D01*
G01X199703Y751156D02*
X199701Y751110D01*
G01X199704Y751200D02*
X199703Y751156D01*
G01X199704Y751241D02*
Y751200D01*
G01X199702Y751279D02*
X199704Y751241D01*
G01X199699Y751315D02*
X199702Y751279D01*
G01X199695Y751347D02*
X199699Y751315D01*
G01X199689Y751378D02*
X199695Y751347D01*
G01X199682Y751405D02*
X199689Y751378D01*
G01X199673Y751429D02*
X199682Y751405D01*
G01X199663Y751451D02*
X199673Y751429D01*
G01X199651Y751469D02*
X199663Y751451D01*
G01X199638Y751485D02*
X199651Y751469D01*
G01X199618Y750471D02*
X199610Y750408D01*
G01X199627Y750535D02*
X199618Y750471D01*
G01X199703Y751156D02*
X199704Y751200D01*
G01X199701Y751110D02*
X199703Y751156D01*
G01X199697Y751062D02*
X199701Y751110D01*
G01X199693Y751011D02*
X199697Y751062D01*
G01X199687Y750958D02*
X199693Y751011D01*
G01X199680Y750903D02*
X199687Y750958D01*
G01X199673Y750845D02*
X199680Y750903D01*
G01X199664Y750786D02*
X199673Y750845D01*
G01X199664Y750786D02*
X199627Y750535D01*
G01X199702Y751279D02*
X199699Y751315D01*
G01X199673Y751429D02*
X199663Y751451D01*
G01X199651Y997901D02*
X199638Y997886D01*
G01X199663Y997919D02*
X199651Y997901D01*
G01X199673Y997941D02*
X199663Y997919D01*
G01X199682Y997965D02*
X199673Y997941D01*
G01X199689Y997993D02*
X199682Y997965D01*
G01X199695Y998023D02*
X199689Y997993D01*
G01X199699Y998056D02*
X199695Y998023D01*
G01X199702Y998091D02*
X199699Y998056D01*
G01X199704Y998130D02*
X199702Y998091D01*
G01X199704Y998171D02*
Y998130D01*
G01X199703Y998214D02*
X199704Y998171D01*
G01X199701Y998260D02*
X199703Y998214D01*
G01X199697Y998308D02*
X199701Y998260D01*
G01X199693Y998360D02*
X199697Y998308D01*
G01X199687Y998413D02*
X199693Y998360D01*
G01X199680Y998468D02*
X199687Y998413D01*
G01X199673Y998525D02*
X199680Y998468D01*
G01X199664Y998585D02*
X199673Y998525D01*
G01X199627Y998835D02*
X199664Y998585D01*
G01X199618Y998899D02*
X199627Y998835D01*
G01X199610Y998962D02*
X199618Y998899D01*
G01X204330Y1002500D02*
X199606Y997854D01*
G01X199610Y998962D02*
X204330Y1003603D01*
G01X199651Y997901D02*
X199663Y997919D01*
G01X208267Y993917D02*
Y1160965D01*
G01X204330Y1002500D02*
Y1004232D01*
G01X199606Y1006201D02*
Y999036D01*
G01X197638Y1006201D02*
X200921D01*
G01X196456Y1011122D02*
X197638Y1009941D01*
G01X204330Y1004232D02*
X200921Y1006201D01*
G01X195669D02*
X197638Y1008169D01*
G01Y1006201D02*
Y1148681D01*
G01X196456Y1011122D02*
Y1143760D01*
G01X195876Y1024154D02*
Y1025728D01*
G01Y1019154D02*
Y1020728D01*
G01Y1014154D02*
Y1015728D01*
G01X195194D02*
Y1014154D01*
G01Y1020728D02*
Y1019154D01*
G01Y1025728D02*
Y1024154D01*
G01X194685Y1024055D02*
Y1025827D01*
G01Y1019055D02*
Y1020827D01*
G01Y1014055D02*
Y1015827D01*
G01X191019Y1024154D02*
Y1025728D01*
G01Y1019154D02*
Y1020728D01*
G01Y1014154D02*
Y1015728D01*
G01X190773Y1024154D02*
Y1025728D01*
G01Y1019154D02*
Y1020728D01*
G01Y1014154D02*
Y1015728D01*
G01X189667D02*
Y1014154D01*
G01Y1020728D02*
Y1019154D01*
G01Y1025728D02*
Y1024154D01*
G01X197638Y1045709D02*
X195669Y1047677D01*
G01X195876Y1039154D02*
Y1040728D01*
G01Y1034154D02*
Y1035728D01*
G01Y1029154D02*
Y1030728D01*
G01X195756Y1044154D02*
Y1045728D01*
G01X195669Y1069646D02*
Y1045236D01*
G01X195194Y1030728D02*
Y1029154D01*
G01Y1035728D02*
Y1034154D01*
G01Y1040728D02*
Y1039154D01*
G01X194767Y1045728D02*
Y1044154D01*
G01X194685Y1044055D02*
Y1045827D01*
G01Y1039055D02*
Y1040827D01*
G01Y1034055D02*
Y1035827D01*
G01Y1029055D02*
Y1030827D01*
G01X191019Y1039154D02*
Y1040728D01*
G01Y1034154D02*
Y1035728D01*
G01Y1029154D02*
Y1030728D01*
G01Y1045728D02*
Y1044154D01*
G01X190773D02*
Y1045728D01*
G01Y1039154D02*
Y1040728D01*
G01Y1034154D02*
Y1035728D01*
G01Y1029154D02*
Y1030728D01*
G01X189667D02*
Y1029154D01*
G01Y1035728D02*
Y1034154D01*
G01Y1040728D02*
Y1039154D01*
G01Y1045728D02*
Y1044154D01*
G01X197441Y1066201D02*
X197638D01*
G01Y1064429D02*
X197441D01*
G01Y1063051D02*
X197638D01*
G01Y1061280D02*
X197441D01*
G01Y1059902D02*
X197638D01*
G01Y1058130D02*
X197441D01*
G01Y1056752D02*
X197638D01*
G01Y1054980D02*
X197441D01*
G01Y1053603D02*
X197638D01*
G01Y1051831D02*
X197441D01*
G01Y1050453D02*
X197638D01*
G01Y1048681D02*
X197441D01*
G01Y1047303D02*
X197638D01*
G01X195669Y1067205D02*
X197638Y1069173D01*
G01X197441Y1066201D02*
Y1067579D01*
G01Y1048681D02*
Y1047303D01*
G01Y1051831D02*
Y1050453D01*
G01Y1058130D02*
Y1056752D01*
G01Y1054980D02*
Y1053603D01*
G01Y1061280D02*
Y1059902D01*
G01Y1064429D02*
Y1063051D01*
G01X194214Y1048583D02*
Y1047402D01*
G01Y1051732D02*
Y1050551D01*
G01Y1054882D02*
Y1053701D01*
G01Y1058032D02*
Y1056851D01*
G01Y1061181D02*
Y1060000D01*
G01Y1064331D02*
Y1063150D01*
G01Y1067480D02*
Y1066299D01*
G01X193477D02*
Y1067480D01*
G01Y1063150D02*
Y1064331D01*
G01Y1060000D02*
Y1061181D01*
G01Y1053701D02*
Y1054882D01*
G01Y1056851D02*
Y1058032D01*
G01Y1050551D02*
Y1051732D01*
G01Y1047402D02*
Y1048583D01*
G01X188661Y1063051D02*
Y1064429D01*
G01Y1059902D02*
Y1061280D01*
G01Y1053603D02*
Y1054980D01*
G01Y1056752D02*
Y1058130D01*
G01Y1050453D02*
Y1051831D01*
G01Y1048681D02*
Y1047303D01*
G01Y1067579D02*
Y1066201D01*
G01X187918Y1048583D02*
Y1047402D01*
G01Y1051732D02*
Y1050551D01*
G01Y1054882D02*
Y1053701D01*
G01Y1058032D02*
Y1056851D01*
G01Y1061181D02*
Y1060000D01*
G01Y1067480D02*
Y1066299D01*
G01Y1064331D02*
Y1063150D01*
G01X197638Y1067579D02*
X197441D01*
G01X195876Y1084154D02*
Y1085728D01*
G01Y1079154D02*
Y1080728D01*
G01Y1074154D02*
Y1075728D01*
G01X195756Y1069154D02*
Y1070728D01*
G01X195194Y1075728D02*
Y1074154D01*
G01Y1080728D02*
Y1079154D01*
G01Y1085728D02*
Y1084154D01*
G01X194767Y1070728D02*
Y1069154D01*
G01X194685Y1084055D02*
Y1085827D01*
G01Y1079055D02*
Y1080827D01*
G01Y1074055D02*
Y1075827D01*
G01Y1069055D02*
Y1070827D01*
G01X191019Y1084154D02*
Y1085728D01*
G01Y1079154D02*
Y1080728D01*
G01Y1074154D02*
Y1075728D01*
G01Y1070728D02*
Y1069154D01*
G01X190773Y1084154D02*
Y1085728D01*
G01Y1079154D02*
Y1080728D01*
G01Y1074154D02*
Y1075728D01*
G01Y1069154D02*
Y1070728D01*
G01X189667D02*
Y1069154D01*
G01Y1075728D02*
Y1074154D01*
G01Y1080728D02*
Y1079154D01*
G01Y1085728D02*
Y1084154D01*
G01X195876Y1109154D02*
Y1110728D01*
G01Y1104154D02*
Y1105728D01*
G01Y1099154D02*
Y1100728D01*
G01Y1094154D02*
Y1095728D01*
G01Y1089154D02*
Y1090728D01*
G01X195194D02*
Y1089154D01*
G01Y1095728D02*
Y1094154D01*
G01Y1100728D02*
Y1099154D01*
G01Y1105728D02*
Y1104154D01*
G01Y1110728D02*
Y1109154D01*
G01X194685Y1109055D02*
Y1110827D01*
G01Y1104055D02*
Y1105827D01*
G01Y1099055D02*
Y1100827D01*
G01Y1094055D02*
Y1095827D01*
G01Y1089055D02*
Y1090827D01*
G01X191019Y1109154D02*
Y1110728D01*
G01Y1104154D02*
Y1105728D01*
G01Y1099154D02*
Y1100728D01*
G01Y1094154D02*
Y1095728D01*
G01Y1089154D02*
Y1090728D01*
G01X190773Y1109154D02*
Y1110728D01*
G01Y1104154D02*
Y1105728D01*
G01Y1099154D02*
Y1100728D01*
G01Y1094154D02*
Y1095728D01*
G01Y1089154D02*
Y1090728D01*
G01X189667D02*
Y1089154D01*
G01Y1095728D02*
Y1094154D01*
G01Y1100728D02*
Y1099154D01*
G01Y1105728D02*
Y1104154D01*
G01Y1110728D02*
Y1109154D01*
G01X195876Y1129154D02*
Y1130728D01*
G01Y1124154D02*
Y1125728D01*
G01Y1119154D02*
Y1120728D01*
G01Y1114154D02*
Y1115728D01*
G01X195194D02*
Y1114154D01*
G01Y1120728D02*
Y1119154D01*
G01Y1125728D02*
Y1124154D01*
G01Y1130728D02*
Y1129154D01*
G01X194685Y1129055D02*
Y1130827D01*
G01Y1124055D02*
Y1125827D01*
G01Y1119055D02*
Y1120827D01*
G01Y1114055D02*
Y1115827D01*
G01X191019Y1129154D02*
Y1130728D01*
G01Y1124154D02*
Y1125728D01*
G01Y1119154D02*
Y1120728D01*
G01Y1114154D02*
Y1115728D01*
G01X190773Y1129154D02*
Y1130728D01*
G01Y1124154D02*
Y1125728D01*
G01Y1119154D02*
Y1120728D01*
G01Y1114154D02*
Y1115728D01*
G01X189667D02*
Y1114154D01*
G01Y1120728D02*
Y1119154D01*
G01Y1125728D02*
Y1124154D01*
G01Y1130728D02*
Y1129154D01*
G01X197638Y1148681D02*
X200921D01*
G01X197638Y1146713D02*
X195669Y1148681D01*
G01X204330Y1151278D02*
X199610Y1155920D01*
G01X200921Y1148681D02*
X204330Y1150650D01*
G01X196456Y1143760D02*
X197638Y1144941D01*
G01X204330Y1150650D02*
Y1152382D01*
G01X199606Y1155847D02*
Y1148681D01*
G01X195876Y1139154D02*
Y1140728D01*
G01Y1134154D02*
Y1135728D01*
G01X195194D02*
Y1134154D01*
G01Y1140728D02*
Y1139154D01*
G01X194685Y1139055D02*
Y1140827D01*
G01Y1134055D02*
Y1135827D01*
G01X191019Y1139154D02*
Y1140728D01*
G01Y1134154D02*
Y1135728D01*
G01X190773Y1139154D02*
Y1140728D01*
G01Y1134154D02*
Y1135728D01*
G01X189667D02*
Y1134154D01*
G01Y1140728D02*
Y1139154D01*
G01X199703Y1156668D02*
X199704Y1156712D01*
G01X199701Y1156622D02*
X199703Y1156668D01*
G01X199697Y1156573D02*
X199701Y1156622D01*
G01X199693Y1156523D02*
X199697Y1156573D01*
G01X199687Y1156469D02*
X199693Y1156523D01*
G01X199680Y1156414D02*
X199687Y1156469D01*
G01X199618Y1155983D02*
X199610Y1155920D01*
G01X199627Y1156047D02*
X199618Y1155983D01*
G01X199673Y1156356D02*
X199664Y1156297D01*
G01X199680Y1156414D02*
X199673Y1156356D01*
G01X199687Y1156469D02*
X199680Y1156414D01*
G01X199693Y1156523D02*
X199687Y1156469D01*
G01X199697Y1156573D02*
X199693Y1156523D01*
G01X199701Y1156622D02*
X199697Y1156573D01*
G01X199703Y1156668D02*
X199701Y1156622D01*
G01X199704Y1156712D02*
X199703Y1156668D01*
G01X199704Y1156753D02*
Y1156712D01*
G01X199702Y1156791D02*
X199704Y1156753D01*
G01X199699Y1156827D02*
X199702Y1156791D01*
G01X199695Y1156859D02*
X199699Y1156827D01*
G01X199689Y1156890D02*
X199695Y1156859D01*
G01X199682Y1156917D02*
X199689Y1156890D01*
G01X199673Y1156941D02*
X199682Y1156917D01*
G01X199663Y1156962D02*
X199673Y1156941D01*
G01X199651Y1156981D02*
X199663Y1156962D01*
G01X199638Y1156997D02*
X199651Y1156981D01*
G01D02*
X199638Y1156997D01*
G01X199606Y1157028D02*
X204330Y1152382D01*
G01X199673Y1156941D02*
X199663Y1156963D01*
G01X199664Y1156297D02*
X199627Y1156047D01*
G01X199702Y1156791D02*
X199699Y1156827D01*
G01X199673Y1404037D02*
X199664Y1404097D01*
G01X199680Y1403980D02*
X199673Y1404037D01*
G01X199687Y1403925D02*
X199680Y1403980D01*
G01X199693Y1403871D02*
X199687Y1403925D01*
G01X199697Y1403821D02*
X199693Y1403871D01*
G01X199701Y1403772D02*
X199697Y1403821D01*
G01X199703Y1403726D02*
X199701Y1403772D01*
G01X199704Y1403682D02*
X199703Y1403726D01*
G01X199704Y1403641D02*
Y1403682D01*
G01X199702Y1403603D02*
X199704Y1403641D01*
G01X199651Y1403413D02*
X199638Y1403397D01*
G01X199663Y1403431D02*
X199651Y1403413D01*
G01X199673Y1403453D02*
X199663Y1403431D01*
G01X199682Y1403477D02*
X199673Y1403453D01*
G01X199689Y1403504D02*
X199682Y1403477D01*
G01X199695Y1403534D02*
X199689Y1403504D01*
G01X199699Y1403567D02*
X199695Y1403534D01*
G01X199702Y1403603D02*
X199699Y1403567D01*
G01X199704Y1403641D02*
X199702Y1403603D01*
G01X199704Y1403682D02*
Y1403641D01*
G01X199703Y1403726D02*
X199704Y1403682D01*
G01X199701Y1403772D02*
X199703Y1403726D01*
G01X199697Y1403820D02*
X199701Y1403772D01*
G01X199693Y1403871D02*
X199697Y1403820D01*
G01X199687Y1403925D02*
X199693Y1403871D01*
G01X199680Y1403980D02*
X199687Y1403925D01*
G01X199673Y1404037D02*
X199680Y1403980D01*
G01X199664Y1404097D02*
X199673Y1404037D01*
G01X199627Y1404347D02*
X199664Y1404097D01*
G01X199618Y1404411D02*
X199627Y1404347D01*
G01X199610Y1404474D02*
X199618Y1404411D01*
G01X208267Y1399429D02*
Y1566477D01*
G01X199606Y1411713D02*
Y1404547D01*
G01X204330Y1408012D02*
X199606Y1403366D01*
G01X199610Y1404474D02*
X204330Y1409115D01*
G01X199651Y1403413D02*
X199663Y1403431D01*
G01X197638Y1411713D02*
X200921D01*
G01X204330Y1409744D02*
X200921Y1411713D01*
G01X196456Y1416634D02*
X197638Y1415453D01*
G01X204330Y1408012D02*
Y1409744D01*
G01X197638Y1411713D02*
Y1554193D01*
G01X196456Y1416634D02*
Y1549272D01*
G01X195876Y1424666D02*
Y1426240D01*
G01Y1419666D02*
Y1421240D01*
G01X195194D02*
Y1419666D01*
G01Y1426240D02*
Y1424666D01*
G01X194685Y1424567D02*
Y1426339D01*
G01Y1419567D02*
Y1421339D01*
G01X191019Y1424666D02*
Y1426240D01*
G01Y1419666D02*
Y1421240D01*
G01X190773Y1424666D02*
Y1426240D01*
G01Y1419666D02*
Y1421240D01*
G01X189667D02*
Y1419666D01*
G01Y1426240D02*
Y1424666D01*
G01X195669Y1411713D02*
X197638Y1413681D01*
G01X195876Y1444666D02*
Y1446240D01*
G01Y1439666D02*
Y1441240D01*
G01Y1434666D02*
Y1436240D01*
G01Y1429666D02*
Y1431240D01*
G01X195194D02*
Y1429666D01*
G01Y1436240D02*
Y1434666D01*
G01Y1441240D02*
Y1439666D01*
G01Y1446240D02*
Y1444666D01*
G01X194685Y1444567D02*
Y1446339D01*
G01Y1439567D02*
Y1441339D01*
G01Y1434567D02*
Y1436339D01*
G01Y1429567D02*
Y1431339D01*
G01X191019Y1444666D02*
Y1446240D01*
G01Y1439666D02*
Y1441240D01*
G01Y1434666D02*
Y1436240D01*
G01Y1429666D02*
Y1431240D01*
G01X190773Y1444666D02*
Y1446240D01*
G01Y1439666D02*
Y1441240D01*
G01Y1434666D02*
Y1436240D01*
G01Y1429666D02*
Y1431240D01*
G01X189667D02*
Y1429666D01*
G01Y1436240D02*
Y1434666D01*
G01Y1441240D02*
Y1439666D01*
G01Y1446240D02*
Y1444666D01*
G01X197441Y1468563D02*
X197638D01*
G01Y1466791D02*
X197441D01*
G01Y1465414D02*
X197638D01*
G01Y1463642D02*
X197441D01*
G01Y1462264D02*
X197638D01*
G01Y1460492D02*
X197441D01*
G01Y1459114D02*
X197638D01*
G01Y1457343D02*
X197441D01*
G01Y1455965D02*
X197638D01*
G01Y1454193D02*
X197441D01*
G01Y1452815D02*
X197638D01*
G01Y1451221D02*
X195669Y1453189D01*
G01X197441Y1454193D02*
Y1452815D01*
G01Y1460492D02*
Y1459114D01*
G01Y1457343D02*
Y1455965D01*
G01Y1463642D02*
Y1462264D01*
G01Y1469941D02*
Y1468563D01*
G01Y1466791D02*
Y1465414D01*
G01X195756Y1449666D02*
Y1451240D01*
G01X195669Y1475158D02*
Y1450748D01*
G01X194767Y1451240D02*
Y1449666D01*
G01X194685Y1449567D02*
Y1451339D01*
G01X194214Y1454095D02*
Y1452914D01*
G01Y1457244D02*
Y1456063D01*
G01Y1460394D02*
Y1459213D01*
G01Y1463543D02*
Y1462362D01*
G01Y1466693D02*
Y1465512D01*
G01Y1469843D02*
Y1468662D01*
G01X193477Y1465512D02*
Y1466693D01*
G01Y1468662D02*
Y1469843D01*
G01Y1462362D02*
Y1463543D01*
G01Y1459213D02*
Y1460394D01*
G01Y1456063D02*
Y1457244D01*
G01Y1452914D02*
Y1454095D01*
G01X191019Y1451240D02*
Y1449666D01*
G01X190773D02*
Y1451240D01*
G01X189667D02*
Y1449666D01*
G01X188661Y1465414D02*
Y1466791D01*
G01Y1468563D02*
Y1469941D01*
G01Y1462264D02*
Y1463642D01*
G01Y1455965D02*
Y1457343D01*
G01Y1459114D02*
Y1460492D01*
G01Y1454193D02*
Y1452815D01*
G01X187918Y1454095D02*
Y1452914D01*
G01Y1460394D02*
Y1459213D01*
G01Y1457244D02*
Y1456063D01*
G01Y1463543D02*
Y1462362D01*
G01Y1466693D02*
Y1465512D01*
G01Y1469843D02*
Y1468662D01*
G01X197638Y1473091D02*
X197441D01*
G01Y1471713D02*
X197638D01*
G01Y1469941D02*
X197441D01*
G01Y1471713D02*
Y1473091D01*
G01X195876Y1489666D02*
Y1491240D01*
G01Y1484666D02*
Y1486240D01*
G01Y1479666D02*
Y1481240D01*
G01X195756Y1474666D02*
Y1476240D01*
G01X195194Y1481240D02*
Y1479666D01*
G01Y1486240D02*
Y1484666D01*
G01Y1491240D02*
Y1489666D01*
G01X194767Y1476240D02*
Y1474666D01*
G01X194685Y1489567D02*
Y1491339D01*
G01Y1484567D02*
Y1486339D01*
G01Y1479567D02*
Y1481339D01*
G01Y1474567D02*
Y1476339D01*
G01X194214Y1472992D02*
Y1471811D01*
G01X193477D02*
Y1472992D01*
G01X191019Y1489666D02*
Y1491240D01*
G01Y1484666D02*
Y1486240D01*
G01Y1479666D02*
Y1481240D01*
G01Y1476240D02*
Y1474666D01*
G01X190773Y1489666D02*
Y1491240D01*
G01Y1484666D02*
Y1486240D01*
G01Y1479666D02*
Y1481240D01*
G01Y1474666D02*
Y1476240D01*
G01X189667D02*
Y1474666D01*
G01Y1481240D02*
Y1479666D01*
G01Y1486240D02*
Y1484666D01*
G01Y1491240D02*
Y1489666D01*
G01X188661Y1473091D02*
Y1471713D01*
G01X187918Y1472992D02*
Y1471811D01*
G01X195669Y1472717D02*
X197638Y1474685D01*
G01X195876Y1509666D02*
Y1511240D01*
G01Y1504666D02*
Y1506240D01*
G01Y1499666D02*
Y1501240D01*
G01Y1494666D02*
Y1496240D01*
G01X195194D02*
Y1494666D01*
G01Y1501240D02*
Y1499666D01*
G01Y1506240D02*
Y1504666D01*
G01Y1511240D02*
Y1509666D01*
G01X194685Y1509567D02*
Y1511339D01*
G01Y1504567D02*
Y1506339D01*
G01Y1499567D02*
Y1501339D01*
G01Y1494567D02*
Y1496339D01*
G01X191019Y1509666D02*
Y1511240D01*
G01Y1504666D02*
Y1506240D01*
G01Y1499666D02*
Y1501240D01*
G01Y1494666D02*
Y1496240D01*
G01X190773Y1509666D02*
Y1511240D01*
G01Y1504666D02*
Y1506240D01*
G01Y1499666D02*
Y1501240D01*
G01Y1494666D02*
Y1496240D01*
G01X189667D02*
Y1494666D01*
G01Y1501240D02*
Y1499666D01*
G01Y1506240D02*
Y1504666D01*
G01Y1511240D02*
Y1509666D01*
G01X195876Y1529666D02*
Y1531240D01*
G01Y1524666D02*
Y1526240D01*
G01Y1519666D02*
Y1521240D01*
G01Y1514666D02*
Y1516240D01*
G01X195194D02*
Y1514666D01*
G01Y1521240D02*
Y1519666D01*
G01Y1526240D02*
Y1524666D01*
G01Y1531240D02*
Y1529666D01*
G01X194685Y1529567D02*
Y1531339D01*
G01Y1524567D02*
Y1526339D01*
G01Y1519567D02*
Y1521339D01*
G01Y1514567D02*
Y1516339D01*
G01X191019Y1529666D02*
Y1531240D01*
G01Y1524666D02*
Y1526240D01*
G01Y1519666D02*
Y1521240D01*
G01Y1514666D02*
Y1516240D01*
G01X190773Y1529666D02*
Y1531240D01*
G01Y1524666D02*
Y1526240D01*
G01Y1519666D02*
Y1521240D01*
G01Y1514666D02*
Y1516240D01*
G01X189667D02*
Y1514666D01*
G01Y1521240D02*
Y1519666D01*
G01Y1526240D02*
Y1524666D01*
G01Y1531240D02*
Y1529666D01*
G01X197638Y1552225D02*
X195669Y1554193D01*
G01X195876Y1544666D02*
Y1546240D01*
G01Y1539666D02*
Y1541240D01*
G01Y1534666D02*
Y1536240D01*
G01X195194D02*
Y1534666D01*
G01Y1541240D02*
Y1539666D01*
G01Y1546240D02*
Y1544666D01*
G01X194685Y1544567D02*
Y1546339D01*
G01Y1539567D02*
Y1541339D01*
G01Y1534567D02*
Y1536339D01*
G01X191019Y1544666D02*
Y1546240D01*
G01Y1539666D02*
Y1541240D01*
G01Y1534666D02*
Y1536240D01*
G01X190773Y1544666D02*
Y1546240D01*
G01Y1539666D02*
Y1541240D01*
G01Y1534666D02*
Y1536240D01*
G01X189667D02*
Y1534666D01*
G01Y1541240D02*
Y1539666D01*
G01Y1546240D02*
Y1544666D01*
G01X196456Y1549272D02*
X197638Y1550453D01*
G01X199618Y1561495D02*
X199610Y1561432D01*
G01X199627Y1561559D02*
X199618Y1561495D01*
G01X199703Y1562180D02*
X199704Y1562223D01*
G01X199701Y1562134D02*
X199703Y1562180D01*
G01X199697Y1562085D02*
X199701Y1562134D01*
G01X199693Y1562034D02*
X199697Y1562085D01*
G01X199687Y1561981D02*
X199693Y1562034D01*
G01X199680Y1561926D02*
X199687Y1561981D01*
G01X199673Y1561869D02*
X199680Y1561926D01*
G01X199664Y1561809D02*
X199673Y1561869D01*
G01Y1561868D02*
X199664Y1561809D01*
G01X199680Y1561926D02*
X199673Y1561868D01*
G01X199687Y1561981D02*
X199680Y1561926D01*
G01X199693Y1562034D02*
X199687Y1561981D01*
G01X199697Y1562085D02*
X199693Y1562034D01*
G01X199701Y1562134D02*
X199697Y1562085D01*
G01X199703Y1562180D02*
X199701Y1562134D01*
G01X199704Y1562223D02*
X199703Y1562180D01*
G01X199704Y1562264D02*
Y1562223D01*
G01X199702Y1562303D02*
X199704Y1562264D01*
G01X199699Y1562338D02*
X199702Y1562303D01*
G01X199695Y1562371D02*
X199699Y1562338D01*
G01X199689Y1562401D02*
X199695Y1562371D01*
G01X199682Y1562428D02*
X199689Y1562401D01*
G01X199673Y1562453D02*
X199682Y1562428D01*
G01X199663Y1562474D02*
X199673Y1562453D01*
G01X199651Y1562493D02*
X199663Y1562474D01*
G01X199638Y1562508D02*
X199651Y1562493D01*
G01X197638Y1554193D02*
X200921D01*
G01X199606Y1562540D02*
X204330Y1557894D01*
G01Y1556790D02*
X199610Y1561432D01*
G01X199651Y1562493D02*
X199638Y1562508D01*
G01X199673Y1562453D02*
X199663Y1562475D01*
G01X199702Y1562303D02*
X199699Y1562338D01*
G01X204330Y1556162D02*
Y1557894D01*
G01X199606Y1561358D02*
Y1554193D01*
G01X199664Y1561809D02*
X199627Y1561559D01*
G01X200921Y1554193D02*
X204330Y1556162D01*
G01X208267Y1804941D02*
Y1971988D01*
G01X199664Y1809608D02*
X199636Y1809795D01*
G01X199673Y1809549D02*
X199664Y1809608D01*
G01X199680Y1809491D02*
X199673Y1809549D01*
G01X199687Y1809436D02*
X199680Y1809491D01*
G01X199693Y1809383D02*
X199687Y1809436D01*
G01X199697Y1809332D02*
X199693Y1809383D01*
G01X199701Y1809284D02*
X199697Y1809332D01*
G01X199703Y1809238D02*
X199701Y1809284D01*
G01X199704Y1809194D02*
X199703Y1809238D01*
G01X199704Y1809153D02*
Y1809194D01*
G01X199702Y1809115D02*
X199704Y1809153D01*
G01X199651Y1808925D02*
X199638Y1808909D01*
G01X199663Y1808943D02*
X199651Y1808925D01*
G01X199673Y1808964D02*
X199663Y1808943D01*
G01X199682Y1808989D02*
X199673Y1808964D01*
G01X199689Y1809016D02*
X199682Y1808989D01*
G01X199695Y1809046D02*
X199689Y1809016D01*
G01X199699Y1809079D02*
X199695Y1809046D01*
G01X199702Y1809115D02*
X199699Y1809079D01*
G01X199704Y1809153D02*
X199702Y1809115D01*
G01X199704Y1809194D02*
Y1809153D01*
G01X199703Y1809238D02*
X199704Y1809194D01*
G01X199701Y1809284D02*
X199703Y1809238D01*
G01X199697Y1809332D02*
X199701Y1809284D01*
G01X199693Y1809383D02*
X199697Y1809332D01*
G01X199687Y1809436D02*
X199693Y1809383D01*
G01X199680Y1809491D02*
X199687Y1809436D01*
G01X199673Y1809549D02*
X199680Y1809491D01*
G01X199664Y1809608D02*
X199673Y1809549D01*
G01X199627Y1809859D02*
X199664Y1809608D01*
G01X199618Y1809923D02*
X199627Y1809859D01*
G01X199610Y1809986D02*
X199618Y1809923D01*
G01X197638Y1817225D02*
X200921D01*
G01X204330Y1815256D02*
X200921Y1817225D01*
G01X196456Y1822146D02*
X197638Y1820965D01*
G01X199636Y1809795D02*
X199627Y1809859D01*
G01X204330Y1813524D02*
Y1815256D01*
G01X199606Y1817225D02*
Y1810059D01*
G01X197638Y1817225D02*
Y1959705D01*
G01X196456Y1822146D02*
Y1954784D01*
G01X195876Y1825177D02*
Y1826752D01*
G01X195194D02*
Y1825177D01*
G01X194685Y1825079D02*
Y1826851D01*
G01X191019Y1825177D02*
Y1826752D01*
G01X190773Y1825177D02*
Y1826752D01*
G01X189667D02*
Y1825177D01*
G01X199651Y1808925D02*
X199663Y1808943D01*
G01X204330Y1813524D02*
X199606Y1808878D01*
G01X199610Y1809986D02*
X204330Y1814627D01*
G01X195669Y1817225D02*
X197638Y1819193D01*
G01X195876Y1845177D02*
Y1846752D01*
G01Y1840177D02*
Y1841752D01*
G01Y1835177D02*
Y1836752D01*
G01Y1830177D02*
Y1831752D01*
G01X195194D02*
Y1830177D01*
G01Y1836752D02*
Y1835177D01*
G01Y1841752D02*
Y1840177D01*
G01Y1846752D02*
Y1845177D01*
G01X194685Y1845079D02*
Y1846851D01*
G01Y1840079D02*
Y1841851D01*
G01Y1835079D02*
Y1836851D01*
G01Y1830079D02*
Y1831851D01*
G01X191019Y1845177D02*
Y1846752D01*
G01Y1840177D02*
Y1841752D01*
G01Y1835177D02*
Y1836752D01*
G01Y1830177D02*
Y1831752D01*
G01X190773Y1845177D02*
Y1846752D01*
G01Y1840177D02*
Y1841752D01*
G01Y1835177D02*
Y1836752D01*
G01Y1830177D02*
Y1831752D01*
G01X189667D02*
Y1830177D01*
G01Y1836752D02*
Y1835177D01*
G01Y1841752D02*
Y1840177D01*
G01Y1846752D02*
Y1845177D01*
G01X197441Y1870925D02*
X197638D01*
G01Y1869154D02*
X197441D01*
G01Y1867776D02*
X197638D01*
G01Y1866004D02*
X197441D01*
G01Y1864626D02*
X197638D01*
G01Y1862854D02*
X197441D01*
G01Y1861477D02*
X197638D01*
G01Y1859705D02*
X197441D01*
G01Y1858327D02*
X197638D01*
G01Y1856732D02*
X195669Y1858701D01*
G01X197441Y1859705D02*
Y1858327D01*
G01Y1862854D02*
Y1861477D01*
G01Y1866004D02*
Y1864626D01*
G01Y1872303D02*
Y1870925D01*
G01Y1869154D02*
Y1867776D01*
G01X195876Y1850177D02*
Y1851752D01*
G01X195756Y1855177D02*
Y1856752D01*
G01X195669Y1880669D02*
Y1856260D01*
G01X195194Y1851752D02*
Y1850177D01*
G01X194767Y1856752D02*
Y1855177D01*
G01X194685Y1855079D02*
Y1856851D01*
G01Y1850079D02*
Y1851851D01*
G01X194214Y1859606D02*
Y1858425D01*
G01Y1862756D02*
Y1861575D01*
G01Y1865906D02*
Y1864725D01*
G01Y1869055D02*
Y1867874D01*
G01Y1872205D02*
Y1871024D01*
G01X193477D02*
Y1872205D01*
G01Y1864725D02*
Y1865906D01*
G01Y1867874D02*
Y1869055D01*
G01Y1861575D02*
Y1862756D01*
G01Y1858425D02*
Y1859606D01*
G01X191019Y1850177D02*
Y1851752D01*
G01Y1856752D02*
Y1855177D01*
G01X190773D02*
Y1856752D01*
G01Y1850177D02*
Y1851752D01*
G01X189667D02*
Y1850177D01*
G01Y1856752D02*
Y1855177D01*
G01X188661Y1867776D02*
Y1869154D01*
G01Y1870925D02*
Y1872303D01*
G01Y1864626D02*
Y1866004D01*
G01Y1861477D02*
Y1862854D01*
G01Y1859705D02*
Y1858327D01*
G01X187918Y1859606D02*
Y1858425D01*
G01Y1862756D02*
Y1861575D01*
G01Y1865906D02*
Y1864725D01*
G01Y1869055D02*
Y1867874D01*
G01Y1872205D02*
Y1871024D01*
G01X197638Y1878603D02*
X197441D01*
G01Y1877225D02*
X197638D01*
G01Y1875453D02*
X197441D01*
G01Y1874075D02*
X197638D01*
G01Y1872303D02*
X197441D01*
G01Y1877225D02*
Y1878603D01*
G01Y1875453D02*
Y1874075D01*
G01X195876Y1890177D02*
Y1891752D01*
G01Y1885177D02*
Y1886752D01*
G01X195756Y1880177D02*
Y1881752D01*
G01X195194Y1886752D02*
Y1885177D01*
G01Y1891752D02*
Y1890177D01*
G01X194767Y1881752D02*
Y1880177D01*
G01X194685Y1890079D02*
Y1891851D01*
G01Y1885079D02*
Y1886851D01*
G01Y1880079D02*
Y1881851D01*
G01X194214Y1875354D02*
Y1874173D01*
G01Y1878504D02*
Y1877323D01*
G01X193477D02*
Y1878504D01*
G01Y1874173D02*
Y1875354D01*
G01X191019Y1890177D02*
Y1891752D01*
G01Y1885177D02*
Y1886752D01*
G01Y1881752D02*
Y1880177D01*
G01X190773Y1890177D02*
Y1891752D01*
G01Y1885177D02*
Y1886752D01*
G01Y1880177D02*
Y1881752D01*
G01X189667D02*
Y1880177D01*
G01Y1886752D02*
Y1885177D01*
G01Y1891752D02*
Y1890177D01*
G01X188661Y1874075D02*
Y1875453D01*
G01Y1878603D02*
Y1877225D01*
G01X187918Y1875354D02*
Y1874173D01*
G01Y1878504D02*
Y1877323D01*
G01X195669Y1878228D02*
X197638Y1880197D01*
G01X195876Y1910177D02*
Y1911752D01*
G01Y1905177D02*
Y1906752D01*
G01Y1900177D02*
Y1901752D01*
G01Y1895177D02*
Y1896752D01*
G01X195194D02*
Y1895177D01*
G01Y1901752D02*
Y1900177D01*
G01Y1906752D02*
Y1905177D01*
G01Y1911752D02*
Y1910177D01*
G01X194685Y1910079D02*
Y1911851D01*
G01Y1905079D02*
Y1906851D01*
G01Y1900079D02*
Y1901851D01*
G01Y1895079D02*
Y1896851D01*
G01X191019Y1910177D02*
Y1911752D01*
G01Y1905177D02*
Y1906752D01*
G01Y1900177D02*
Y1901752D01*
G01Y1895177D02*
Y1896752D01*
G01X190773Y1910177D02*
Y1911752D01*
G01Y1905177D02*
Y1906752D01*
G01Y1900177D02*
Y1901752D01*
G01Y1895177D02*
Y1896752D01*
G01X189667D02*
Y1895177D01*
G01Y1901752D02*
Y1900177D01*
G01Y1906752D02*
Y1905177D01*
G01Y1911752D02*
Y1910177D01*
G01X195876Y1930177D02*
Y1931752D01*
G01Y1925177D02*
Y1926752D01*
G01Y1920177D02*
Y1921752D01*
G01Y1915177D02*
Y1916752D01*
G01X195194D02*
Y1915177D01*
G01Y1921752D02*
Y1920177D01*
G01Y1926752D02*
Y1925177D01*
G01Y1931752D02*
Y1930177D01*
G01X194685Y1930079D02*
Y1931851D01*
G01Y1925079D02*
Y1926851D01*
G01Y1920079D02*
Y1921851D01*
G01Y1915079D02*
Y1916851D01*
G01X191019Y1930177D02*
Y1931752D01*
G01Y1925177D02*
Y1926752D01*
G01Y1920177D02*
Y1921752D01*
G01Y1915177D02*
Y1916752D01*
G01X190773Y1930177D02*
Y1931752D01*
G01Y1925177D02*
Y1926752D01*
G01Y1920177D02*
Y1921752D01*
G01Y1915177D02*
Y1916752D01*
G01X189667D02*
Y1915177D01*
G01Y1921752D02*
Y1920177D01*
G01Y1926752D02*
Y1925177D01*
G01Y1931752D02*
Y1930177D01*
G01X195876Y1950177D02*
Y1951752D01*
G01Y1945177D02*
Y1946752D01*
G01Y1940177D02*
Y1941752D01*
G01Y1935177D02*
Y1936752D01*
G01X195194D02*
Y1935177D01*
G01Y1941752D02*
Y1940177D01*
G01Y1946752D02*
Y1945177D01*
G01Y1951752D02*
Y1950177D01*
G01X194685Y1950079D02*
Y1951851D01*
G01Y1945079D02*
Y1946851D01*
G01Y1940079D02*
Y1941851D01*
G01Y1935079D02*
Y1936851D01*
G01X191019Y1950177D02*
Y1951752D01*
G01Y1945177D02*
Y1946752D01*
G01Y1940177D02*
Y1941752D01*
G01Y1935177D02*
Y1936752D01*
G01X190773Y1950177D02*
Y1951752D01*
G01Y1945177D02*
Y1946752D01*
G01Y1940177D02*
Y1941752D01*
G01Y1935177D02*
Y1936752D01*
G01X189667D02*
Y1935177D01*
G01Y1941752D02*
Y1940177D01*
G01Y1946752D02*
Y1945177D01*
G01Y1951752D02*
Y1950177D01*
G01X196456Y1954784D02*
X197638Y1955965D01*
G01X199618Y1967007D02*
X199610Y1966944D01*
G01X199627Y1967071D02*
X199618Y1967007D01*
G01X199703Y1967691D02*
X199704Y1967735D01*
G01X199701Y1967645D02*
X199703Y1967691D01*
G01X199697Y1967597D02*
X199701Y1967645D01*
G01X199693Y1967546D02*
X199697Y1967597D01*
G01X199687Y1967493D02*
X199693Y1967546D01*
G01X199680Y1967438D02*
X199687Y1967493D01*
G01X199673Y1967380D02*
X199680Y1967438D01*
G01X199664Y1967321D02*
X199673Y1967380D01*
G01D02*
X199664Y1967321D01*
G01X199680Y1967438D02*
X199673Y1967380D01*
G01X199687Y1967493D02*
X199680Y1967438D01*
G01X199693Y1967546D02*
X199687Y1967493D01*
G01X199697Y1967597D02*
X199693Y1967546D01*
G01X199701Y1967645D02*
X199697Y1967597D01*
G01X199703Y1967691D02*
X199701Y1967645D01*
G01X199704Y1967735D02*
X199703Y1967691D01*
G01X199704Y1967776D02*
Y1967735D01*
G01X199702Y1967814D02*
X199704Y1967776D01*
G01X199699Y1967850D02*
X199702Y1967814D01*
G01X199695Y1967883D02*
X199699Y1967850D01*
G01X199689Y1967913D02*
X199695Y1967883D01*
G01X199682Y1967940D02*
X199689Y1967913D01*
G01X199673Y1967965D02*
X199682Y1967940D01*
G01X199663Y1967986D02*
X199673Y1967965D01*
G01X199651Y1968004D02*
X199663Y1967986D01*
G01X199638Y1968020D02*
X199651Y1968004D01*
G01X197638Y1959705D02*
X200921D01*
G01X199606Y1968051D02*
X204330Y1963406D01*
G01Y1962302D02*
X199610Y1966944D01*
G01X199651Y1968004D02*
X199638Y1968020D01*
G01X197638Y1957736D02*
X195669Y1959705D01*
G01X199673Y1967965D02*
X199663Y1967986D01*
G01X199702Y1967814D02*
X199699Y1967850D01*
G01X204330Y1961673D02*
Y1963406D01*
G01X199606Y1966870D02*
Y1959705D01*
G01X199636Y1967134D02*
X199655Y1967260D01*
G01X199664Y1967321D02*
X199627Y1967071D01*
G01X200921Y1959705D02*
X204330Y1961673D01*
G01X246841Y-51088D02*
Y-70025D01*
G01Y2126667D02*
Y2107730D01*
G01X278642Y267717D02*
G03I-6989J0D01*
G01X287401D02*
G03I-15748J0D01*
G01Y673228D02*
G03I-15748J0D01*
G01X278642D02*
G03I-6989J0D01*
G01X287401Y1078740D02*
G03I-15748J0D01*
G01X278642D02*
G03I-6989J0D01*
G01X287401Y1484252D02*
G03I-15748J0D01*
G01X278642D02*
G03I-6989J0D01*
G01Y1889764D02*
G03I-6989J0D01*
G01X287401D02*
G03I-15748J0D01*
G01X358877Y-66238D02*
Y-54831D01*
X353601Y-63006D01*
X360731D01*
G01X358877Y2111517D02*
Y2122924D01*
X353601Y2114749D01*
X360731D01*
G01X447093Y-51088D02*
X1628688D01*
G01X466510D02*
Y-70025D01*
G01Y2126667D02*
Y2107730D01*
G01X573699Y-64527D02*
X574554Y-65478D01*
X575552Y-66048D01*
X576836Y-66238D01*
X578120Y-65858D01*
X579118Y-65098D01*
X579831Y-63767D01*
X579973Y-62246D01*
X579688Y-60725D01*
X578975Y-59774D01*
X577977Y-59014D01*
X576979Y-58824D01*
X575980Y-59014D01*
X574697Y-59774D01*
X575125Y-54831D01*
X578975D01*
G01X573699Y2113228D02*
X574554Y2112277D01*
X575552Y2111707D01*
X576836Y2111517D01*
X578120Y2111897D01*
X579118Y2112657D01*
X579831Y2113988D01*
X579973Y2115509D01*
X579688Y2117030D01*
X578975Y2117981D01*
X577977Y2118741D01*
X576979Y2118931D01*
X575980Y2118741D01*
X574697Y2117981D01*
X575125Y2122924D01*
X578975D01*
G01X686180Y-51088D02*
Y-70025D01*
G01Y2126667D02*
Y2107730D01*
G01X793796Y-61485D02*
X794794Y-60154D01*
X795649Y-59394D01*
X796790Y-59014D01*
X797789Y-59394D01*
X798501Y-60154D01*
X799072Y-61295D01*
X799214Y-62626D01*
X799072Y-63767D01*
X798501Y-64907D01*
X797646Y-65858D01*
X796648Y-66238D01*
X795507Y-65858D01*
X794509Y-64717D01*
X793938Y-63006D01*
X793796Y-61105D01*
X794081Y-58634D01*
X794509Y-57302D01*
X795221Y-55972D01*
X796220Y-55021D01*
X797218Y-54831D01*
X798216Y-55211D01*
X798929Y-56162D01*
G01X793796Y2116270D02*
X794794Y2117601D01*
X795649Y2118361D01*
X796790Y2118741D01*
X797789Y2118361D01*
X798501Y2117601D01*
X799072Y2116460D01*
X799214Y2115129D01*
X799072Y2113988D01*
X798501Y2112848D01*
X797646Y2111897D01*
X796648Y2111517D01*
X795507Y2111897D01*
X794509Y2113038D01*
X793938Y2114749D01*
X793796Y2116650D01*
X794081Y2119121D01*
X794509Y2120453D01*
X795221Y2121783D01*
X796220Y2122734D01*
X797218Y2122924D01*
X798216Y2122544D01*
X798929Y2121593D01*
G01X819134Y198327D02*
Y171752D01*
G01X839212D02*
X819134D01*
G01X839212Y198327D02*
X819134D01*
G01X839212Y1793799D02*
X819134D01*
G01Y1820374D02*
Y1793799D01*
G01X839212Y1820374D02*
X819134D01*
G01X839212Y171752D02*
Y198327D01*
G01X833504Y175689D02*
Y179331D01*
G01X832519Y175689D02*
Y179331D01*
G01X830945Y175689D02*
Y179331D01*
G01X829960Y175689D02*
Y179331D01*
G01X828386Y175689D02*
Y179331D01*
G01X827401Y175689D02*
Y179331D01*
G01X825827Y175689D02*
Y179331D01*
G01X824842Y175689D02*
Y179331D01*
G01X825827Y177658D02*
X824842D01*
G01X830945D02*
X829960D01*
G01X828386D02*
X827401D01*
G01X833504D02*
X832519D01*
G01X825827Y177576D02*
X824842D01*
G01X828386D02*
X827401D01*
G01X830945D02*
X829960D01*
G01X833504D02*
X832519D01*
G01X825827Y175689D02*
X824842D01*
G01X828386D02*
X827401D01*
G01X830945D02*
X829960D01*
G01X833504D02*
X832519D01*
G01X833701Y188977D02*
G03I-591J0D01*
G01X835275Y179331D02*
Y190748D01*
G01X833701Y192077D02*
Y192028D01*
G01X833504Y190748D02*
Y194390D01*
G01X833307Y192028D02*
Y192077D01*
G01X832519Y190748D02*
Y194390D01*
G01X830945Y190748D02*
Y194390D01*
G01X829960Y190748D02*
Y194390D01*
G01X828386Y190748D02*
Y194390D01*
G01X827401Y190748D02*
Y194390D01*
G01X825827Y190748D02*
Y194390D01*
G01X824842Y190748D02*
Y194390D01*
G01X823071Y190748D02*
Y179331D01*
G01X833642Y192126D02*
X833701Y192077D01*
G01X833634D02*
X833575Y192126D01*
G01X825827Y194390D02*
X824842D01*
G01X828386D02*
X827401D01*
G01X830945D02*
X829960D01*
G01X833504D02*
X832519D01*
G01X825827Y192503D02*
X824842D01*
G01X830945D02*
X829960D01*
G01X828386D02*
X827401D01*
G01X833504D02*
X832519D01*
G01X825827Y192421D02*
X824842D01*
G01X830945D02*
X829960D01*
G01X828386D02*
X827401D01*
G01X833504D02*
X832519D01*
G01X833575Y192126D02*
X833642D01*
G01X833504Y192077D02*
X833634D01*
G01X833307D02*
X833504D01*
G01X833701Y192028D02*
X833504D01*
G01D02*
X833307D01*
G01X825827Y191027D02*
X824842D01*
G01X830945D02*
X829960D01*
G01X828386D02*
X827401D01*
G01X833504D02*
X832519D01*
G01X825827Y190945D02*
X824842D01*
G01X830945D02*
X829960D01*
G01X828386D02*
X827401D01*
G01X833504D02*
X832519D01*
G01X835275Y190748D02*
X823071D01*
G01Y179331D02*
X835275D01*
G01X825827Y179134D02*
X824842D01*
G01X830945D02*
X829960D01*
G01X828386D02*
X827401D01*
G01X833504D02*
X832519D01*
G01X825827Y179053D02*
X824842D01*
G01X828386D02*
X827401D01*
G01X830945D02*
X829960D01*
G01X833504D02*
X832519D01*
G01X823071Y1801378D02*
X835275D01*
G01X825827Y1801181D02*
X824842D01*
G01X830945D02*
X829960D01*
G01X828386D02*
X827401D01*
G01X833504D02*
X832519D01*
G01X825827Y1801100D02*
X824842D01*
G01X828386D02*
X827401D01*
G01X830945D02*
X829960D01*
G01X833504D02*
X832519D01*
G01X825827Y1799705D02*
X824842D01*
G01X830945D02*
X829960D01*
G01X828386D02*
X827401D01*
G01X833504D02*
X832519D01*
G01X825827Y1799623D02*
X824842D01*
G01X828386D02*
X827401D01*
G01X830945D02*
X829960D01*
G01X833504D02*
X832519D01*
G01X825827Y1797736D02*
X824842D01*
G01X828386D02*
X827401D01*
G01X830945D02*
X829960D01*
G01X833504D02*
X832519D01*
G01X839212Y1793799D02*
Y1820374D01*
G01X835275Y1801378D02*
Y1812795D01*
G01X833504Y1797736D02*
Y1801378D01*
G01X832519Y1797736D02*
Y1801378D01*
G01X830945Y1797736D02*
Y1801378D01*
G01X829960Y1797736D02*
Y1801378D01*
G01X828386Y1797736D02*
Y1801378D01*
G01X827401Y1797736D02*
Y1801378D01*
G01X825827Y1797736D02*
Y1801378D01*
G01X824842Y1797736D02*
Y1801378D01*
G01X823071Y1812795D02*
Y1801378D01*
G01X833701Y1811024D02*
G03I-591J0D01*
G01X833642Y1814173D02*
X833701Y1814124D01*
G01X833634D02*
X833575Y1814173D01*
G01X825827Y1816437D02*
X824842D01*
G01X828386D02*
X827401D01*
G01X830945D02*
X829960D01*
G01X833504D02*
X832519D01*
G01X825827Y1814550D02*
X824842D01*
G01X830945D02*
X829960D01*
G01X828386D02*
X827401D01*
G01X833504D02*
X832519D01*
G01X825827Y1814469D02*
X824842D01*
G01X830945D02*
X829960D01*
G01X828386D02*
X827401D01*
G01X833504D02*
X832519D01*
G01X833575Y1814173D02*
X833642D01*
G01X833504Y1814124D02*
X833634D01*
G01X833307D02*
X833504D01*
G01X833701Y1814075D02*
X833504D01*
G01D02*
X833307D01*
G01X825827Y1813074D02*
X824842D01*
G01X830945D02*
X829960D01*
G01X828386D02*
X827401D01*
G01X833504D02*
X832519D01*
G01X825827Y1812992D02*
X824842D01*
G01X830945D02*
X829960D01*
G01X828386D02*
X827401D01*
G01X833504D02*
X832519D01*
G01X835275Y1812795D02*
X823071D01*
G01X833701Y1814124D02*
Y1814075D01*
G01X833504Y1812795D02*
Y1816437D01*
G01X833307Y1814075D02*
Y1814124D01*
G01X832519Y1812795D02*
Y1816437D01*
G01X830945Y1812795D02*
Y1816437D01*
G01X829960Y1812795D02*
Y1816437D01*
G01X828386Y1812795D02*
Y1816437D01*
G01X827401Y1812795D02*
Y1816437D01*
G01X825827Y1812795D02*
Y1816437D01*
G01X824842Y1812795D02*
Y1816437D01*
G01X881890Y169941D02*
Y182894D01*
G01X909449Y169941D02*
X881890D01*
G01X888976Y191614D02*
G03I-2559J0D01*
G01X889764D02*
G03I-3347J0D01*
G01X889921D02*
G03I-3504J0D01*
G01X886342Y195747D02*
G03X886417Y187480I75J-4133D01*
G01X881890Y200099D02*
Y201851D01*
G01X874016Y186831D02*
Y200099D01*
G01X870079Y349941D02*
Y182894D01*
G01X893701Y200099D02*
X874016D01*
G01Y198327D02*
X893701D01*
G01X874016Y195177D02*
X924016D01*
G01X874016Y192225D02*
X894488D01*
G01X927953Y186831D02*
X874016D01*
G01X870079Y182894D02*
X881890D01*
G01X878810Y203248D02*
X878911Y203281D01*
G01X885039Y203032D02*
X881890Y201851D01*
G01X885039Y208032D02*
X881890Y206851D01*
G01X885039Y213032D02*
X881890Y211851D01*
G01X885039Y218032D02*
X881890Y216851D01*
G01X877872Y204101D02*
X878006Y204167D01*
G01X878040Y203970D02*
X877939Y203904D01*
G01X878978Y204429D02*
X879212Y204626D01*
G01X878944D02*
X878710Y204429D01*
G01X879025Y203130D02*
X878978Y203084D01*
G01X879112Y203215D02*
X879025Y203130D01*
G01X877738Y203970D02*
X877872Y204101D01*
G01X878911Y203281D02*
X878978Y203379D01*
G01X877939Y203904D02*
X877872Y203806D01*
G01X879179Y203347D02*
X879112Y203215D01*
G01X877671Y203839D02*
X877738Y203970D01*
G01X878978Y203379D02*
X879011Y203478D01*
G01X879212D02*
X879179Y203347D01*
G01X877872Y203806D02*
X877839Y203675D01*
G01X877638D02*
X877671Y203839D01*
G01X884134Y218130D02*
Y219705D01*
G01Y213130D02*
Y214705D01*
G01Y208130D02*
Y209705D01*
G01Y203130D02*
Y204705D01*
G01X882559Y218130D02*
Y219705D01*
G01Y213130D02*
Y214705D01*
G01Y208130D02*
Y209705D01*
G01Y203130D02*
Y204705D01*
G01X881890Y220984D02*
Y221851D01*
G01Y215984D02*
Y216851D01*
G01Y210984D02*
Y211851D01*
G01Y205984D02*
Y206851D01*
G01X881771Y204705D02*
Y203130D01*
G01Y209705D02*
Y208130D01*
G01Y214705D02*
Y213130D01*
G01Y219705D02*
Y218130D01*
G01X881378Y204705D02*
Y203130D01*
G01Y209705D02*
Y208130D01*
G01Y214705D02*
Y213130D01*
G01Y219705D02*
Y218130D01*
G01X879212Y204705D02*
Y204823D01*
G01Y204626D02*
Y204705D01*
G01Y203642D02*
Y203478D01*
G01X879011D02*
Y203675D01*
G01X878844Y203871D02*
Y204068D01*
G01X878542Y203675D02*
Y203478D01*
G01X878341D02*
Y203675D01*
G01X878073Y203130D02*
Y202953D01*
G01Y203150D02*
Y203130D01*
G01X877839Y203675D02*
Y203412D01*
G01X877638D02*
Y203675D01*
G01Y204823D02*
Y204705D01*
G01D02*
Y204626D01*
G01X876456Y218130D02*
Y219705D01*
G01Y213130D02*
Y214705D01*
G01Y208130D02*
Y209705D01*
G01Y203130D02*
Y204705D01*
G01X879179Y203806D02*
X879212Y203642D01*
G01X878509Y203839D02*
X878542Y203675D01*
G01X877671Y203248D02*
X877638Y203412D01*
G01X878341Y203675D02*
X878308Y203806D01*
G01X878375Y203347D02*
X878341Y203478D01*
G01X877839Y203412D02*
X877872Y203281D01*
G01X879011Y203675D02*
X878978Y203773D01*
G01X878542Y203478D02*
X878576Y203379D01*
G01X878442Y203970D02*
X878509Y203839D01*
G01X878442Y203215D02*
X878375Y203347D01*
G01X877772Y203084D02*
X877743Y203130D01*
G01D02*
X877671Y203248D01*
G01X878308Y203806D02*
X878241Y203904D01*
G01X878576Y203379D02*
X878643Y203281D01*
G01X879079Y203937D02*
X879179Y203806D01*
G01X878978Y203773D02*
X878911Y203839D01*
G01X878308Y204101D02*
X878442Y203970D01*
G01X878529Y203130D02*
X878442Y203215D01*
G01X878576Y203084D02*
X878529Y203130D01*
G01X877872Y203281D02*
X877973Y203182D01*
G01X878944Y204036D02*
X879079Y203937D01*
G01X878241Y203904D02*
X878140Y203970D01*
G01X877939Y202986D02*
X877772Y203084D01*
G01X878911Y203839D02*
X878844Y203871D01*
G01X878174Y204167D02*
X878308Y204101D01*
G01X881890Y220984D02*
X885039Y219803D01*
G01X881890Y215984D02*
X885039Y214803D01*
G01X881890Y210984D02*
X885039Y209803D01*
G01X881890Y205984D02*
X885039Y204803D01*
G01X878844Y204068D02*
X878944Y204036D01*
G01X878643Y203281D02*
X878743Y203248D01*
G01X877973Y203182D02*
X878073Y203150D01*
G01X878710Y203051D02*
X878576Y203084D01*
G01X878073Y202953D02*
X877939Y202986D01*
G01X889764Y219803D02*
X885039D01*
G01X876456Y219705D02*
X893701D01*
G01Y218130D02*
X876456D01*
G01X885039Y218032D02*
X889764D01*
G01Y214803D02*
X885039D01*
G01X876456Y214705D02*
X893701D01*
G01Y213130D02*
X876456D01*
G01X885039Y213032D02*
X889764D01*
G01Y209803D02*
X885039D01*
G01X876456Y209705D02*
X893701D01*
G01Y208130D02*
X876456D01*
G01X885039Y208032D02*
X889764D01*
G01X879212Y204823D02*
X877638D01*
G01X889764Y204803D02*
X885039D01*
G01X876456Y204705D02*
X893701D01*
G01X877638Y204626D02*
X878944D01*
G01X878710Y204429D02*
X878978D01*
G01X878006Y204167D02*
X878174D01*
G01X878140Y203970D02*
X878040D01*
G01X878743Y203248D02*
X878810D01*
G01X893701Y203130D02*
X876456D01*
G01X878844Y203051D02*
X878710D01*
G01X885039Y203032D02*
X889764D01*
G01X878978Y203084D02*
X878844Y203051D01*
G01X885039Y223032D02*
X881890Y221851D01*
G01X885039Y228032D02*
X881890Y226851D01*
G01X885039Y233032D02*
X881890Y231851D01*
G01X885591Y237211D02*
X885424Y237146D01*
G01X885156Y238261D02*
X885323Y238327D01*
G01X885156Y236817D02*
X885290Y236883D01*
G01X885323Y236686D02*
X885223Y236621D01*
G01X885558Y237408D02*
X885424Y237310D01*
G01X885189Y238064D02*
X885323Y238163D01*
G01X885021Y236686D02*
X885156Y236817D01*
G01X885759Y238130D02*
X885859Y238228D01*
G01X885055Y238163D02*
X885156Y238261D01*
G01X885692Y237343D02*
X885591Y237211D01*
G01X885223Y236621D02*
X885156Y236522D01*
G01X884955Y237999D02*
X885055Y238163D01*
G01X885725Y237408D02*
X885692Y237343D01*
G01X885625Y237540D02*
X885558Y237408D01*
G01X885725Y238064D02*
X885759Y238130D01*
G01X884955Y236555D02*
X885021Y236686D01*
G01X885122Y237933D02*
X885189Y238064D01*
G01X885658Y237671D02*
X885630Y237559D01*
G01D02*
X885625Y237540D01*
G01X885156Y236522D02*
X885122Y236391D01*
G01X885089Y237802D02*
X885122Y237933D01*
G01X884921Y236391D02*
X884955Y236555D01*
G01X884921Y237835D02*
X884955Y237999D01*
G01X885658Y237802D02*
Y237671D01*
G01X885630Y234803D02*
Y235394D01*
G01X885625Y236194D02*
Y236378D01*
G01D02*
Y236391D01*
G01X885356Y235866D02*
Y235669D01*
G01X885122Y236378D02*
Y236128D01*
G01Y236391D02*
Y236378D01*
G01X885089Y237671D02*
Y237802D01*
G01X884921Y237638D02*
Y237835D01*
G01Y236128D02*
Y236378D01*
G01D02*
Y236391D01*
G01X884449Y239528D02*
Y240709D01*
G01Y236378D02*
Y237559D01*
G01X884134Y233130D02*
Y234705D01*
G01Y228130D02*
Y229705D01*
G01Y223130D02*
Y224705D01*
G01X882559Y233130D02*
Y234705D01*
G01Y228130D02*
Y229705D01*
G01Y223130D02*
Y224705D01*
G01X881890Y230984D02*
Y231851D01*
G01Y225984D02*
Y226851D01*
G01X881771Y224705D02*
Y223130D01*
G01Y229705D02*
Y228130D01*
G01Y234705D02*
Y233130D01*
G01X881378Y224705D02*
Y223130D01*
G01Y229705D02*
Y228130D01*
G01Y234705D02*
Y233130D01*
G01X876456D02*
Y234705D01*
G01Y228130D02*
Y229705D01*
G01Y223130D02*
Y224705D01*
G01X884937Y237559D02*
X884921Y237638D01*
G01X884955Y237474D02*
X884937Y237559D01*
G01X884955Y235965D02*
X884921Y236128D01*
G01X885625Y237933D02*
X885658Y237802D01*
G01X885625Y236391D02*
X885591Y236522D01*
G01X885658Y236063D02*
X885625Y236194D01*
G01X885117Y237559D02*
X885089Y237671D01*
G01X885122Y237540D02*
X885117Y237559D01*
G01X885122Y236128D02*
X885156Y235997D01*
G01X885692Y238130D02*
X885725Y238064D01*
G01X885558D02*
X885625Y237933D01*
G01X885759Y237343D02*
X885725Y237408D01*
G01Y236686D02*
X885792Y236555D01*
G01X885189Y237408D02*
X885122Y237540D01*
G01X885725Y235932D02*
X885658Y236063D01*
G01X885055Y237310D02*
X884955Y237474D01*
G01X885055Y235801D02*
X884955Y235965D01*
G01X885591Y236522D02*
X885524Y236621D01*
G01X885591Y238261D02*
X885692Y238130D01*
G01X885859Y237244D02*
X885759Y237343D01*
G01X885591Y236817D02*
X885725Y236686D01*
G01X885156Y237211D02*
X885055Y237310D01*
G01X885859Y235801D02*
X885725Y235932D01*
G01X885156Y235997D02*
X885256Y235899D01*
G01X885424Y238163D02*
X885558Y238064D01*
G01X885323Y237310D02*
X885189Y237408D01*
G01X885524Y236621D02*
X885424Y236686D01*
G01X885223Y235702D02*
X885055Y235801D01*
G01X885457Y236883D02*
X885591Y236817D01*
G01X885424Y238327D02*
X885591Y238261D01*
G01X885323Y237146D02*
X885156Y237211D01*
G01X881890Y230984D02*
X885039Y229803D01*
G01X881890Y225984D02*
X885039Y224803D01*
G01X885256Y235899D02*
X885356Y235866D01*
G01Y235669D02*
X885223Y235702D01*
G01X884449Y240709D02*
X896456D01*
G01X884449Y239528D02*
X896456D01*
G01X885323Y238327D02*
X885424D01*
G01X885323Y238163D02*
X885424D01*
G01X884449Y237559D02*
X896456D01*
G01X885424Y237310D02*
X885323D01*
G01X885424Y237146D02*
X885323D01*
G01X885290Y236883D02*
X885457D01*
G01X885424Y236686D02*
X885323D01*
G01X884449Y236378D02*
X896456D01*
G01X885630Y235394D02*
X888976D01*
G01X889764Y234803D02*
X885630D01*
G01X876456Y234705D02*
X893701D01*
G01Y233130D02*
X876456D01*
G01X885039Y233032D02*
X889764D01*
G01Y229803D02*
X885039D01*
G01X876456Y229705D02*
X893701D01*
G01Y228130D02*
X876456D01*
G01X885039Y228032D02*
X889764D01*
G01Y224803D02*
X885039D01*
G01X876456Y224705D02*
X893701D01*
G01Y223130D02*
X876456D01*
G01X885039Y223032D02*
X889764D01*
G01X878682Y258977D02*
X878783Y259009D01*
G01X878749Y259206D02*
X878649Y259173D01*
G01X885039Y263032D02*
X881890Y261851D01*
G01X878649Y259173D02*
X878515Y259075D01*
G01X879017Y259469D02*
X879252Y259666D01*
G01X878984D02*
X878749Y259469D01*
G01X878615Y258911D02*
X878682Y258977D01*
G01X878515Y259075D02*
X878414Y258943D01*
G01X878582Y258812D02*
X878615Y258911D01*
G01X878414Y258943D02*
X878380Y258780D01*
G01X885630Y257441D02*
Y258032D01*
G01X884449Y255276D02*
Y256457D01*
G01Y248977D02*
Y250158D01*
G01Y252126D02*
Y253307D01*
G01Y245827D02*
Y247008D01*
G01Y242677D02*
Y243858D01*
G01X884134Y263130D02*
Y264705D01*
G01Y258130D02*
Y259705D01*
G01X882559Y263130D02*
Y264705D01*
G01Y258130D02*
Y259705D01*
G01X881890Y260984D02*
Y261851D01*
G01X881771Y259705D02*
Y258130D01*
G01Y264705D02*
Y263130D01*
G01X881378Y259705D02*
Y258130D01*
G01Y264705D02*
Y263130D01*
G01X879252Y259705D02*
Y259862D01*
G01Y259666D02*
Y259705D01*
G01Y257992D02*
Y258130D01*
G01D02*
Y258780D01*
G01X879084Y258812D02*
Y258189D01*
G01X878582D02*
Y258812D01*
G01X878380Y258780D02*
Y258189D01*
G01X877677Y258130D02*
Y257992D01*
G01Y258189D02*
Y258130D01*
G01Y259862D02*
Y259705D01*
G01D02*
Y259666D01*
G01X876456Y263130D02*
Y264705D01*
G01X875000Y258130D02*
Y259705D01*
G01X879252Y258780D02*
X879218Y258943D01*
G01X879051Y258911D02*
X879084Y258812D01*
G01X879218Y258943D02*
X879118Y259075D01*
G01X878984Y258977D02*
X879051Y258911D01*
G01X879118Y259075D02*
X878984Y259173D01*
G01X881890Y260984D02*
X885039Y259803D01*
G01X878984Y259173D02*
X878883Y259206D01*
G01Y259009D02*
X878984Y258977D01*
G01X893701Y263130D02*
X876456D01*
G01X885039Y263032D02*
X889764D01*
G01X879252Y259862D02*
X877677D01*
G01X889764Y259803D02*
X885039D01*
G01X875000Y259705D02*
X893701D01*
G01X877677Y259666D02*
X878984D01*
G01X878749Y259469D02*
X879017D01*
G01X878883Y259206D02*
X878749D01*
G01X878783Y259009D02*
X878883D01*
G01X879084Y258189D02*
X878582D01*
G01X878380D02*
X877677D01*
G01X875000Y258130D02*
X893701D01*
G01X885630Y258032D02*
X889764D01*
G01X877677Y257992D02*
X879252D01*
G01X888976Y257441D02*
X885630D01*
G01X884449Y256457D02*
X896456D01*
G01X884449Y255276D02*
X896456D01*
G01X884449Y253307D02*
X896456D01*
G01X884449Y252126D02*
X896456D01*
G01X884449Y250158D02*
X896456D01*
G01X884449Y248977D02*
X896456D01*
G01X884449Y247008D02*
X896456D01*
G01X884449Y245827D02*
X896456D01*
G01X884449Y243858D02*
X896456D01*
G01X884449Y242677D02*
X896456D01*
G01X885039Y268032D02*
X881890Y266851D01*
G01X885039Y278032D02*
X881890Y276851D01*
G01X885039Y283032D02*
X881890Y281851D01*
G01X884134Y283130D02*
Y284705D01*
G01Y278130D02*
Y279705D01*
G01Y273130D02*
Y274705D01*
G01Y268130D02*
Y269705D01*
G01X882559Y283130D02*
Y284705D01*
G01Y278130D02*
Y279705D01*
G01Y273130D02*
Y274705D01*
G01Y268130D02*
Y269705D01*
G01X881890Y280984D02*
Y281851D01*
G01Y275984D02*
Y276851D01*
G01Y270984D02*
Y271851D01*
G01Y265984D02*
Y266851D01*
G01X881771Y269705D02*
Y268130D01*
G01Y274705D02*
Y273130D01*
G01Y279705D02*
Y278130D01*
G01Y284705D02*
Y283130D01*
G01X881378Y269705D02*
Y268130D01*
G01Y274705D02*
Y273130D01*
G01Y279705D02*
Y278130D01*
G01Y284705D02*
Y283130D01*
G01X876456D02*
Y284705D01*
G01Y278130D02*
Y279705D01*
G01Y268130D02*
Y269705D01*
G01X875000Y273130D02*
Y274705D01*
G01X881890Y280984D02*
X885039Y279803D01*
G01X881890Y270984D02*
X885039Y269803D01*
G01X881890Y265984D02*
X885039Y264803D01*
G01X881890Y275984D02*
X887008Y274803D01*
G01X876456Y284705D02*
X893701D01*
G01Y283130D02*
X876456D01*
G01X885039Y283032D02*
X889764D01*
G01Y279803D02*
X885039D01*
G01X876456Y279705D02*
X893701D01*
G01Y278130D02*
X876456D01*
G01X885039Y278032D02*
X889764D01*
G01X875000Y274705D02*
X894882D01*
G01X875000Y273130D02*
X894882D01*
G01X889764Y269803D02*
X885039D01*
G01X876456Y269705D02*
X893701D01*
G01Y268130D02*
X876456D01*
G01X885039Y268032D02*
X889764D01*
G01Y264803D02*
X885039D01*
G01X876456Y264705D02*
X893701D01*
G01X887008Y273032D02*
X881890Y271851D01*
G01X885039Y288032D02*
X881890Y286851D01*
G01X885039Y293032D02*
X881890Y291851D01*
G01X885039Y298032D02*
X881890Y296851D01*
G01X885039Y303032D02*
X881890Y301851D01*
G01X884134Y303130D02*
Y304705D01*
G01Y298130D02*
Y299705D01*
G01Y293130D02*
Y294705D01*
G01Y288130D02*
Y289705D01*
G01X882559Y303130D02*
Y304705D01*
G01Y298130D02*
Y299705D01*
G01Y293130D02*
Y294705D01*
G01Y288130D02*
Y289705D01*
G01X881890Y300984D02*
Y301851D01*
G01Y295984D02*
Y296851D01*
G01Y290984D02*
Y291851D01*
G01Y285984D02*
Y286851D01*
G01X881771Y289705D02*
Y288130D01*
G01Y294705D02*
Y293130D01*
G01Y299705D02*
Y298130D01*
G01Y304705D02*
Y303130D01*
G01X881378Y289705D02*
Y288130D01*
G01Y294705D02*
Y293130D01*
G01Y299705D02*
Y298130D01*
G01Y304705D02*
Y303130D01*
G01X876456D02*
Y304705D01*
G01Y298130D02*
Y299705D01*
G01Y293130D02*
Y294705D01*
G01Y288130D02*
Y289705D01*
G01X881890Y305984D02*
X885039Y304803D01*
G01X881890Y300984D02*
X885039Y299803D01*
G01X881890Y295984D02*
X885039Y294803D01*
G01X881890Y290984D02*
X885039Y289803D01*
G01X881890Y285984D02*
X885039Y284803D01*
G01X889764Y304803D02*
X885039D01*
G01X876456Y304705D02*
X893701D01*
G01Y303130D02*
X876456D01*
G01X885039Y303032D02*
X889764D01*
G01Y299803D02*
X885039D01*
G01X876456Y299705D02*
X893701D01*
G01Y298130D02*
X876456D01*
G01X885039Y298032D02*
X889764D01*
G01Y294803D02*
X885039D01*
G01X876456Y294705D02*
X893701D01*
G01Y293130D02*
X876456D01*
G01X885039Y293032D02*
X889764D01*
G01Y289803D02*
X885039D01*
G01X876456Y289705D02*
X893701D01*
G01Y288130D02*
X876456D01*
G01X885039Y288032D02*
X889764D01*
G01Y284803D02*
X885039D01*
G01Y308032D02*
X881890Y306851D01*
G01X885039Y318032D02*
X881890Y316851D01*
G01X885039Y323032D02*
X881890Y321851D01*
G01X885039Y328032D02*
X881890Y326851D01*
G01X884134Y323130D02*
Y324705D01*
G01Y318130D02*
Y319705D01*
G01Y313130D02*
Y314705D01*
G01Y308130D02*
Y309705D01*
G01X882559Y323130D02*
Y324705D01*
G01Y318130D02*
Y319705D01*
G01Y313130D02*
Y314705D01*
G01Y308130D02*
Y309705D01*
G01X881890Y325984D02*
Y326851D01*
G01Y320984D02*
Y321851D01*
G01Y315984D02*
Y316851D01*
G01Y310984D02*
Y311851D01*
G01Y305984D02*
Y306851D01*
G01X881771Y309705D02*
Y308130D01*
G01Y314705D02*
Y313130D01*
G01Y319705D02*
Y318130D01*
G01Y324705D02*
Y323130D01*
G01X881378Y309705D02*
Y308130D01*
G01Y314705D02*
Y313130D01*
G01Y319705D02*
Y318130D01*
G01Y324705D02*
Y323130D01*
G01X876456D02*
Y324705D01*
G01Y318130D02*
Y319705D01*
G01Y308130D02*
Y309705D01*
G01X875000Y313130D02*
Y314705D01*
G01X881890Y325984D02*
X885039Y324803D01*
G01X881890Y320984D02*
X885039Y319803D01*
G01X881890Y310984D02*
X885039Y309803D01*
G01X881890Y315984D02*
X887008Y314803D01*
G01X889764Y324803D02*
X885039D01*
G01X876456Y324705D02*
X893701D01*
G01Y323130D02*
X876456D01*
G01X885039Y323032D02*
X889764D01*
G01Y319803D02*
X885039D01*
G01X876456Y319705D02*
X893701D01*
G01Y318130D02*
X876456D01*
G01X885039Y318032D02*
X889764D01*
G01X875000Y314705D02*
X894882D01*
G01X875000Y313130D02*
X894882D01*
G01X889764Y309803D02*
X885039D01*
G01X876456Y309705D02*
X893701D01*
G01Y308130D02*
X876456D01*
G01X885039Y308032D02*
X889764D01*
G01X887008Y313032D02*
X881890Y311851D01*
G01X884285Y343037D02*
X884400Y342795D01*
G01X884167Y343300D02*
X884285Y343037D01*
G01X884047Y343583D02*
X884167Y343300D01*
G01X884046Y338857D02*
X884047Y338858D01*
G01X884045Y338853D02*
X884046Y338857D01*
G01X884020Y338795D02*
X884045Y338853D01*
G01X884280Y339393D02*
X884400Y339646D01*
G01X884163Y339131D02*
X884280Y339393D01*
G01X884047Y338858D02*
X884163Y339131D01*
G01X884400Y342795D02*
G03Y339646I2017J-1574D01*
G01X884047Y343583D02*
G03Y338858I2370J-2363D01*
G01X889921Y341221D02*
G03I-3504J0D01*
G01X883740Y344370D02*
G03Y338071I2677J-3149D01*
G01X883982Y338701D02*
X884020Y338795D01*
G01X883899Y338493D02*
X883982Y338701D01*
G01X883865Y338406D02*
X883899Y338493D01*
G01X883830Y338315D02*
X883865Y338406D01*
G01X883794Y338219D02*
X883830Y338315D01*
G01X883740Y338071D02*
X883794Y338219D01*
G01X884134Y328130D02*
Y329705D01*
G01X882559Y328130D02*
Y329705D01*
G01X881890Y330984D02*
Y332736D01*
G01X881771Y329705D02*
Y328130D01*
G01X881378Y329705D02*
Y328130D01*
G01X876456D02*
Y329705D01*
G01X874016Y332736D02*
Y346004D01*
G01X883794Y344222D02*
X883740Y344370D01*
G01X883830Y344126D02*
X883794Y344222D01*
G01X883865Y344035D02*
X883830Y344126D01*
G01X883899Y343949D02*
X883865Y344035D01*
G01X883970Y343769D02*
X883899Y343949D01*
G01X884003Y343688D02*
X883970Y343769D01*
G01X884047Y343583D02*
X884003Y343688D01*
G01X881890Y330984D02*
X885039Y329803D01*
G01X927953Y346004D02*
X874016D01*
G01X883740Y344370D02*
X889095D01*
G01X888788Y343583D02*
X884047D01*
G01X884400Y342795D02*
X888434D01*
G01X894488Y340610D02*
X874016D01*
G01X884400Y339646D02*
X888434D01*
G01X884047Y338858D02*
X888788D01*
G01X889095Y338071D02*
X883740D01*
G01X924016Y337658D02*
X874016D01*
G01X893701Y334508D02*
X874016D01*
G01Y332736D02*
X893701D01*
G01X889764Y329803D02*
X885039D01*
G01X876456Y329705D02*
X893701D01*
G01Y328130D02*
X876456D01*
G01X885039Y328032D02*
X889764D01*
G01X881890Y349941D02*
Y362894D01*
G01D02*
X909449D01*
G01X881890Y349941D02*
X870079D01*
G01X881890Y575453D02*
Y588406D01*
G01X909449Y575453D02*
X881890D01*
G01X888976Y597126D02*
G03I-2559J0D01*
G01X889764D02*
G03I-3347J0D01*
G01X889921D02*
G03I-3504J0D01*
G01X886342Y601259D02*
G03X886417Y592992I75J-4133D01*
G01X874016Y592343D02*
Y605610D01*
G01X870079Y755453D02*
Y588406D01*
G01X874016Y600689D02*
X924016D01*
G01X874016Y597736D02*
X894488D01*
G01X927953Y592343D02*
X874016D01*
G01X870079Y588406D02*
X881890D01*
G01X878810Y608760D02*
X878911Y608793D01*
G01X885039Y608543D02*
X881890Y607362D01*
G01X885039Y613543D02*
X881890Y612362D01*
G01X885039Y618543D02*
X881890Y617362D01*
G01X885039Y623543D02*
X881890Y622362D01*
G01X877872Y609613D02*
X878006Y609678D01*
G01X878040Y609482D02*
X877939Y609416D01*
G01X878978Y609941D02*
X879212Y610138D01*
G01X878944D02*
X878710Y609941D01*
G01X879025Y608642D02*
X878978Y608596D01*
G01X879112Y608727D02*
X879025Y608642D01*
G01X877738Y609482D02*
X877872Y609613D01*
G01X878911Y608793D02*
X878978Y608891D01*
G01X877939Y609416D02*
X877872Y609317D01*
G01X879179Y608858D02*
X879112Y608727D01*
G01X877671Y609351D02*
X877738Y609482D01*
G01X878978Y608891D02*
X879011Y608990D01*
G01X879212D02*
X879179Y608858D01*
G01X877872Y609317D02*
X877839Y609186D01*
G01X877638D02*
X877671Y609351D01*
G01X884134Y618642D02*
Y620217D01*
G01Y613642D02*
Y615217D01*
G01Y608642D02*
Y610217D01*
G01X882559Y618642D02*
Y620217D01*
G01Y613642D02*
Y615217D01*
G01Y608642D02*
Y610217D01*
G01X881890Y621496D02*
Y622362D01*
G01Y616496D02*
Y617362D01*
G01Y611496D02*
Y612362D01*
G01Y605610D02*
Y607362D01*
G01X881771Y610217D02*
Y608642D01*
G01Y615217D02*
Y613642D01*
G01Y620217D02*
Y618642D01*
G01X881378Y610217D02*
Y608642D01*
G01Y615217D02*
Y613642D01*
G01Y620217D02*
Y618642D01*
G01X879212Y610217D02*
Y610335D01*
G01Y610138D02*
Y610217D01*
G01Y609154D02*
Y608990D01*
G01X879011D02*
Y609186D01*
G01X878844Y609383D02*
Y609580D01*
G01X878542Y609186D02*
Y608990D01*
G01X878341D02*
Y609186D01*
G01X878073Y608642D02*
Y608465D01*
G01Y608662D02*
Y608642D01*
G01X877839Y609186D02*
Y608924D01*
G01X877638D02*
Y609186D01*
G01Y610335D02*
Y610217D01*
G01D02*
Y610138D01*
G01X876456Y618642D02*
Y620217D01*
G01Y613642D02*
Y615217D01*
G01Y608642D02*
Y610217D01*
G01X879179Y609317D02*
X879212Y609154D01*
G01X878509Y609351D02*
X878542Y609186D01*
G01X877671Y608760D02*
X877638Y608924D01*
G01X878341Y609186D02*
X878308Y609317D01*
G01X878375Y608858D02*
X878341Y608990D01*
G01X877839Y608924D02*
X877872Y608793D01*
G01X879011Y609186D02*
X878978Y609285D01*
G01X878542Y608990D02*
X878576Y608891D01*
G01X878442Y609482D02*
X878509Y609351D01*
G01X878442Y608727D02*
X878375Y608858D01*
G01X877772Y608596D02*
X877743Y608642D01*
G01D02*
X877671Y608760D01*
G01X878308Y609317D02*
X878241Y609416D01*
G01X878576Y608891D02*
X878643Y608793D01*
G01X879079Y609449D02*
X879179Y609317D01*
G01X878978Y609285D02*
X878911Y609351D01*
G01X878308Y609613D02*
X878442Y609482D01*
G01X878576Y608596D02*
X878529Y608642D01*
G01D02*
X878442Y608727D01*
G01X877872Y608793D02*
X877973Y608694D01*
G01X878944Y609547D02*
X879079Y609449D01*
G01X878241Y609416D02*
X878140Y609482D01*
G01X877939Y608497D02*
X877772Y608596D01*
G01X878911Y609351D02*
X878844Y609383D01*
G01X878174Y609678D02*
X878308Y609613D01*
G01X881890Y621496D02*
X885039Y620315D01*
G01X881890Y616496D02*
X885039Y615315D01*
G01X881890Y611496D02*
X885039Y610315D01*
G01X878844Y609580D02*
X878944Y609547D01*
G01X878643Y608793D02*
X878743Y608760D01*
G01X877973Y608694D02*
X878073Y608662D01*
G01X878710Y608563D02*
X878576Y608596D01*
G01X878073Y608465D02*
X877939Y608497D01*
G01X889764Y620315D02*
X885039D01*
G01X876456Y620217D02*
X893701D01*
G01Y618642D02*
X876456D01*
G01X885039Y618543D02*
X889764D01*
G01Y615315D02*
X885039D01*
G01X876456Y615217D02*
X893701D01*
G01Y613642D02*
X876456D01*
G01X885039Y613543D02*
X889764D01*
G01X879212Y610335D02*
X877638D01*
G01X889764Y610315D02*
X885039D01*
G01X876456Y610217D02*
X893701D01*
G01X877638Y610138D02*
X878944D01*
G01X878710Y609941D02*
X878978D01*
G01X878006Y609678D02*
X878174D01*
G01X878140Y609482D02*
X878040D01*
G01X878743Y608760D02*
X878810D01*
G01X893701Y608642D02*
X876456D01*
G01X878844Y608563D02*
X878710D01*
G01X885039Y608543D02*
X889764D01*
G01X893701Y605610D02*
X874016D01*
G01Y603839D02*
X893701D01*
G01X878978Y608596D02*
X878844Y608563D01*
G01X885039Y628543D02*
X881890Y627362D01*
G01X885039Y633543D02*
X881890Y632362D01*
G01X885156Y642329D02*
X885290Y642395D01*
G01X885323Y642198D02*
X885223Y642132D01*
G01X885558Y642920D02*
X885424Y642821D01*
G01X885189Y643576D02*
X885323Y643675D01*
G01X885021Y642198D02*
X885156Y642329D01*
G01X885759Y643642D02*
X885859Y643740D01*
G01X885055Y643675D02*
X885156Y643773D01*
G01X885692Y642854D02*
X885591Y642723D01*
G01X885223Y642132D02*
X885156Y642034D01*
G01X884955Y643510D02*
X885055Y643675D01*
G01X885725Y642920D02*
X885692Y642854D01*
G01X885625Y643051D02*
X885558Y642920D01*
G01X885725Y643576D02*
X885759Y643642D01*
G01X884955Y642067D02*
X885021Y642198D01*
G01X885122Y643445D02*
X885189Y643576D01*
G01X885039Y638543D02*
X881890Y637362D01*
G01X885591Y642723D02*
X885424Y642658D01*
G01X885156Y643773D02*
X885323Y643839D01*
G01X885658Y643182D02*
X885630Y643071D01*
G01D02*
X885625Y643051D01*
G01X885156Y642034D02*
X885122Y641903D01*
G01X885089Y643314D02*
X885122Y643445D01*
G01X884921Y641903D02*
X884955Y642067D01*
G01X884921Y643347D02*
X884955Y643510D01*
G01X885658Y643314D02*
Y643182D01*
G01X885630Y640315D02*
Y640906D01*
G01X885625Y641706D02*
Y641890D01*
G01D02*
Y641903D01*
G01X885356Y641378D02*
Y641181D01*
G01X885122Y641890D02*
Y641640D01*
G01Y641903D02*
Y641890D01*
G01X885089Y643182D02*
Y643314D01*
G01X884921Y643150D02*
Y643347D01*
G01Y641640D02*
Y641890D01*
G01D02*
Y641903D01*
G01X884449Y641890D02*
Y643071D01*
G01X884134Y638642D02*
Y640217D01*
G01Y633642D02*
Y635217D01*
G01Y628642D02*
Y630217D01*
G01Y623642D02*
Y625217D01*
G01X882559Y638642D02*
Y640217D01*
G01Y633642D02*
Y635217D01*
G01Y628642D02*
Y630217D01*
G01Y623642D02*
Y625217D01*
G01X881890Y636496D02*
Y637362D01*
G01Y631496D02*
Y632362D01*
G01Y626496D02*
Y627362D01*
G01X881771Y625217D02*
Y623642D01*
G01Y630217D02*
Y628642D01*
G01Y635217D02*
Y633642D01*
G01Y640217D02*
Y638642D01*
G01X881378Y625217D02*
Y623642D01*
G01Y630217D02*
Y628642D01*
G01Y635217D02*
Y633642D01*
G01Y640217D02*
Y638642D01*
G01X876456D02*
Y640217D01*
G01Y633642D02*
Y635217D01*
G01Y628642D02*
Y630217D01*
G01Y623642D02*
Y625217D01*
G01X884937Y643071D02*
X884921Y643150D01*
G01X884955Y642986D02*
X884937Y643071D01*
G01X884955Y641477D02*
X884921Y641640D01*
G01X885625Y643445D02*
X885658Y643314D01*
G01X885625Y641903D02*
X885591Y642034D01*
G01X885658Y641575D02*
X885625Y641706D01*
G01X885117Y643071D02*
X885089Y643182D01*
G01X885122Y643051D02*
X885117Y643071D01*
G01X885122Y641640D02*
X885156Y641509D01*
G01X885692Y643642D02*
X885725Y643576D01*
G01X885558D02*
X885625Y643445D01*
G01X885759Y642854D02*
X885725Y642920D01*
G01Y642198D02*
X885792Y642067D01*
G01X885189Y642920D02*
X885122Y643051D01*
G01X885725Y641443D02*
X885658Y641575D01*
G01X885055Y642821D02*
X884955Y642986D01*
G01X885055Y641312D02*
X884955Y641477D01*
G01X885591Y642034D02*
X885524Y642132D01*
G01X885591Y643773D02*
X885692Y643642D01*
G01X885859Y642756D02*
X885759Y642854D01*
G01X885591Y642329D02*
X885725Y642198D01*
G01X885156Y642723D02*
X885055Y642821D01*
G01X885859Y641312D02*
X885725Y641443D01*
G01X885156Y641509D02*
X885256Y641411D01*
G01X885424Y643675D02*
X885558Y643576D01*
G01X885323Y642821D02*
X885189Y642920D01*
G01X885524Y642132D02*
X885424Y642198D01*
G01X885223Y641214D02*
X885055Y641312D01*
G01X885457Y642395D02*
X885591Y642329D01*
G01X885424Y643839D02*
X885591Y643773D01*
G01X885323Y642658D02*
X885156Y642723D01*
G01X881890Y636496D02*
X885039Y635315D01*
G01X881890Y631496D02*
X885039Y630315D01*
G01X881890Y626496D02*
X885039Y625315D01*
G01X885256Y641411D02*
X885356Y641378D01*
G01Y641181D02*
X885223Y641214D01*
G01X885323Y643839D02*
X885424D01*
G01X885323Y643675D02*
X885424D01*
G01X884449Y643071D02*
X896456D01*
G01X885424Y642821D02*
X885323D01*
G01X885424Y642658D02*
X885323D01*
G01X885290Y642395D02*
X885457D01*
G01X885424Y642198D02*
X885323D01*
G01X884449Y641890D02*
X896456D01*
G01X885630Y640906D02*
X888976D01*
G01X889764Y640315D02*
X885630D01*
G01X876456Y640217D02*
X893701D01*
G01Y638642D02*
X876456D01*
G01X885039Y638543D02*
X889764D01*
G01Y635315D02*
X885039D01*
G01X876456Y635217D02*
X893701D01*
G01Y633642D02*
X876456D01*
G01X885039Y633543D02*
X889764D01*
G01Y630315D02*
X885039D01*
G01X876456Y630217D02*
X893701D01*
G01Y628642D02*
X876456D01*
G01X885039Y628543D02*
X889764D01*
G01Y625315D02*
X885039D01*
G01X876456Y625217D02*
X893701D01*
G01Y623642D02*
X876456D01*
G01X885039Y623543D02*
X889764D01*
G01X878649Y664685D02*
X878515Y664587D01*
G01X879017Y664980D02*
X879252Y665177D01*
G01X878984D02*
X878749Y664980D01*
G01X878615Y664423D02*
X878682Y664488D01*
G01X878515Y664587D02*
X878414Y664455D01*
G01X878682Y664488D02*
X878783Y664521D01*
G01X878749Y664718D02*
X878649Y664685D01*
G01X878582Y664324D02*
X878615Y664423D01*
G01X878414Y664455D02*
X878380Y664291D01*
G01X885630Y662953D02*
Y663543D01*
G01X884449Y660788D02*
Y661969D01*
G01Y657638D02*
Y658819D01*
G01Y651339D02*
Y652520D01*
G01Y654488D02*
Y655669D01*
G01Y648189D02*
Y649370D01*
G01Y645040D02*
Y646221D01*
G01X884134Y663642D02*
Y665217D01*
G01X882559Y663642D02*
Y665217D01*
G01X881771D02*
Y663642D01*
G01X881378Y665217D02*
Y663642D01*
G01X879252Y665217D02*
Y665374D01*
G01Y663504D02*
Y663642D01*
G01Y665177D02*
Y665217D01*
G01Y663642D02*
Y664291D01*
G01X879084Y664324D02*
Y663701D01*
G01X878582D02*
Y664324D01*
G01X878380Y664291D02*
Y663701D01*
G01X877677Y665374D02*
Y665217D01*
G01Y663642D02*
Y663504D01*
G01Y665217D02*
Y665177D01*
G01Y663701D02*
Y663642D01*
G01X875000D02*
Y665217D01*
G01X879252Y664291D02*
X879218Y664455D01*
G01X879051Y664423D02*
X879084Y664324D01*
G01X879218Y664455D02*
X879118Y664587D01*
G01X878984Y664488D02*
X879051Y664423D01*
G01X879118Y664587D02*
X878984Y664685D01*
G01X881890Y666496D02*
X885039Y665315D01*
G01X878984Y664685D02*
X878883Y664718D01*
G01Y664521D02*
X878984Y664488D01*
G01X879252Y665374D02*
X877677D01*
G01X889764Y665315D02*
X885039D01*
G01X875000Y665217D02*
X893701D01*
G01X877677Y665177D02*
X878984D01*
G01X878749Y664980D02*
X879017D01*
G01X878883Y664718D02*
X878749D01*
G01X878783Y664521D02*
X878883D01*
G01X879084Y663701D02*
X878582D01*
G01X878380D02*
X877677D01*
G01X875000Y663642D02*
X893701D01*
G01X885630Y663543D02*
X889764D01*
G01X877677Y663504D02*
X879252D01*
G01X888976Y662953D02*
X885630D01*
G01X884449Y661969D02*
X896456D01*
G01X884449Y660788D02*
X896456D01*
G01X884449Y658819D02*
X896456D01*
G01X884449Y657638D02*
X896456D01*
G01X884449Y655669D02*
X896456D01*
G01X884449Y654488D02*
X896456D01*
G01X884449Y652520D02*
X896456D01*
G01X884449Y651339D02*
X896456D01*
G01X884449Y649370D02*
X896456D01*
G01X884449Y648189D02*
X896456D01*
G01X884449Y646221D02*
X896456D01*
G01X884449Y645040D02*
X896456D01*
G01X885039Y668543D02*
X881890Y667362D01*
G01X885039Y673543D02*
X881890Y672362D01*
G01X885039Y683543D02*
X881890Y682362D01*
G01X884134Y683642D02*
Y685217D01*
G01Y678642D02*
Y680217D01*
G01Y673642D02*
Y675217D01*
G01Y668642D02*
Y670217D01*
G01X882559Y683642D02*
Y685217D01*
G01Y678642D02*
Y680217D01*
G01Y673642D02*
Y675217D01*
G01Y668642D02*
Y670217D01*
G01X881890Y686496D02*
Y687362D01*
G01Y681496D02*
Y682362D01*
G01Y676496D02*
Y677362D01*
G01Y671496D02*
Y672362D01*
G01Y666496D02*
Y667362D01*
G01X881771Y670217D02*
Y668642D01*
G01Y675217D02*
Y673642D01*
G01Y680217D02*
Y678642D01*
G01Y685217D02*
Y683642D01*
G01X881378Y670217D02*
Y668642D01*
G01Y675217D02*
Y673642D01*
G01Y680217D02*
Y678642D01*
G01Y685217D02*
Y683642D01*
G01X876456D02*
Y685217D01*
G01Y673642D02*
Y675217D01*
G01Y668642D02*
Y670217D01*
G01X875000Y678642D02*
Y680217D01*
G01X881890Y686496D02*
X885039Y685315D01*
G01X881890Y676496D02*
X885039Y675315D01*
G01X881890Y671496D02*
X885039Y670315D01*
G01X881890Y681496D02*
X887008Y680315D01*
G01X889764Y685315D02*
X885039D01*
G01X876456Y685217D02*
X893701D01*
G01Y683642D02*
X876456D01*
G01X885039Y683543D02*
X889764D01*
G01X875000Y680217D02*
X894882D01*
G01X875000Y678642D02*
X894882D01*
G01X889764Y675315D02*
X885039D01*
G01X876456Y675217D02*
X893701D01*
G01Y673642D02*
X876456D01*
G01X885039Y673543D02*
X889764D01*
G01Y670315D02*
X885039D01*
G01X876456Y670217D02*
X893701D01*
G01Y668642D02*
X876456D01*
G01X885039Y668543D02*
X889764D01*
G01X887008Y678543D02*
X881890Y677362D01*
G01X885039Y688543D02*
X881890Y687362D01*
G01X885039Y693543D02*
X881890Y692362D01*
G01X885039Y698543D02*
X881890Y697362D01*
G01X885039Y703543D02*
X881890Y702362D01*
G01X885039Y708543D02*
X881890Y707362D01*
G01X884134Y703642D02*
Y705217D01*
G01Y698642D02*
Y700217D01*
G01Y693642D02*
Y695217D01*
G01Y688642D02*
Y690217D01*
G01X882559Y703642D02*
Y705217D01*
G01Y698642D02*
Y700217D01*
G01Y693642D02*
Y695217D01*
G01Y688642D02*
Y690217D01*
G01X881890Y706496D02*
Y707362D01*
G01Y701496D02*
Y702362D01*
G01Y696496D02*
Y697362D01*
G01Y691496D02*
Y692362D01*
G01X881771Y690217D02*
Y688642D01*
G01Y695217D02*
Y693642D01*
G01Y700217D02*
Y698642D01*
G01Y705217D02*
Y703642D01*
G01X881378Y690217D02*
Y688642D01*
G01Y695217D02*
Y693642D01*
G01Y700217D02*
Y698642D01*
G01Y705217D02*
Y703642D01*
G01X876456D02*
Y705217D01*
G01Y698642D02*
Y700217D01*
G01Y693642D02*
Y695217D01*
G01Y688642D02*
Y690217D01*
G01X881890Y706496D02*
X885039Y705315D01*
G01X881890Y701496D02*
X885039Y700315D01*
G01X881890Y696496D02*
X885039Y695315D01*
G01X881890Y691496D02*
X885039Y690315D01*
G01X889764Y705315D02*
X885039D01*
G01X876456Y705217D02*
X893701D01*
G01Y703642D02*
X876456D01*
G01X885039Y703543D02*
X889764D01*
G01Y700315D02*
X885039D01*
G01X876456Y700217D02*
X893701D01*
G01Y698642D02*
X876456D01*
G01X885039Y698543D02*
X889764D01*
G01Y695315D02*
X885039D01*
G01X876456Y695217D02*
X893701D01*
G01Y693642D02*
X876456D01*
G01X885039Y693543D02*
X889764D01*
G01Y690315D02*
X885039D01*
G01X876456Y690217D02*
X893701D01*
G01Y688642D02*
X876456D01*
G01X885039Y688543D02*
X889764D01*
G01X885039Y713543D02*
X881890Y712362D01*
G01X885039Y723543D02*
X881890Y722362D01*
G01X885039Y728543D02*
X881890Y727362D01*
G01X884134Y728642D02*
Y730217D01*
G01Y723642D02*
Y725217D01*
G01Y718642D02*
Y720217D01*
G01Y713642D02*
Y715217D01*
G01Y708642D02*
Y710217D01*
G01X882559Y728642D02*
Y730217D01*
G01Y723642D02*
Y725217D01*
G01Y718642D02*
Y720217D01*
G01Y713642D02*
Y715217D01*
G01Y708642D02*
Y710217D01*
G01X881890Y726496D02*
Y727362D01*
G01Y721496D02*
Y722362D01*
G01Y716496D02*
Y717362D01*
G01Y711496D02*
Y712362D01*
G01X881771Y710217D02*
Y708642D01*
G01Y715217D02*
Y713642D01*
G01Y720217D02*
Y718642D01*
G01Y725217D02*
Y723642D01*
G01Y730217D02*
Y728642D01*
G01X881378Y710217D02*
Y708642D01*
G01Y715217D02*
Y713642D01*
G01Y720217D02*
Y718642D01*
G01Y725217D02*
Y723642D01*
G01Y730217D02*
Y728642D01*
G01X876456D02*
Y730217D01*
G01Y723642D02*
Y725217D01*
G01Y713642D02*
Y715217D01*
G01Y708642D02*
Y710217D01*
G01X875000Y718642D02*
Y720217D01*
G01X881890Y726496D02*
X885039Y725315D01*
G01X881890Y716496D02*
X885039Y715315D01*
G01X881890Y711496D02*
X885039Y710315D01*
G01X881890Y721496D02*
X887008Y720315D01*
G01X893701Y728642D02*
X876456D01*
G01X885039Y728543D02*
X889764D01*
G01Y725315D02*
X885039D01*
G01X876456Y725217D02*
X893701D01*
G01Y723642D02*
X876456D01*
G01X885039Y723543D02*
X889764D01*
G01X875000Y720217D02*
X894882D01*
G01X875000Y718642D02*
X894882D01*
G01X889764Y715315D02*
X885039D01*
G01X876456Y715217D02*
X893701D01*
G01Y713642D02*
X876456D01*
G01X885039Y713543D02*
X889764D01*
G01Y710315D02*
X885039D01*
G01X876456Y710217D02*
X893701D01*
G01Y708642D02*
X876456D01*
G01X885039Y708543D02*
X889764D01*
G01X887008Y718543D02*
X881890Y717362D01*
G01X884285Y748549D02*
X884400Y748307D01*
G01X884167Y748812D02*
X884285Y748549D01*
G01X884047Y749095D02*
X884167Y748812D01*
G01X884046Y744369D02*
X884047Y744370D01*
G01X884045Y744365D02*
X884046Y744369D01*
G01X884020Y744306D02*
X884045Y744365D01*
G01X884280Y744905D02*
X884400Y745158D01*
G01X884163Y744643D02*
X884280Y744905D01*
G01X884047Y744370D02*
X884163Y744643D01*
G01X884400Y748307D02*
G03Y745158I2017J-1574D01*
G01X884047Y749095D02*
G03Y744370I2370J-2363D01*
G01X889921Y746732D02*
G03I-3504J0D01*
G01X883740Y749882D02*
G03Y743583I2677J-3150D01*
G01X883982Y744213D02*
X884020Y744306D01*
G01X883899Y744004D02*
X883982Y744213D01*
G01X883865Y743918D02*
X883899Y744004D01*
G01X883830Y743827D02*
X883865Y743918D01*
G01X883794Y743731D02*
X883830Y743827D01*
G01X883740Y743583D02*
X883794Y743731D01*
G01X885039Y733543D02*
X881890Y732362D01*
G01X884134Y733642D02*
Y735217D01*
G01X882559Y733642D02*
Y735217D01*
G01X881890Y736496D02*
Y738248D01*
G01Y731496D02*
Y732362D01*
G01X881771Y735217D02*
Y733642D01*
G01X881378Y735217D02*
Y733642D01*
G01X876456D02*
Y735217D01*
G01X874016Y738248D02*
Y751516D01*
G01X883794Y749734D02*
X883740Y749882D01*
G01X883830Y749638D02*
X883794Y749734D01*
G01X883865Y749547D02*
X883830Y749638D01*
G01X883899Y749460D02*
X883865Y749547D01*
G01X883970Y749281D02*
X883899Y749460D01*
G01X884003Y749200D02*
X883970Y749281D01*
G01X884047Y749095D02*
X884003Y749200D01*
G01X881890Y736496D02*
X885039Y735315D01*
G01X881890Y731496D02*
X885039Y730315D01*
G01X883740Y749882D02*
X889095D01*
G01X888788Y749095D02*
X884047D01*
G01X884400Y748307D02*
X888434D01*
G01X894488Y746122D02*
X874016D01*
G01X884400Y745158D02*
X888434D01*
G01X884047Y744370D02*
X888788D01*
G01X889095Y743583D02*
X883740D01*
G01X924016Y743169D02*
X874016D01*
G01X893701Y740020D02*
X874016D01*
G01Y738248D02*
X893701D01*
G01X889764Y735315D02*
X885039D01*
G01X876456Y735217D02*
X893701D01*
G01Y733642D02*
X876456D01*
G01X885039Y733543D02*
X889764D01*
G01Y730315D02*
X885039D01*
G01X876456Y730217D02*
X893701D01*
G01X881890Y755453D02*
Y768406D01*
G01D02*
X909449D01*
G01X881890Y755453D02*
X870079D01*
G01X927953Y751516D02*
X874016D01*
G01X881890Y980965D02*
Y993917D01*
G01X909449Y980965D02*
X881890D01*
G01X888976Y1002638D02*
G03I-2559J0D01*
G01X889764D02*
G03I-3347J0D01*
G01X889921D02*
G03I-3504J0D01*
G01X886342Y1006771D02*
G03X886417Y998504I75J-4133D01*
G01X874016Y997854D02*
Y1011122D01*
G01X870079Y1160965D02*
Y993917D01*
G01X874016Y1003248D02*
X894488D01*
G01X927953Y997854D02*
X874016D01*
G01X870079Y993917D02*
X881890D01*
G01X879179Y1014829D02*
X879212Y1014666D01*
G01X878509Y1014862D02*
X878542Y1014698D01*
G01X877671Y1014272D02*
X877638Y1014436D01*
G01X878341Y1014698D02*
X878308Y1014829D01*
G01X878375Y1014370D02*
X878341Y1014501D01*
G01X877839Y1014436D02*
X877872Y1014304D01*
G01X879011Y1014698D02*
X878978Y1014797D01*
G01X878542Y1014501D02*
X878576Y1014403D01*
G01X878442Y1014993D02*
X878509Y1014862D01*
G01X878442Y1014239D02*
X878375Y1014370D01*
G01X878978Y1014403D02*
X879011Y1014501D01*
G01X879212D02*
X879179Y1014370D01*
G01X877872Y1014829D02*
X877839Y1014698D01*
G01X877638D02*
X877671Y1014862D01*
G01X884134Y1024154D02*
Y1025728D01*
G01Y1019154D02*
Y1020728D01*
G01Y1014154D02*
Y1015728D01*
G01X882559Y1024154D02*
Y1025728D01*
G01Y1019154D02*
Y1020728D01*
G01Y1014154D02*
Y1015728D01*
G01X881890Y1022008D02*
Y1022874D01*
G01Y1017008D02*
Y1017874D01*
G01Y1011122D02*
Y1012874D01*
G01X881771Y1015728D02*
Y1014154D01*
G01Y1020728D02*
Y1019154D01*
G01Y1025728D02*
Y1024154D01*
G01X881378Y1015728D02*
Y1014154D01*
G01Y1020728D02*
Y1019154D01*
G01Y1025728D02*
Y1024154D01*
G01X879212Y1015728D02*
Y1015847D01*
G01Y1015650D02*
Y1015728D01*
G01Y1014666D02*
Y1014501D01*
G01X879011D02*
Y1014698D01*
G01X878844Y1014895D02*
Y1015092D01*
G01X878542Y1014698D02*
Y1014501D01*
G01X878341D02*
Y1014698D01*
G01X878073Y1014154D02*
Y1013977D01*
G01Y1014173D02*
Y1014154D01*
G01X877839Y1014698D02*
Y1014436D01*
G01X877638D02*
Y1014698D01*
G01Y1015847D02*
Y1015728D01*
G01D02*
Y1015650D01*
G01X876456Y1024154D02*
Y1025728D01*
G01Y1019154D02*
Y1020728D01*
G01Y1014154D02*
Y1015728D01*
G01X877772Y1014108D02*
X877743Y1014154D01*
G01D02*
X877671Y1014272D01*
G01X878308Y1014829D02*
X878241Y1014928D01*
G01X878576Y1014403D02*
X878643Y1014304D01*
G01X879079Y1014961D02*
X879179Y1014829D01*
G01X878978Y1014797D02*
X878911Y1014862D01*
G01X878308Y1015125D02*
X878442Y1014993D01*
G01X878576Y1014108D02*
X878529Y1014154D01*
G01D02*
X878442Y1014239D01*
G01X877872Y1014304D02*
X877973Y1014206D01*
G01X878911Y1014304D02*
X878978Y1014403D01*
G01X877939Y1014928D02*
X877872Y1014829D01*
G01X879179Y1014370D02*
X879112Y1014239D01*
G01X877671Y1014862D02*
X877738Y1014993D01*
G01X878944Y1015059D02*
X879079Y1014961D01*
G01X878241Y1014928D02*
X878140Y1014993D01*
G01X877939Y1014009D02*
X877772Y1014108D01*
G01X878911Y1014862D02*
X878844Y1014895D01*
G01X878174Y1015190D02*
X878308Y1015125D01*
G01X878040Y1014993D02*
X877939Y1014928D01*
G01X878978Y1015453D02*
X879212Y1015650D01*
G01X878944D02*
X878710Y1015453D01*
G01X879025Y1014154D02*
X878978Y1014108D01*
G01X879112Y1014239D02*
X879025Y1014154D01*
G01X877738Y1014993D02*
X877872Y1015125D01*
G01X881890Y1022008D02*
X885039Y1020827D01*
G01X881890Y1017008D02*
X885039Y1015827D01*
G01X878844Y1015092D02*
X878944Y1015059D01*
G01X878643Y1014304D02*
X878743Y1014272D01*
G01X877973Y1014206D02*
X878073Y1014173D01*
G01X878710Y1014075D02*
X878576Y1014108D01*
G01X878073Y1013977D02*
X877939Y1014009D01*
G01X878810Y1014272D02*
X878911Y1014304D01*
G01X885039Y1014055D02*
X881890Y1012874D01*
G01X885039Y1019055D02*
X881890Y1017874D01*
G01X885039Y1024055D02*
X881890Y1022874D01*
G01X877872Y1015125D02*
X878006Y1015190D01*
G01X893701Y1024154D02*
X876456D01*
G01X885039Y1024055D02*
X889764D01*
G01Y1020827D02*
X885039D01*
G01X876456Y1020728D02*
X893701D01*
G01Y1019154D02*
X876456D01*
G01X885039Y1019055D02*
X889764D01*
G01X879212Y1015847D02*
X877638D01*
G01X889764Y1015827D02*
X885039D01*
G01X876456Y1015728D02*
X893701D01*
G01X877638Y1015650D02*
X878944D01*
G01X878710Y1015453D02*
X878978D01*
G01X878006Y1015190D02*
X878174D01*
G01X878140Y1014993D02*
X878040D01*
G01X878743Y1014272D02*
X878810D01*
G01X893701Y1014154D02*
X876456D01*
G01X878844Y1014075D02*
X878710D01*
G01X885039Y1014055D02*
X889764D01*
G01X893701Y1011122D02*
X874016D01*
G01Y1009351D02*
X893701D01*
G01X874016Y1006201D02*
X924016D01*
G01X878978Y1014108D02*
X878844Y1014075D01*
G01X885630Y1045827D02*
Y1046417D01*
G01X884134Y1044154D02*
Y1045728D01*
G01Y1039154D02*
Y1040728D01*
G01Y1034154D02*
Y1035728D01*
G01Y1029154D02*
Y1030728D01*
G01X882559Y1044154D02*
Y1045728D01*
G01Y1039154D02*
Y1040728D01*
G01Y1034154D02*
Y1035728D01*
G01Y1029154D02*
Y1030728D01*
G01X881890Y1042008D02*
Y1042874D01*
G01Y1037008D02*
Y1037874D01*
G01Y1032008D02*
Y1032874D01*
G01Y1027008D02*
Y1027874D01*
G01X881771Y1030728D02*
Y1029154D01*
G01Y1035728D02*
Y1034154D01*
G01Y1040728D02*
Y1039154D01*
G01Y1045728D02*
Y1044154D01*
G01X881378Y1030728D02*
Y1029154D01*
G01Y1035728D02*
Y1034154D01*
G01Y1040728D02*
Y1039154D01*
G01Y1045728D02*
Y1044154D01*
G01X876456D02*
Y1045728D01*
G01Y1039154D02*
Y1040728D01*
G01Y1034154D02*
Y1035728D01*
G01Y1029154D02*
Y1030728D01*
G01X881890Y1042008D02*
X885039Y1040827D01*
G01X881890Y1037008D02*
X885039Y1035827D01*
G01X881890Y1032008D02*
X885039Y1030827D01*
G01X881890Y1027008D02*
X885039Y1025827D01*
G01Y1029055D02*
X881890Y1027874D01*
G01X885039Y1034055D02*
X881890Y1032874D01*
G01X885039Y1039055D02*
X881890Y1037874D01*
G01X889764Y1045827D02*
X885630D01*
G01X876456Y1045728D02*
X893701D01*
G01Y1044154D02*
X876456D01*
G01X885039Y1044055D02*
X889764D01*
G01Y1040827D02*
X885039D01*
G01X876456Y1040728D02*
X893701D01*
G01Y1039154D02*
X876456D01*
G01X885039Y1039055D02*
X889764D01*
G01Y1035827D02*
X885039D01*
G01X876456Y1035728D02*
X893701D01*
G01Y1034154D02*
X876456D01*
G01X885039Y1034055D02*
X889764D01*
G01Y1030827D02*
X885039D01*
G01X876456Y1030728D02*
X893701D01*
G01Y1029154D02*
X876456D01*
G01X885039Y1029055D02*
X889764D01*
G01Y1025827D02*
X885039D01*
G01X876456Y1025728D02*
X893701D01*
G01X885039Y1044055D02*
X881890Y1042874D01*
G01X884937Y1048583D02*
X884921Y1048662D01*
G01X884955Y1048497D02*
X884937Y1048583D01*
G01X884955Y1046988D02*
X884921Y1047152D01*
G01X885625Y1048957D02*
X885658Y1048825D01*
G01X885625Y1047415D02*
X885591Y1047546D01*
G01X885658Y1047087D02*
X885625Y1047218D01*
G01X885117Y1048583D02*
X885089Y1048694D01*
G01X885122Y1048563D02*
X885117Y1048583D01*
G01X885122Y1047152D02*
X885156Y1047021D01*
G01X885692Y1049154D02*
X885725Y1049088D01*
G01X885558D02*
X885625Y1048957D01*
G01X885759Y1048366D02*
X885725Y1048432D01*
G01Y1047710D02*
X885792Y1047579D01*
G01X885189Y1048432D02*
X885122Y1048563D01*
G01X885725Y1046955D02*
X885658Y1047087D01*
G01X885055Y1048333D02*
X884955Y1048497D01*
G01X885055Y1046824D02*
X884955Y1046988D01*
G01X885591Y1047546D02*
X885524Y1047644D01*
G01X885591Y1049285D02*
X885692Y1049154D01*
G01X885658Y1048694D02*
X885630Y1048583D01*
G01D02*
X885625Y1048563D01*
G01X885156Y1047546D02*
X885122Y1047415D01*
G01X885089Y1048825D02*
X885122Y1048957D01*
G01X884921Y1047415D02*
X884955Y1047579D01*
G01X884921Y1048858D02*
X884955Y1049022D01*
G01X885658Y1048825D02*
Y1048694D01*
G01X885625Y1047218D02*
Y1047402D01*
G01D02*
Y1047415D01*
G01X885356Y1046890D02*
Y1046693D01*
G01X885122Y1047402D02*
Y1047152D01*
G01Y1047415D02*
Y1047402D01*
G01X885089Y1048694D02*
Y1048825D01*
G01X884921Y1048662D02*
Y1048858D01*
G01Y1047152D02*
Y1047402D01*
G01D02*
Y1047415D01*
G01X884449Y1063150D02*
Y1064331D01*
G01Y1066299D02*
Y1067480D01*
G01Y1060000D02*
Y1061181D01*
G01Y1053701D02*
Y1054882D01*
G01Y1056851D02*
Y1058032D01*
G01Y1050551D02*
Y1051732D01*
G01Y1047402D02*
Y1048583D01*
G01X885859Y1048268D02*
X885759Y1048366D01*
G01X885591Y1047841D02*
X885725Y1047710D01*
G01X885156Y1048235D02*
X885055Y1048333D01*
G01X885859Y1046824D02*
X885725Y1046955D01*
G01X885156Y1047021D02*
X885256Y1046923D01*
G01X885424Y1049186D02*
X885558Y1049088D01*
G01X885323Y1048333D02*
X885189Y1048432D01*
G01X885524Y1047644D02*
X885424Y1047710D01*
G01X885692Y1048366D02*
X885591Y1048235D01*
G01X885223Y1047644D02*
X885156Y1047546D01*
G01X884955Y1049022D02*
X885055Y1049186D01*
G01X885725Y1048432D02*
X885692Y1048366D01*
G01X885625Y1048563D02*
X885558Y1048432D01*
G01X884955Y1047579D02*
X885021Y1047710D01*
G01X885725Y1049088D02*
X885759Y1049154D01*
G01X885122Y1048957D02*
X885189Y1049088D01*
G01X885223Y1046726D02*
X885055Y1046824D01*
G01X885457Y1047907D02*
X885591Y1047841D01*
G01X885424Y1049351D02*
X885591Y1049285D01*
G01X885323Y1048169D02*
X885156Y1048235D01*
G01X885558Y1048432D02*
X885424Y1048333D01*
G01X885189Y1049088D02*
X885323Y1049186D01*
G01X885021Y1047710D02*
X885156Y1047841D01*
G01X885759Y1049154D02*
X885859Y1049252D01*
G01X885055Y1049186D02*
X885156Y1049285D01*
G01X885256Y1046923D02*
X885356Y1046890D01*
G01Y1046693D02*
X885223Y1046726D01*
G01X885156Y1047841D02*
X885290Y1047907D01*
G01X885323Y1047710D02*
X885223Y1047644D01*
G01X884449Y1066299D02*
X896456D01*
G01X884449Y1064331D02*
X896456D01*
G01X884449Y1063150D02*
X896456D01*
G01X884449Y1061181D02*
X896456D01*
G01X884449Y1060000D02*
X896456D01*
G01X884449Y1058032D02*
X896456D01*
G01X884449Y1056851D02*
X896456D01*
G01X884449Y1054882D02*
X896456D01*
G01X884449Y1053701D02*
X896456D01*
G01X884449Y1051732D02*
X896456D01*
G01X884449Y1050551D02*
X896456D01*
G01X885323Y1049351D02*
X885424D01*
G01X885323Y1049186D02*
X885424D01*
G01X884449Y1048583D02*
X896456D01*
G01X885424Y1048333D02*
X885323D01*
G01X885424Y1048169D02*
X885323D01*
G01X885290Y1047907D02*
X885457D01*
G01X885424Y1047710D02*
X885323D01*
G01X884449Y1047402D02*
X896456D01*
G01X885630Y1046417D02*
X888976D01*
G01X885591Y1048235D02*
X885424Y1048169D01*
G01X885156Y1049285D02*
X885323Y1049351D01*
G01X879252Y1069803D02*
X879218Y1069967D01*
G01X879051Y1069934D02*
X879084Y1069836D01*
G01X879218Y1069967D02*
X879118Y1070099D01*
G01X878582Y1069836D02*
X878615Y1069934D01*
G01X878414Y1069967D02*
X878380Y1069803D01*
G01X885630Y1068465D02*
Y1069055D01*
G01X884134Y1084154D02*
Y1085728D01*
G01Y1079154D02*
Y1080728D01*
G01Y1074154D02*
Y1075728D01*
G01Y1069154D02*
Y1070728D01*
G01X882559Y1084154D02*
Y1085728D01*
G01Y1079154D02*
Y1080728D01*
G01Y1074154D02*
Y1075728D01*
G01Y1069154D02*
Y1070728D01*
G01X881890Y1087008D02*
Y1087874D01*
G01Y1082008D02*
Y1082874D01*
G01Y1077008D02*
Y1077874D01*
G01Y1072008D02*
Y1072874D01*
G01X881771Y1070728D02*
Y1069154D01*
G01Y1075728D02*
Y1074154D01*
G01Y1080728D02*
Y1079154D01*
G01Y1085728D02*
Y1084154D01*
G01X881378Y1070728D02*
Y1069154D01*
G01Y1075728D02*
Y1074154D01*
G01Y1080728D02*
Y1079154D01*
G01Y1085728D02*
Y1084154D01*
G01X879252Y1070728D02*
Y1070886D01*
G01Y1069016D02*
Y1069154D01*
G01Y1070689D02*
Y1070728D01*
G01Y1069154D02*
Y1069803D01*
G01X879084Y1069836D02*
Y1069213D01*
G01X878582D02*
Y1069836D01*
G01X878380Y1069803D02*
Y1069213D01*
G01X877677Y1070886D02*
Y1070728D01*
G01Y1069154D02*
Y1069016D01*
G01Y1070728D02*
Y1070689D01*
G01Y1069213D02*
Y1069154D01*
G01X876456Y1079154D02*
Y1080728D01*
G01Y1074154D02*
Y1075728D01*
G01X875000Y1084154D02*
Y1085728D01*
G01Y1069154D02*
Y1070728D01*
G01X878984Y1070000D02*
X879051Y1069934D01*
G01X879118Y1070099D02*
X878984Y1070197D01*
G01X878515Y1070099D02*
X878414Y1069967D01*
G01X881890Y1082008D02*
X885039Y1080827D01*
G01X881890Y1077008D02*
X885039Y1075827D01*
G01X881890Y1072008D02*
X885039Y1070827D01*
G01X878984Y1070197D02*
X878883Y1070230D01*
G01Y1070033D02*
X878984Y1070000D01*
G01X881890Y1087008D02*
X887008Y1085827D01*
G01X879017Y1070492D02*
X879252Y1070689D01*
G01X878984D02*
X878749Y1070492D01*
G01X878615Y1069934D02*
X878682Y1070000D01*
G01X875000Y1085728D02*
X894882D01*
G01X875000Y1084154D02*
X894882D01*
G01X878649Y1070197D02*
X878515Y1070099D01*
G01X889764Y1080827D02*
X885039D01*
G01X876456Y1080728D02*
X893701D01*
G01Y1079154D02*
X876456D01*
G01X885039Y1079055D02*
X889764D01*
G01Y1075827D02*
X885039D01*
G01X876456Y1075728D02*
X893701D01*
G01Y1074154D02*
X876456D01*
G01X885039Y1074055D02*
X889764D01*
G01X879252Y1070886D02*
X877677D01*
G01X889764Y1070827D02*
X885039D01*
G01X875000Y1070728D02*
X893701D01*
G01X877677Y1070689D02*
X878984D01*
G01X878749Y1070492D02*
X879017D01*
G01X878883Y1070230D02*
X878749D01*
G01X878783Y1070033D02*
X878883D01*
G01X879084Y1069213D02*
X878582D01*
G01X878380D02*
X877677D01*
G01X875000Y1069154D02*
X893701D01*
G01X885630Y1069055D02*
X889764D01*
G01X877677Y1069016D02*
X879252D01*
G01X888976Y1068465D02*
X885630D01*
G01X884449Y1067480D02*
X896456D01*
G01X878682Y1070000D02*
X878783Y1070033D01*
G01X878749Y1070230D02*
X878649Y1070197D01*
G01X885039Y1074055D02*
X881890Y1072874D01*
G01X885039Y1079055D02*
X881890Y1077874D01*
G01X885039Y1089055D02*
X881890Y1087874D01*
G01X887008Y1084055D02*
X881890Y1082874D01*
G01X884134Y1109154D02*
Y1110728D01*
G01Y1104154D02*
Y1105728D01*
G01Y1099154D02*
Y1100728D01*
G01Y1094154D02*
Y1095728D01*
G01Y1089154D02*
Y1090728D01*
G01X882559Y1109154D02*
Y1110728D01*
G01Y1104154D02*
Y1105728D01*
G01Y1099154D02*
Y1100728D01*
G01Y1094154D02*
Y1095728D01*
G01Y1089154D02*
Y1090728D01*
G01X881890Y1107008D02*
Y1107874D01*
G01Y1102008D02*
Y1102874D01*
G01Y1097008D02*
Y1097874D01*
G01Y1092008D02*
Y1092874D01*
G01X881771Y1090728D02*
Y1089154D01*
G01Y1095728D02*
Y1094154D01*
G01Y1100728D02*
Y1099154D01*
G01Y1105728D02*
Y1104154D01*
G01Y1110728D02*
Y1109154D01*
G01X881378Y1090728D02*
Y1089154D01*
G01Y1095728D02*
Y1094154D01*
G01Y1100728D02*
Y1099154D01*
G01Y1105728D02*
Y1104154D01*
G01Y1110728D02*
Y1109154D01*
G01X876456D02*
Y1110728D01*
G01Y1104154D02*
Y1105728D01*
G01Y1099154D02*
Y1100728D01*
G01Y1094154D02*
Y1095728D01*
G01Y1089154D02*
Y1090728D01*
G01X881890Y1107008D02*
X885039Y1105827D01*
G01X881890Y1102008D02*
X885039Y1100827D01*
G01X881890Y1097008D02*
X885039Y1095827D01*
G01X881890Y1092008D02*
X885039Y1090827D01*
G01X893701Y1109154D02*
X876456D01*
G01X885039Y1109055D02*
X889764D01*
G01Y1105827D02*
X885039D01*
G01X876456Y1105728D02*
X893701D01*
G01Y1104154D02*
X876456D01*
G01X885039Y1104055D02*
X889764D01*
G01Y1100827D02*
X885039D01*
G01X876456Y1100728D02*
X893701D01*
G01Y1099154D02*
X876456D01*
G01X885039Y1099055D02*
X889764D01*
G01Y1095827D02*
X885039D01*
G01X876456Y1095728D02*
X893701D01*
G01Y1094154D02*
X876456D01*
G01X885039Y1094055D02*
X889764D01*
G01Y1090827D02*
X885039D01*
G01X876456Y1090728D02*
X893701D01*
G01Y1089154D02*
X876456D01*
G01X885039Y1089055D02*
X889764D01*
G01X885039Y1094055D02*
X881890Y1092874D01*
G01X885039Y1099055D02*
X881890Y1097874D01*
G01X885039Y1104055D02*
X881890Y1102874D01*
G01X885039Y1109055D02*
X881890Y1107874D01*
G01X884134Y1129154D02*
Y1130728D01*
G01Y1124154D02*
Y1125728D01*
G01Y1119154D02*
Y1120728D01*
G01Y1114154D02*
Y1115728D01*
G01X882559Y1129154D02*
Y1130728D01*
G01Y1124154D02*
Y1125728D01*
G01Y1119154D02*
Y1120728D01*
G01Y1114154D02*
Y1115728D01*
G01X881890Y1127008D02*
Y1127874D01*
G01Y1122008D02*
Y1122874D01*
G01Y1117008D02*
Y1117874D01*
G01Y1112008D02*
Y1112874D01*
G01X881771Y1115728D02*
Y1114154D01*
G01Y1120728D02*
Y1119154D01*
G01Y1125728D02*
Y1124154D01*
G01Y1130728D02*
Y1129154D01*
G01X881378Y1115728D02*
Y1114154D01*
G01Y1120728D02*
Y1119154D01*
G01Y1125728D02*
Y1124154D01*
G01Y1130728D02*
Y1129154D01*
G01X876456D02*
Y1130728D01*
G01Y1119154D02*
Y1120728D01*
G01Y1114154D02*
Y1115728D01*
G01X875000Y1124154D02*
Y1125728D01*
G01X881890Y1122008D02*
X885039Y1120827D01*
G01X881890Y1117008D02*
X885039Y1115827D01*
G01X881890Y1112008D02*
X885039Y1110827D01*
G01X881890Y1127008D02*
X887008Y1125827D01*
G01X876456Y1130728D02*
X893701D01*
G01Y1129154D02*
X876456D01*
G01X885039Y1129055D02*
X889764D01*
G01X875000Y1125728D02*
X894882D01*
G01X875000Y1124154D02*
X894882D01*
G01X889764Y1120827D02*
X885039D01*
G01X876456Y1120728D02*
X893701D01*
G01Y1119154D02*
X876456D01*
G01X885039Y1119055D02*
X889764D01*
G01Y1115827D02*
X885039D01*
G01X876456Y1115728D02*
X893701D01*
G01Y1114154D02*
X876456D01*
G01X885039Y1114055D02*
X889764D01*
G01Y1110827D02*
X885039D01*
G01X876456Y1110728D02*
X893701D01*
G01X887008Y1124055D02*
X881890Y1122874D01*
G01X885039Y1114055D02*
X881890Y1112874D01*
G01X885039Y1119055D02*
X881890Y1117874D01*
G01X885039Y1129055D02*
X881890Y1127874D01*
G01X884046Y1149880D02*
X884047Y1149882D01*
G01X884033Y1149849D02*
X884046Y1149880D01*
G01X884280Y1150417D02*
X884400Y1150669D01*
G01X884163Y1150155D02*
X884280Y1150417D01*
G01X884047Y1149882D02*
X884163Y1150155D01*
G01X884400Y1153819D02*
G03Y1150669I2017J-1575D01*
G01X884047Y1154606D02*
G03Y1149882I2370J-2362D01*
G01X889921Y1152244D02*
G03I-3504J0D01*
G01X883740Y1155394D02*
G03Y1149095I2677J-3150D01*
G01X884134Y1139154D02*
Y1140728D01*
G01Y1134154D02*
Y1135728D01*
G01X882559Y1139154D02*
Y1140728D01*
G01Y1134154D02*
Y1135728D01*
G01X881890Y1142008D02*
Y1143760D01*
G01Y1137008D02*
Y1137874D01*
G01Y1132008D02*
Y1132874D01*
G01X881771Y1135728D02*
Y1134154D01*
G01Y1140728D02*
Y1139154D01*
G01X881378Y1135728D02*
Y1134154D01*
G01Y1140728D02*
Y1139154D01*
G01X876456D02*
Y1140728D01*
G01Y1134154D02*
Y1135728D01*
G01X874016Y1143760D02*
Y1157028D01*
G01X881890Y1142008D02*
X885039Y1140827D01*
G01X881890Y1137008D02*
X885039Y1135827D01*
G01X881890Y1132008D02*
X885039Y1130827D01*
G01X883993Y1149752D02*
X884033Y1149849D01*
G01X883958Y1149663D02*
X883993Y1149752D01*
G01X883899Y1149516D02*
X883958Y1149663D01*
G01X883865Y1149430D02*
X883899Y1149516D01*
G01X883830Y1149338D02*
X883865Y1149430D01*
G01X883794Y1149243D02*
X883830Y1149338D01*
G01X883740Y1149095D02*
X883794Y1149243D01*
G01X894488Y1151634D02*
X874016D01*
G01X884400Y1150669D02*
X888434D01*
G01X884047Y1149882D02*
X888788D01*
G01X889095Y1149095D02*
X883740D01*
G01X924016Y1148681D02*
X874016D01*
G01X893701Y1145532D02*
X874016D01*
G01Y1143760D02*
X893701D01*
G01X889764Y1140827D02*
X885039D01*
G01X876456Y1140728D02*
X893701D01*
G01Y1139154D02*
X876456D01*
G01X885039Y1139055D02*
X889764D01*
G01Y1135827D02*
X885039D01*
G01X876456Y1135728D02*
X893701D01*
G01Y1134154D02*
X876456D01*
G01X885039Y1134055D02*
X889764D01*
G01Y1130827D02*
X885039D01*
G01Y1134055D02*
X881890Y1132874D01*
G01X885039Y1139055D02*
X881890Y1137874D01*
G01X884285Y1154061D02*
X884400Y1153819D01*
G01X884167Y1154323D02*
X884285Y1154061D01*
G01X884047Y1154606D02*
X884167Y1154323D01*
G01X883794Y1155246D02*
X883740Y1155394D01*
G01X883830Y1155150D02*
X883794Y1155246D01*
G01X883865Y1155058D02*
X883830Y1155150D01*
G01X883899Y1154972D02*
X883865Y1155058D01*
G01X883970Y1154793D02*
X883899Y1154972D01*
G01X884003Y1154712D02*
X883970Y1154793D01*
G01X884047Y1154606D02*
X884003Y1154712D01*
G01X881890Y1160965D02*
Y1173917D01*
G01Y1160965D02*
X870079D01*
G01X927953Y1157028D02*
X874016D01*
G01X883740Y1155394D02*
X889095D01*
G01X888788Y1154606D02*
X884047D01*
G01X884400Y1153819D02*
X888434D01*
G01X881890Y1173917D02*
X909449D01*
G01X888976Y1408150D02*
G03I-2559J0D01*
G01X889764D02*
G03I-3347J0D01*
G01X889921D02*
G03I-3504J0D01*
G01X886342Y1412283D02*
G03X886417Y1404016I75J-4133D01*
G01X927953Y1403366D02*
X874016D01*
G01X870079Y1399429D02*
X881890D01*
G01X909449Y1386477D02*
X881890D01*
G01D02*
Y1399429D01*
G01X874016Y1403366D02*
Y1416634D01*
G01X870079Y1566477D02*
Y1399429D01*
G01X878978Y1420308D02*
X878911Y1420374D01*
G01X878308Y1420636D02*
X878442Y1420505D01*
G01X878576Y1419619D02*
X878529Y1419666D01*
G01D02*
X878442Y1419751D01*
G01X877872Y1419816D02*
X877973Y1419718D01*
G01X878944Y1420571D02*
X879079Y1420473D01*
G01X878241Y1420440D02*
X878140Y1420505D01*
G01X877939Y1419521D02*
X877772Y1419619D01*
G01X879011Y1420210D02*
X878978Y1420308D01*
G01X878542Y1420013D02*
X878576Y1419915D01*
G01X878442Y1420505D02*
X878509Y1420374D01*
G01X878442Y1419751D02*
X878375Y1419882D01*
G01X877772Y1419619D02*
X877743Y1419666D01*
G01D02*
X877671Y1419784D01*
G01X878308Y1420341D02*
X878241Y1420440D01*
G01X878576Y1419915D02*
X878643Y1419816D01*
G01X879079Y1420473D02*
X879179Y1420341D01*
G01X878911Y1420374D02*
X878844Y1420407D01*
G01X878174Y1420702D02*
X878308Y1420636D01*
G01X881890Y1427520D02*
X885039Y1426339D01*
G01X881890Y1422520D02*
X885039Y1421339D01*
G01X878844Y1420604D02*
X878944Y1420571D01*
G01X878643Y1419816D02*
X878743Y1419784D01*
G01X877973Y1419718D02*
X878073Y1419685D01*
G01X878710Y1419587D02*
X878576Y1419619D01*
G01X878073Y1419488D02*
X877939Y1419521D01*
G01X879179Y1420341D02*
X879212Y1420177D01*
G01X878509Y1420374D02*
X878542Y1420210D01*
G01X877671Y1419784D02*
X877638Y1419947D01*
G01X878341Y1420210D02*
X878308Y1420341D01*
G01X878375Y1419882D02*
X878341Y1420013D01*
G01X877839Y1419947D02*
X877872Y1419816D01*
G01X889764Y1426339D02*
X885039D01*
G01X876456Y1426240D02*
X893701D01*
G01Y1424666D02*
X876456D01*
G01X885039Y1424567D02*
X889764D01*
G01X879212Y1421358D02*
X877638D01*
G01X889764Y1421339D02*
X885039D01*
G01X876456Y1421240D02*
X893701D01*
G01X877638Y1421162D02*
X878944D01*
G01X878710Y1420965D02*
X878978D01*
G01X878006Y1420702D02*
X878174D01*
G01X878140Y1420505D02*
X878040D01*
G01X878743Y1419784D02*
X878810D01*
G01X893701Y1419666D02*
X876456D01*
G01X878844Y1419587D02*
X878710D01*
G01X885039Y1419567D02*
X889764D01*
G01X893701Y1416634D02*
X874016D01*
G01Y1414862D02*
X893701D01*
G01X874016Y1411713D02*
X924016D01*
G01X874016Y1408760D02*
X894488D01*
G01X878978Y1419619D02*
X878844Y1419587D01*
G01X884134Y1424666D02*
Y1426240D01*
G01Y1419666D02*
Y1421240D01*
G01X882559Y1424666D02*
Y1426240D01*
G01Y1419666D02*
Y1421240D01*
G01X881890Y1422520D02*
Y1423386D01*
G01Y1416634D02*
Y1418386D01*
G01X881771Y1421240D02*
Y1419666D01*
G01Y1426240D02*
Y1424666D01*
G01X881378Y1421240D02*
Y1419666D01*
G01Y1426240D02*
Y1424666D01*
G01X879212Y1421240D02*
Y1421358D01*
G01Y1421162D02*
Y1421240D01*
G01Y1420177D02*
Y1420013D01*
G01X879011D02*
Y1420210D01*
G01X878844Y1420407D02*
Y1420604D01*
G01X878542Y1420210D02*
Y1420013D01*
G01X878341D02*
Y1420210D01*
G01X878073Y1419666D02*
Y1419488D01*
G01Y1419685D02*
Y1419666D01*
G01X877839Y1420210D02*
Y1419947D01*
G01X877638D02*
Y1420210D01*
G01Y1421358D02*
Y1421240D01*
G01D02*
Y1421162D01*
G01X876456Y1424666D02*
Y1426240D01*
G01Y1419666D02*
Y1421240D01*
G01X879212Y1420013D02*
X879179Y1419882D01*
G01X877872Y1420341D02*
X877839Y1420210D01*
G01X877638D02*
X877671Y1420374D01*
G01X878978Y1419915D02*
X879011Y1420013D01*
G01X879179Y1419882D02*
X879112Y1419751D01*
G01X877671Y1420374D02*
X877738Y1420505D01*
G01X878911Y1419816D02*
X878978Y1419915D01*
G01X877939Y1420440D02*
X877872Y1420341D01*
G01X879025Y1419666D02*
X878978Y1419619D01*
G01X879112Y1419751D02*
X879025Y1419666D01*
G01X877738Y1420505D02*
X877872Y1420636D01*
G01X878978Y1420965D02*
X879212Y1421162D01*
G01X878944D02*
X878710Y1420965D01*
G01X878040Y1420505D02*
X877939Y1420440D01*
G01X878810Y1419784D02*
X878911Y1419816D01*
G01X885039Y1419567D02*
X881890Y1418386D01*
G01X885039Y1424567D02*
X881890Y1423386D01*
G01X877872Y1420636D02*
X878006Y1420702D01*
G01X881890Y1447520D02*
X885039Y1446339D01*
G01X881890Y1442520D02*
X885039Y1441339D01*
G01X881890Y1437520D02*
X885039Y1436339D01*
G01X881890Y1432520D02*
X885039Y1431339D01*
G01X889764Y1446339D02*
X885039D01*
G01X876456Y1446240D02*
X893701D01*
G01Y1444666D02*
X876456D01*
G01X885039Y1444567D02*
X889764D01*
G01Y1441339D02*
X885039D01*
G01X876456Y1441240D02*
X893701D01*
G01Y1439666D02*
X876456D01*
G01X885039Y1439567D02*
X889764D01*
G01Y1436339D02*
X885039D01*
G01X876456Y1436240D02*
X893701D01*
G01Y1434666D02*
X876456D01*
G01X885039Y1434567D02*
X889764D01*
G01Y1431339D02*
X885039D01*
G01X876456Y1431240D02*
X893701D01*
G01Y1429666D02*
X876456D01*
G01X885039Y1429567D02*
X889764D01*
G01X884134Y1444666D02*
Y1446240D01*
G01Y1439666D02*
Y1441240D01*
G01Y1434666D02*
Y1436240D01*
G01Y1429666D02*
Y1431240D01*
G01X882559Y1444666D02*
Y1446240D01*
G01Y1439666D02*
Y1441240D01*
G01Y1434666D02*
Y1436240D01*
G01Y1429666D02*
Y1431240D01*
G01X881890Y1447520D02*
Y1448386D01*
G01Y1442520D02*
Y1443386D01*
G01Y1437520D02*
Y1438386D01*
G01Y1432520D02*
Y1433386D01*
G01Y1427520D02*
Y1428386D01*
G01X881771Y1431240D02*
Y1429666D01*
G01Y1436240D02*
Y1434666D01*
G01Y1441240D02*
Y1439666D01*
G01Y1446240D02*
Y1444666D01*
G01X881378Y1431240D02*
Y1429666D01*
G01Y1436240D02*
Y1434666D01*
G01Y1441240D02*
Y1439666D01*
G01Y1446240D02*
Y1444666D01*
G01X876456D02*
Y1446240D01*
G01Y1439666D02*
Y1441240D01*
G01Y1434666D02*
Y1436240D01*
G01Y1429666D02*
Y1431240D01*
G01X885039Y1429567D02*
X881890Y1428386D01*
G01X885039Y1434567D02*
X881890Y1433386D01*
G01X885039Y1439567D02*
X881890Y1438386D01*
G01X885039Y1444567D02*
X881890Y1443386D01*
G01X885055Y1453845D02*
X884955Y1454009D01*
G01X885055Y1452336D02*
X884955Y1452500D01*
G01X885591Y1453058D02*
X885524Y1453156D01*
G01X885591Y1454797D02*
X885692Y1454666D01*
G01X885859Y1453780D02*
X885759Y1453878D01*
G01X885591Y1453353D02*
X885725Y1453222D01*
G01X885156Y1453747D02*
X885055Y1453845D01*
G01X885859Y1452336D02*
X885725Y1452467D01*
G01X885156Y1452533D02*
X885256Y1452434D01*
G01X885424Y1454698D02*
X885558Y1454600D01*
G01X885323Y1453845D02*
X885189Y1453943D01*
G01X885524Y1453156D02*
X885424Y1453222D01*
G01X885223Y1452238D02*
X885055Y1452336D01*
G01X885457Y1453419D02*
X885591Y1453353D01*
G01X885424Y1454862D02*
X885591Y1454797D01*
G01X885323Y1453681D02*
X885156Y1453747D01*
G01X885256Y1452434D02*
X885356Y1452402D01*
G01X885625Y1454469D02*
X885658Y1454337D01*
G01X885625Y1452927D02*
X885591Y1453058D01*
G01X885658Y1452599D02*
X885625Y1452730D01*
G01X885117Y1454095D02*
X885089Y1454206D01*
G01X885122Y1454075D02*
X885117Y1454095D01*
G01X885692Y1454666D02*
X885725Y1454600D01*
G01X885558D02*
X885625Y1454469D01*
G01X885759Y1453878D02*
X885725Y1453943D01*
G01Y1453222D02*
X885792Y1453091D01*
G01X885189Y1453943D02*
X885122Y1454075D01*
G01X885725Y1452467D02*
X885658Y1452599D01*
G01X885356Y1452205D02*
X885223Y1452238D01*
G01X884449Y1468662D02*
X896456D01*
G01X884449Y1466693D02*
X896456D01*
G01X884449Y1465512D02*
X896456D01*
G01X884449Y1463543D02*
X896456D01*
G01X884937Y1454095D02*
X884921Y1454173D01*
G01X884955Y1454009D02*
X884937Y1454095D01*
G01X884955Y1452500D02*
X884921Y1452664D01*
G01X885122D02*
X885156Y1452533D01*
G01X884449Y1462362D02*
X896456D01*
G01X884449Y1460394D02*
X896456D01*
G01X884449Y1459213D02*
X896456D01*
G01X884449Y1457244D02*
X896456D01*
G01X884449Y1456063D02*
X896456D01*
G01X885323Y1454862D02*
X885424D01*
G01X885323Y1454698D02*
X885424D01*
G01X884449Y1454095D02*
X896456D01*
G01X885424Y1453845D02*
X885323D01*
G01X885424Y1453681D02*
X885323D01*
G01X885290Y1453419D02*
X885457D01*
G01X885424Y1453222D02*
X885323D01*
G01X884449Y1452914D02*
X896456D01*
G01X885630Y1451929D02*
X888976D01*
G01X889764Y1451339D02*
X885630D01*
G01X876456Y1451240D02*
X893701D01*
G01Y1449666D02*
X876456D01*
G01X885039Y1449567D02*
X889764D01*
G01X885658Y1454337D02*
Y1454206D01*
G01X885630Y1451339D02*
Y1451929D01*
G01X885625Y1452730D02*
Y1452914D01*
G01D02*
Y1452927D01*
G01X885356Y1452402D02*
Y1452205D01*
G01X885122Y1452914D02*
Y1452664D01*
G01Y1452927D02*
Y1452914D01*
G01X885089Y1454206D02*
Y1454337D01*
G01X884921Y1454173D02*
Y1454370D01*
G01Y1452664D02*
Y1452914D01*
G01D02*
Y1452927D01*
G01X884449Y1465512D02*
Y1466693D01*
G01Y1468662D02*
Y1469843D01*
G01Y1462362D02*
Y1463543D01*
G01Y1456063D02*
Y1457244D01*
G01Y1459213D02*
Y1460394D01*
G01Y1452914D02*
Y1454095D01*
G01X884134Y1449666D02*
Y1451240D01*
G01X882559Y1449666D02*
Y1451240D01*
G01X881771D02*
Y1449666D01*
G01X881378Y1451240D02*
Y1449666D01*
G01X876456D02*
Y1451240D01*
G01X885658Y1454206D02*
X885630Y1454095D01*
G01D02*
X885625Y1454075D01*
G01X885156Y1453058D02*
X885122Y1452927D01*
G01X885089Y1454337D02*
X885122Y1454469D01*
G01X884921Y1452927D02*
X884955Y1453091D01*
G01X884921Y1454370D02*
X884955Y1454534D01*
G01X885725Y1453943D02*
X885692Y1453878D01*
G01X885625Y1454075D02*
X885558Y1453943D01*
G01X884955Y1453091D02*
X885021Y1453222D01*
G01X885725Y1454600D02*
X885759Y1454666D01*
G01X885122Y1454469D02*
X885189Y1454600D01*
G01X885692Y1453878D02*
X885591Y1453747D01*
G01X885223Y1453156D02*
X885156Y1453058D01*
G01X884955Y1454534D02*
X885055Y1454698D01*
G01X885021Y1453222D02*
X885156Y1453353D01*
G01X885759Y1454666D02*
X885859Y1454764D01*
G01X885055Y1454698D02*
X885156Y1454797D01*
G01X885323Y1453222D02*
X885223Y1453156D01*
G01X885558Y1453943D02*
X885424Y1453845D01*
G01X885189Y1454600D02*
X885323Y1454698D01*
G01X885591Y1453747D02*
X885424Y1453681D01*
G01X885156Y1454797D02*
X885323Y1454862D01*
G01X885156Y1453353D02*
X885290Y1453419D01*
G01X885039Y1449567D02*
X881890Y1448386D01*
G01X879218Y1475479D02*
X879118Y1475610D01*
G01X878984Y1475512D02*
X879051Y1475446D01*
G01X879118Y1475610D02*
X878984Y1475709D01*
G01X881890Y1487520D02*
X885039Y1486339D01*
G01X881890Y1482520D02*
X885039Y1481339D01*
G01X881890Y1477520D02*
X885039Y1476339D01*
G01X878984Y1475709D02*
X878883Y1475741D01*
G01Y1475545D02*
X878984Y1475512D01*
G01X879051Y1475446D02*
X879084Y1475348D01*
G01X875000Y1489666D02*
X894882D01*
G01X889764Y1486339D02*
X885039D01*
G01X876456Y1486240D02*
X893701D01*
G01Y1484666D02*
X876456D01*
G01X885039Y1484567D02*
X889764D01*
G01Y1481339D02*
X885039D01*
G01X876456Y1481240D02*
X893701D01*
G01Y1479666D02*
X876456D01*
G01X885039Y1479567D02*
X889764D01*
G01X879252Y1476398D02*
X877677D01*
G01X889764Y1476339D02*
X885039D01*
G01X875000Y1476240D02*
X893701D01*
G01X877677Y1476201D02*
X878984D01*
G01X878749Y1476004D02*
X879017D01*
G01X878883Y1475741D02*
X878749D01*
G01X878783Y1475545D02*
X878883D01*
G01X879084Y1474725D02*
X878582D01*
G01X878380D02*
X877677D01*
G01X875000Y1474666D02*
X893701D01*
G01X885630Y1474567D02*
X889764D01*
G01X877677Y1474528D02*
X879252D01*
G01X888976Y1473977D02*
X885630D01*
G01X884449Y1472992D02*
X896456D01*
G01X884449Y1471811D02*
X896456D01*
G01X884449Y1469843D02*
X896456D01*
G01X879252Y1475315D02*
X879218Y1475479D01*
G01X887008Y1489567D02*
X881890Y1488386D01*
G01X885630Y1473977D02*
Y1474567D01*
G01X884449Y1471811D02*
Y1472992D01*
G01X884134Y1489666D02*
Y1491240D01*
G01Y1484666D02*
Y1486240D01*
G01Y1479666D02*
Y1481240D01*
G01Y1474666D02*
Y1476240D01*
G01X882559Y1489666D02*
Y1491240D01*
G01Y1484666D02*
Y1486240D01*
G01Y1479666D02*
Y1481240D01*
G01Y1474666D02*
Y1476240D01*
G01X881890Y1487520D02*
Y1488386D01*
G01Y1482520D02*
Y1483386D01*
G01Y1477520D02*
Y1478386D01*
G01X881771Y1476240D02*
Y1474666D01*
G01Y1481240D02*
Y1479666D01*
G01Y1486240D02*
Y1484666D01*
G01Y1491240D02*
Y1489666D01*
G01X881378Y1476240D02*
Y1474666D01*
G01Y1481240D02*
Y1479666D01*
G01Y1486240D02*
Y1484666D01*
G01Y1491240D02*
Y1489666D01*
G01X879252Y1476240D02*
Y1476398D01*
G01Y1476201D02*
Y1476240D01*
G01Y1474528D02*
Y1474666D01*
G01D02*
Y1475315D01*
G01X879084Y1475348D02*
Y1474725D01*
G01X878582D02*
Y1475348D01*
G01X878380Y1475315D02*
Y1474725D01*
G01X877677Y1474666D02*
Y1474528D01*
G01Y1474725D02*
Y1474666D01*
G01Y1476398D02*
Y1476240D01*
G01D02*
Y1476201D01*
G01X876456Y1484666D02*
Y1486240D01*
G01Y1479666D02*
Y1481240D01*
G01X875000Y1489666D02*
Y1491240D01*
G01Y1474666D02*
Y1476240D01*
G01X878414Y1475479D02*
X878380Y1475315D01*
G01X878582Y1475348D02*
X878615Y1475446D01*
G01X878515Y1475610D02*
X878414Y1475479D01*
G01X879017Y1476004D02*
X879252Y1476201D01*
G01X878984D02*
X878749Y1476004D01*
G01X878615Y1475446D02*
X878682Y1475512D01*
G01X878649Y1475709D02*
X878515Y1475610D01*
G01X878682Y1475512D02*
X878783Y1475545D01*
G01X878749Y1475741D02*
X878649Y1475709D01*
G01X885039Y1479567D02*
X881890Y1478386D01*
G01X885039Y1484567D02*
X881890Y1483386D01*
G01Y1512520D02*
X885039Y1511339D01*
G01X881890Y1507520D02*
X885039Y1506339D01*
G01X881890Y1502520D02*
X885039Y1501339D01*
G01X881890Y1497520D02*
X885039Y1496339D01*
G01X881890Y1492520D02*
X887008Y1491339D01*
G01X889764Y1511339D02*
X885039D01*
G01X876456Y1511240D02*
X893701D01*
G01Y1509666D02*
X876456D01*
G01X885039Y1509567D02*
X889764D01*
G01Y1506339D02*
X885039D01*
G01X876456Y1506240D02*
X893701D01*
G01Y1504666D02*
X876456D01*
G01X885039Y1504567D02*
X889764D01*
G01Y1501339D02*
X885039D01*
G01X876456Y1501240D02*
X893701D01*
G01Y1499666D02*
X876456D01*
G01X885039Y1499567D02*
X889764D01*
G01Y1496339D02*
X885039D01*
G01X876456Y1496240D02*
X893701D01*
G01Y1494666D02*
X876456D01*
G01X885039Y1494567D02*
X889764D01*
G01X875000Y1491240D02*
X894882D01*
G01X884134Y1509666D02*
Y1511240D01*
G01Y1504666D02*
Y1506240D01*
G01Y1499666D02*
Y1501240D01*
G01Y1494666D02*
Y1496240D01*
G01X882559Y1509666D02*
Y1511240D01*
G01Y1504666D02*
Y1506240D01*
G01Y1499666D02*
Y1501240D01*
G01Y1494666D02*
Y1496240D01*
G01X881890Y1507520D02*
Y1508386D01*
G01Y1502520D02*
Y1503386D01*
G01Y1497520D02*
Y1498386D01*
G01Y1492520D02*
Y1493386D01*
G01X881771Y1496240D02*
Y1494666D01*
G01Y1501240D02*
Y1499666D01*
G01Y1506240D02*
Y1504666D01*
G01Y1511240D02*
Y1509666D01*
G01X881378Y1496240D02*
Y1494666D01*
G01Y1501240D02*
Y1499666D01*
G01Y1506240D02*
Y1504666D01*
G01Y1511240D02*
Y1509666D01*
G01X876456D02*
Y1511240D01*
G01Y1504666D02*
Y1506240D01*
G01Y1499666D02*
Y1501240D01*
G01Y1494666D02*
Y1496240D01*
G01X885039Y1494567D02*
X881890Y1493386D01*
G01X885039Y1499567D02*
X881890Y1498386D01*
G01X885039Y1504567D02*
X881890Y1503386D01*
G01X885039Y1509567D02*
X881890Y1508386D01*
G01Y1527520D02*
X885039Y1526339D01*
G01X881890Y1522520D02*
X885039Y1521339D01*
G01X881890Y1517520D02*
X885039Y1516339D01*
G01X881890Y1532520D02*
X887008Y1531339D01*
G01X875000Y1531240D02*
X894882D01*
G01X875000Y1529666D02*
X894882D01*
G01X889764Y1526339D02*
X885039D01*
G01X876456Y1526240D02*
X893701D01*
G01Y1524666D02*
X876456D01*
G01X885039Y1524567D02*
X889764D01*
G01Y1521339D02*
X885039D01*
G01X876456Y1521240D02*
X893701D01*
G01Y1519666D02*
X876456D01*
G01X885039Y1519567D02*
X889764D01*
G01Y1516339D02*
X885039D01*
G01X876456Y1516240D02*
X893701D01*
G01Y1514666D02*
X876456D01*
G01X885039Y1514567D02*
X889764D01*
G01X887008Y1529567D02*
X881890Y1528386D01*
G01X884134Y1529666D02*
Y1531240D01*
G01Y1524666D02*
Y1526240D01*
G01Y1519666D02*
Y1521240D01*
G01Y1514666D02*
Y1516240D01*
G01X882559Y1529666D02*
Y1531240D01*
G01Y1524666D02*
Y1526240D01*
G01Y1519666D02*
Y1521240D01*
G01Y1514666D02*
Y1516240D01*
G01X881890Y1532520D02*
Y1533386D01*
G01Y1527520D02*
Y1528386D01*
G01Y1522520D02*
Y1523386D01*
G01Y1517520D02*
Y1518386D01*
G01Y1512520D02*
Y1513386D01*
G01X881771Y1516240D02*
Y1514666D01*
G01Y1521240D02*
Y1519666D01*
G01Y1526240D02*
Y1524666D01*
G01Y1531240D02*
Y1529666D01*
G01X881378Y1516240D02*
Y1514666D01*
G01Y1521240D02*
Y1519666D01*
G01Y1526240D02*
Y1524666D01*
G01Y1531240D02*
Y1529666D01*
G01X876456Y1524666D02*
Y1526240D01*
G01Y1519666D02*
Y1521240D01*
G01Y1514666D02*
Y1516240D01*
G01X875000Y1529666D02*
Y1531240D01*
G01X885039Y1514567D02*
X881890Y1513386D01*
G01X885039Y1519567D02*
X881890Y1518386D01*
G01X885039Y1524567D02*
X881890Y1523386D01*
G01Y1547520D02*
X885039Y1546339D01*
G01X881890Y1542520D02*
X885039Y1541339D01*
G01X881890Y1537520D02*
X885039Y1536339D01*
G01X893701Y1551043D02*
X874016D01*
G01Y1549272D02*
X893701D01*
G01X889764Y1546339D02*
X885039D01*
G01X876456Y1546240D02*
X893701D01*
G01Y1544666D02*
X876456D01*
G01X885039Y1544567D02*
X889764D01*
G01Y1541339D02*
X885039D01*
G01X876456Y1541240D02*
X893701D01*
G01Y1539666D02*
X876456D01*
G01X885039Y1539567D02*
X889764D01*
G01Y1536339D02*
X885039D01*
G01X876456Y1536240D02*
X893701D01*
G01Y1534666D02*
X876456D01*
G01X885039Y1534567D02*
X889764D01*
G01X884134Y1544666D02*
Y1546240D01*
G01Y1539666D02*
Y1541240D01*
G01Y1534666D02*
Y1536240D01*
G01X882559Y1544666D02*
Y1546240D01*
G01Y1539666D02*
Y1541240D01*
G01Y1534666D02*
Y1536240D01*
G01X881890Y1547520D02*
Y1549272D01*
G01Y1542520D02*
Y1543386D01*
G01Y1537520D02*
Y1538386D01*
G01X881771Y1536240D02*
Y1534666D01*
G01Y1541240D02*
Y1539666D01*
G01Y1546240D02*
Y1544666D01*
G01X881378Y1536240D02*
Y1534666D01*
G01Y1541240D02*
Y1539666D01*
G01Y1546240D02*
Y1544666D01*
G01X876456D02*
Y1546240D01*
G01Y1539666D02*
Y1541240D01*
G01Y1534666D02*
Y1536240D01*
G01X874016Y1549272D02*
Y1562540D01*
G01X885039Y1534567D02*
X881890Y1533386D01*
G01X885039Y1539567D02*
X881890Y1538386D01*
G01X885039Y1544567D02*
X881890Y1543386D01*
G01X884046Y1555392D02*
X884047Y1555394D01*
G01X884033Y1555361D02*
X884046Y1555392D01*
G01X884280Y1555929D02*
X884400Y1556181D01*
G01X884163Y1555667D02*
X884280Y1555929D01*
G01X884047Y1555394D02*
X884163Y1555667D01*
G01X884285Y1559573D02*
X884400Y1559331D01*
G01X884167Y1559835D02*
X884285Y1559573D01*
G01X884047Y1560118D02*
X884167Y1559835D01*
G01X884400Y1559331D02*
G03Y1556181I2017J-1575D01*
G01X884047Y1560118D02*
G03Y1555394I2370J-2362D01*
G01X889921Y1557756D02*
G03I-3504J0D01*
G01X883740Y1560906D02*
G03Y1554606I2677J-3150D01*
G01X883899Y1560484D02*
X883865Y1560570D01*
G01X883970Y1560305D02*
X883899Y1560484D01*
G01X884003Y1560224D02*
X883970Y1560305D01*
G01X884047Y1560118D02*
X884003Y1560224D01*
G01X881890Y1566477D02*
X870079D01*
G01X927953Y1562540D02*
X874016D01*
G01X883740Y1560906D02*
X889095D01*
G01X888788Y1560118D02*
X884047D01*
G01X884400Y1559331D02*
X888434D01*
G01X894488Y1557146D02*
X874016D01*
G01X884400Y1556181D02*
X888434D01*
G01X884047Y1555394D02*
X888788D01*
G01X889095Y1554606D02*
X883740D01*
G01X924016Y1554193D02*
X874016D01*
G01X883794Y1560758D02*
X883740Y1560906D01*
G01X883830Y1560662D02*
X883794Y1560758D01*
G01X883865Y1560570D02*
X883830Y1560662D01*
G01X881890Y1566477D02*
Y1579429D01*
G01X883993Y1555264D02*
X884033Y1555361D01*
G01X883958Y1555175D02*
X883993Y1555264D01*
G01X883899Y1555028D02*
X883958Y1555175D01*
G01X883865Y1554942D02*
X883899Y1555028D01*
G01X883830Y1554850D02*
X883865Y1554942D01*
G01X883794Y1554754D02*
X883830Y1554850D01*
G01X883740Y1554606D02*
X883794Y1554754D01*
G01X881890Y1579429D02*
X909449D01*
G01X870079Y1804941D02*
X881890D01*
G01X909449Y1791988D02*
X881890D01*
G01D02*
Y1804941D01*
G01X870079Y1971988D02*
Y1804941D01*
G01X888976Y1813662D02*
G03I-2559J0D01*
G01X889764D02*
G03I-3347J0D01*
G01X889921D02*
G03I-3504J0D01*
G01X886342Y1817795D02*
G03X886417Y1809528I75J-4133D01*
G01X878944Y1826083D02*
X879079Y1825984D01*
G01X878241Y1825951D02*
X878140Y1826017D01*
G01X877939Y1825033D02*
X877772Y1825131D01*
G01X878911Y1825886D02*
X878844Y1825919D01*
G01X878174Y1826214D02*
X878308Y1826148D01*
G01X881890Y1828032D02*
X885039Y1826851D01*
G01X878844Y1826116D02*
X878944Y1826083D01*
G01X878643Y1825328D02*
X878743Y1825295D01*
G01X877973Y1825230D02*
X878073Y1825197D01*
G01X878710Y1825099D02*
X878576Y1825131D01*
G01X878073Y1825000D02*
X877939Y1825033D01*
G01X879079Y1825984D02*
X879179Y1825853D01*
G01X878978Y1825820D02*
X878911Y1825886D01*
G01X878308Y1826148D02*
X878442Y1826017D01*
G01X878576Y1825131D02*
X878529Y1825177D01*
G01D02*
X878442Y1825262D01*
G01X877872Y1825328D02*
X877973Y1825230D01*
G01X879212Y1826870D02*
X877638D01*
G01X889764Y1826851D02*
X885039D01*
G01X876456Y1826752D02*
X893701D01*
G01X877638Y1826673D02*
X878944D01*
G01X878710Y1826477D02*
X878978D01*
G01X878006Y1826214D02*
X878174D01*
G01X878140Y1826017D02*
X878040D01*
G01X878743Y1825295D02*
X878810D01*
G01X893701Y1825177D02*
X876456D01*
G01X878844Y1825099D02*
X878710D01*
G01X885039Y1825079D02*
X889764D01*
G01X893701Y1822146D02*
X874016D01*
G01Y1820374D02*
X893701D01*
G01X874016Y1817225D02*
X924016D01*
G01X874016Y1814272D02*
X894488D01*
G01X927953Y1808878D02*
X874016D01*
G01X878442Y1826017D02*
X878509Y1825886D01*
G01X878442Y1825262D02*
X878375Y1825394D01*
G01X877772Y1825131D02*
X877743Y1825177D01*
G01D02*
X877671Y1825295D01*
G01X878308Y1825853D02*
X878241Y1825951D01*
G01X878576Y1825427D02*
X878643Y1825328D01*
G01X878978Y1825131D02*
X878844Y1825099D01*
G01X878341Y1825722D02*
X878308Y1825853D01*
G01X878375Y1825394D02*
X878341Y1825525D01*
G01X877839Y1825459D02*
X877872Y1825328D01*
G01X879011Y1825722D02*
X878978Y1825820D01*
G01X878542Y1825525D02*
X878576Y1825427D01*
G01X879179Y1825853D02*
X879212Y1825689D01*
G01X878509Y1825886D02*
X878542Y1825722D01*
G01X877671Y1825295D02*
X877638Y1825459D01*
G01X884134Y1825177D02*
Y1826752D01*
G01X882559Y1825177D02*
Y1826752D01*
G01X881890Y1828032D02*
Y1828898D01*
G01Y1822146D02*
Y1823898D01*
G01X881771Y1826752D02*
Y1825177D01*
G01X881378Y1826752D02*
Y1825177D01*
G01X879212Y1826752D02*
Y1826870D01*
G01Y1826673D02*
Y1826752D01*
G01Y1825689D02*
Y1825525D01*
G01X879011D02*
Y1825722D01*
G01X878844Y1825919D02*
Y1826116D01*
G01X878542Y1825722D02*
Y1825525D01*
G01X878341D02*
Y1825722D01*
G01X878073Y1825177D02*
Y1825000D01*
G01Y1825197D02*
Y1825177D01*
G01X877839Y1825722D02*
Y1825459D01*
G01X877638D02*
Y1825722D01*
G01Y1826870D02*
Y1826752D01*
G01D02*
Y1826673D01*
G01X876456Y1825177D02*
Y1826752D01*
G01X874016Y1808878D02*
Y1822146D01*
G01X877638Y1825722D02*
X877671Y1825886D01*
G01X879212Y1825525D02*
X879179Y1825394D01*
G01X877872Y1825853D02*
X877839Y1825722D01*
G01X878978Y1825427D02*
X879011Y1825525D01*
G01X879179Y1825394D02*
X879112Y1825262D01*
G01X877671Y1825886D02*
X877738Y1826017D01*
G01X878911Y1825328D02*
X878978Y1825427D01*
G01X877939Y1825951D02*
X877872Y1825853D01*
G01X879025Y1825177D02*
X878978Y1825131D01*
G01X879112Y1825262D02*
X879025Y1825177D01*
G01X877738Y1826017D02*
X877872Y1826148D01*
G01X878978Y1826477D02*
X879212Y1826673D01*
G01X878944D02*
X878710Y1826477D01*
G01X878040Y1826017D02*
X877939Y1825951D01*
G01X877872Y1826148D02*
X878006Y1826214D01*
G01X885039Y1825079D02*
X881890Y1823898D01*
G01X878810Y1825295D02*
X878911Y1825328D01*
G01X881890Y1848032D02*
X885039Y1846851D01*
G01X881890Y1843032D02*
X885039Y1841851D01*
G01X881890Y1838032D02*
X885039Y1836851D01*
G01X881890Y1833032D02*
X885039Y1831851D01*
G01X889764Y1846851D02*
X885039D01*
G01X876456Y1846752D02*
X893701D01*
G01Y1845177D02*
X876456D01*
G01X885039Y1845079D02*
X889764D01*
G01Y1841851D02*
X885039D01*
G01X876456Y1841752D02*
X893701D01*
G01Y1840177D02*
X876456D01*
G01X885039Y1840079D02*
X889764D01*
G01Y1836851D02*
X885039D01*
G01X876456Y1836752D02*
X893701D01*
G01Y1835177D02*
X876456D01*
G01X885039Y1835079D02*
X889764D01*
G01Y1831851D02*
X885039D01*
G01X876456Y1831752D02*
X893701D01*
G01Y1830177D02*
X876456D01*
G01X885039Y1830079D02*
X889764D01*
G01X884134Y1845177D02*
Y1846752D01*
G01Y1840177D02*
Y1841752D01*
G01Y1835177D02*
Y1836752D01*
G01Y1830177D02*
Y1831752D01*
G01X882559Y1845177D02*
Y1846752D01*
G01Y1840177D02*
Y1841752D01*
G01Y1835177D02*
Y1836752D01*
G01Y1830177D02*
Y1831752D01*
G01X881890Y1848032D02*
Y1848898D01*
G01Y1843032D02*
Y1843898D01*
G01Y1838032D02*
Y1838898D01*
G01Y1833032D02*
Y1833898D01*
G01X881771Y1831752D02*
Y1830177D01*
G01Y1836752D02*
Y1835177D01*
G01Y1841752D02*
Y1840177D01*
G01Y1846752D02*
Y1845177D01*
G01X881378Y1831752D02*
Y1830177D01*
G01Y1836752D02*
Y1835177D01*
G01Y1841752D02*
Y1840177D01*
G01Y1846752D02*
Y1845177D01*
G01X876456D02*
Y1846752D01*
G01Y1840177D02*
Y1841752D01*
G01Y1835177D02*
Y1836752D01*
G01Y1830177D02*
Y1831752D01*
G01X885039Y1830079D02*
X881890Y1828898D01*
G01X885039Y1835079D02*
X881890Y1833898D01*
G01X885039Y1840079D02*
X881890Y1838898D01*
G01X885039Y1845079D02*
X881890Y1843898D01*
G01X885039Y1850079D02*
X881890Y1848898D01*
G01X885223Y1857749D02*
X885055Y1857848D01*
G01X885457Y1858930D02*
X885591Y1858865D01*
G01X885424Y1860374D02*
X885591Y1860308D01*
G01X885323Y1859193D02*
X885156Y1859258D01*
G01X881890Y1853032D02*
X885039Y1851851D01*
G01X885256Y1857946D02*
X885356Y1857914D01*
G01X885859Y1859291D02*
X885759Y1859390D01*
G01X885591Y1858865D02*
X885725Y1858734D01*
G01X885156Y1859258D02*
X885055Y1859357D01*
G01X885859Y1857848D02*
X885725Y1857979D01*
G01X885156Y1858045D02*
X885256Y1857946D01*
G01X885424Y1860210D02*
X885558Y1860112D01*
G01X885323Y1859357D02*
X885189Y1859455D01*
G01X885524Y1858668D02*
X885424Y1858734D01*
G01X885356Y1857717D02*
X885223Y1857749D01*
G01X884449Y1871024D02*
X896456D01*
G01X884449Y1869055D02*
X896456D01*
G01X884449Y1867874D02*
X896456D01*
G01X884449Y1865906D02*
X896456D01*
G01X884449Y1864725D02*
X896456D01*
G01X884449Y1862756D02*
X896456D01*
G01X884449Y1861575D02*
X896456D01*
G01X885323Y1860374D02*
X885424D01*
G01X885323Y1860210D02*
X885424D01*
G01X884449Y1859606D02*
X896456D01*
G01X885424Y1859357D02*
X885323D01*
G01X885424Y1859193D02*
X885323D01*
G01X885290Y1858930D02*
X885457D01*
G01X885424Y1858734D02*
X885323D01*
G01X884449Y1858425D02*
X896456D01*
G01X885630Y1857441D02*
X888976D01*
G01X889764Y1856851D02*
X885630D01*
G01X876456Y1856752D02*
X893701D01*
G01Y1855177D02*
X876456D01*
G01X885039Y1855079D02*
X889764D01*
G01Y1851851D02*
X885039D01*
G01X876456Y1851752D02*
X893701D01*
G01Y1850177D02*
X876456D01*
G01X885039Y1850079D02*
X889764D01*
G01X885591Y1858569D02*
X885524Y1858668D01*
G01X885591Y1860308D02*
X885692Y1860177D01*
G01D02*
X885725Y1860112D01*
G01X885558D02*
X885625Y1859980D01*
G01X885759Y1859390D02*
X885725Y1859455D01*
G01Y1858734D02*
X885792Y1858603D01*
G01X885189Y1859455D02*
X885122Y1859587D01*
G01X885725Y1857979D02*
X885658Y1858110D01*
G01X885055Y1859357D02*
X884955Y1859521D01*
G01X885055Y1857848D02*
X884955Y1858012D01*
G01X885625Y1859980D02*
X885658Y1859849D01*
G01X885625Y1858438D02*
X885591Y1858569D01*
G01X885658Y1858110D02*
X885625Y1858241D01*
G01X885117Y1859606D02*
X885089Y1859718D01*
G01X885122Y1859587D02*
X885117Y1859606D01*
G01X885122Y1858176D02*
X885156Y1858045D01*
G01X884937Y1859606D02*
X884921Y1859685D01*
G01X884955Y1859521D02*
X884937Y1859606D01*
G01X884955Y1858012D02*
X884921Y1858176D01*
G01X885658Y1859849D02*
Y1859718D01*
G01X885630Y1856851D02*
Y1857441D01*
G01X885625Y1858241D02*
Y1858425D01*
G01D02*
Y1858438D01*
G01X885356Y1857914D02*
Y1857717D01*
G01X885122Y1858425D02*
Y1858176D01*
G01Y1858438D02*
Y1858425D01*
G01X885089Y1859718D02*
Y1859849D01*
G01X884921Y1859685D02*
Y1859882D01*
G01Y1858176D02*
Y1858425D01*
G01D02*
Y1858438D01*
G01X884449Y1871024D02*
Y1872205D01*
G01Y1864725D02*
Y1865906D01*
G01Y1867874D02*
Y1869055D01*
G01Y1861575D02*
Y1862756D01*
G01Y1858425D02*
Y1859606D01*
G01X884134Y1855177D02*
Y1856752D01*
G01Y1850177D02*
Y1851752D01*
G01X882559Y1855177D02*
Y1856752D01*
G01Y1850177D02*
Y1851752D01*
G01X881890Y1853032D02*
Y1853898D01*
G01X881771Y1851752D02*
Y1850177D01*
G01Y1856752D02*
Y1855177D01*
G01X881378Y1851752D02*
Y1850177D01*
G01Y1856752D02*
Y1855177D01*
G01X876456D02*
Y1856752D01*
G01Y1850177D02*
Y1851752D01*
G01X884921Y1858438D02*
X884955Y1858603D01*
G01X884921Y1859882D02*
X884955Y1860046D01*
G01X885658Y1859718D02*
X885630Y1859606D01*
G01D02*
X885625Y1859587D01*
G01X885156Y1858569D02*
X885122Y1858438D01*
G01X885089Y1859849D02*
X885122Y1859980D01*
G01X884955Y1860046D02*
X885055Y1860210D01*
G01X885725Y1859455D02*
X885692Y1859390D01*
G01X885625Y1859587D02*
X885558Y1859455D01*
G01X884955Y1858603D02*
X885021Y1858734D01*
G01X885725Y1860112D02*
X885759Y1860177D01*
G01X885122Y1859980D02*
X885189Y1860112D01*
G01X885223Y1858668D02*
X885156Y1858569D01*
G01X885692Y1859390D02*
X885591Y1859258D01*
G01X885021Y1858734D02*
X885156Y1858865D01*
G01X885759Y1860177D02*
X885859Y1860276D01*
G01X885055Y1860210D02*
X885156Y1860308D01*
G01X885323Y1858734D02*
X885223Y1858668D01*
G01X885558Y1859455D02*
X885424Y1859357D01*
G01X885189Y1860112D02*
X885323Y1860210D01*
G01X885591Y1859258D02*
X885424Y1859193D01*
G01X885156Y1860308D02*
X885323Y1860374D01*
G01X885156Y1858865D02*
X885290Y1858930D01*
G01X885039Y1855079D02*
X881890Y1853898D01*
G01X879118Y1881122D02*
X878984Y1881221D01*
G01X881890Y1893032D02*
X885039Y1891851D01*
G01X881890Y1888032D02*
X885039Y1886851D01*
G01X881890Y1883032D02*
X885039Y1881851D01*
G01X878984Y1881221D02*
X878883Y1881253D01*
G01Y1881056D02*
X878984Y1881024D01*
G01D02*
X879051Y1880958D01*
G01X889764Y1891851D02*
X885039D01*
G01X876456Y1891752D02*
X893701D01*
G01Y1890177D02*
X876456D01*
G01X885039Y1890079D02*
X889764D01*
G01Y1886851D02*
X885039D01*
G01X876456Y1886752D02*
X893701D01*
G01Y1885177D02*
X876456D01*
G01X885039Y1885079D02*
X889764D01*
G01X879252Y1881910D02*
X877677D01*
G01X889764Y1881851D02*
X885039D01*
G01X875000Y1881752D02*
X893701D01*
G01X877677Y1881713D02*
X878984D01*
G01X878749Y1881516D02*
X879017D01*
G01X878883Y1881253D02*
X878749D01*
G01X878783Y1881056D02*
X878883D01*
G01X879084Y1880236D02*
X878582D01*
G01X878380D02*
X877677D01*
G01X875000Y1880177D02*
X893701D01*
G01X885630Y1880079D02*
X889764D01*
G01X877677Y1880040D02*
X879252D01*
G01X888976Y1879488D02*
X885630D01*
G01X884449Y1878504D02*
X896456D01*
G01X884449Y1877323D02*
X896456D01*
G01X884449Y1875354D02*
X896456D01*
G01X884449Y1874173D02*
X896456D01*
G01X884449Y1872205D02*
X896456D01*
G01X879218Y1880991D02*
X879118Y1881122D01*
G01X879051Y1880958D02*
X879084Y1880860D01*
G01X879252Y1880827D02*
X879218Y1880991D01*
G01X885630Y1879488D02*
Y1880079D01*
G01X884449Y1877323D02*
Y1878504D01*
G01Y1874173D02*
Y1875354D01*
G01X884134Y1890177D02*
Y1891752D01*
G01Y1885177D02*
Y1886752D01*
G01Y1880177D02*
Y1881752D01*
G01X882559Y1890177D02*
Y1891752D01*
G01Y1885177D02*
Y1886752D01*
G01Y1880177D02*
Y1881752D01*
G01X881890Y1888032D02*
Y1888898D01*
G01Y1883032D02*
Y1883898D01*
G01X881771Y1881752D02*
Y1880177D01*
G01Y1886752D02*
Y1885177D01*
G01Y1891752D02*
Y1890177D01*
G01X881378Y1881752D02*
Y1880177D01*
G01Y1886752D02*
Y1885177D01*
G01Y1891752D02*
Y1890177D01*
G01X879252Y1881752D02*
Y1881910D01*
G01Y1880040D02*
Y1880177D01*
G01Y1881713D02*
Y1881752D01*
G01Y1880177D02*
Y1880827D01*
G01X879084Y1880860D02*
Y1880236D01*
G01X878582D02*
Y1880860D01*
G01X878380Y1880827D02*
Y1880236D01*
G01X877677Y1881910D02*
Y1881752D01*
G01Y1880177D02*
Y1880040D01*
G01Y1881752D02*
Y1881713D01*
G01Y1880236D02*
Y1880177D01*
G01X876456Y1890177D02*
Y1891752D01*
G01Y1885177D02*
Y1886752D01*
G01X875000Y1880177D02*
Y1881752D01*
G01X878414Y1880991D02*
X878380Y1880827D01*
G01X878582Y1880860D02*
X878615Y1880958D01*
G01X878515Y1881122D02*
X878414Y1880991D01*
G01X878615Y1880958D02*
X878682Y1881024D01*
G01X878649Y1881221D02*
X878515Y1881122D01*
G01X879017Y1881516D02*
X879252Y1881713D01*
G01X878984D02*
X878749Y1881516D01*
G01X878682Y1881024D02*
X878783Y1881056D01*
G01X878749Y1881253D02*
X878649Y1881221D01*
G01X885039Y1885079D02*
X881890Y1883898D01*
G01X885039Y1890079D02*
X881890Y1888898D01*
G01Y1913032D02*
X885039Y1911851D01*
G01X881890Y1908032D02*
X885039Y1906851D01*
G01X881890Y1903032D02*
X885039Y1901851D01*
G01X881890Y1898032D02*
X887008Y1896851D01*
G01X889764Y1911851D02*
X885039D01*
G01X876456Y1911752D02*
X893701D01*
G01Y1910177D02*
X876456D01*
G01X885039Y1910079D02*
X889764D01*
G01Y1906851D02*
X885039D01*
G01X876456Y1906752D02*
X893701D01*
G01Y1905177D02*
X876456D01*
G01X885039Y1905079D02*
X889764D01*
G01Y1901851D02*
X885039D01*
G01X876456Y1901752D02*
X893701D01*
G01Y1900177D02*
X876456D01*
G01X885039Y1900079D02*
X889764D01*
G01X875000Y1896752D02*
X894882D01*
G01X875000Y1895177D02*
X894882D01*
G01X887008Y1895079D02*
X881890Y1893898D01*
G01X884134Y1910177D02*
Y1911752D01*
G01Y1905177D02*
Y1906752D01*
G01Y1900177D02*
Y1901752D01*
G01Y1895177D02*
Y1896752D01*
G01X882559Y1910177D02*
Y1911752D01*
G01Y1905177D02*
Y1906752D01*
G01Y1900177D02*
Y1901752D01*
G01Y1895177D02*
Y1896752D01*
G01X881890Y1913032D02*
Y1913898D01*
G01Y1908032D02*
Y1908898D01*
G01Y1903032D02*
Y1903898D01*
G01Y1898032D02*
Y1898898D01*
G01Y1893032D02*
Y1893898D01*
G01X881771Y1896752D02*
Y1895177D01*
G01Y1901752D02*
Y1900177D01*
G01Y1906752D02*
Y1905177D01*
G01Y1911752D02*
Y1910177D01*
G01X881378Y1896752D02*
Y1895177D01*
G01Y1901752D02*
Y1900177D01*
G01Y1906752D02*
Y1905177D01*
G01Y1911752D02*
Y1910177D01*
G01X876456D02*
Y1911752D01*
G01Y1905177D02*
Y1906752D01*
G01Y1900177D02*
Y1901752D01*
G01X875000Y1895177D02*
Y1896752D01*
G01X885039Y1900079D02*
X881890Y1898898D01*
G01X885039Y1905079D02*
X881890Y1903898D01*
G01X885039Y1910079D02*
X881890Y1908898D01*
G01Y1933032D02*
X885039Y1931851D01*
G01X881890Y1928032D02*
X885039Y1926851D01*
G01X881890Y1923032D02*
X885039Y1921851D01*
G01X881890Y1918032D02*
X885039Y1916851D01*
G01X889764Y1931851D02*
X885039D01*
G01X876456Y1931752D02*
X893701D01*
G01Y1930177D02*
X876456D01*
G01X885039Y1930079D02*
X889764D01*
G01Y1926851D02*
X885039D01*
G01X876456Y1926752D02*
X893701D01*
G01Y1925177D02*
X876456D01*
G01X885039Y1925079D02*
X889764D01*
G01Y1921851D02*
X885039D01*
G01X876456Y1921752D02*
X893701D01*
G01Y1920177D02*
X876456D01*
G01X885039Y1920079D02*
X889764D01*
G01Y1916851D02*
X885039D01*
G01X876456Y1916752D02*
X893701D01*
G01Y1915177D02*
X876456D01*
G01X885039Y1915079D02*
X889764D01*
G01X887008Y1935079D02*
X881890Y1933898D01*
G01X884134Y1930177D02*
Y1931752D01*
G01Y1925177D02*
Y1926752D01*
G01Y1920177D02*
Y1921752D01*
G01Y1915177D02*
Y1916752D01*
G01X882559Y1930177D02*
Y1931752D01*
G01Y1925177D02*
Y1926752D01*
G01Y1920177D02*
Y1921752D01*
G01Y1915177D02*
Y1916752D01*
G01X881890Y1933032D02*
Y1933898D01*
G01Y1928032D02*
Y1928898D01*
G01Y1923032D02*
Y1923898D01*
G01Y1918032D02*
Y1918898D01*
G01X881771Y1916752D02*
Y1915177D01*
G01Y1921752D02*
Y1920177D01*
G01Y1926752D02*
Y1925177D01*
G01Y1931752D02*
Y1930177D01*
G01X881378Y1916752D02*
Y1915177D01*
G01Y1921752D02*
Y1920177D01*
G01Y1926752D02*
Y1925177D01*
G01Y1931752D02*
Y1930177D01*
G01X876456D02*
Y1931752D01*
G01Y1925177D02*
Y1926752D01*
G01Y1920177D02*
Y1921752D01*
G01Y1915177D02*
Y1916752D01*
G01X885039Y1915079D02*
X881890Y1913898D01*
G01X885039Y1920079D02*
X881890Y1918898D01*
G01X885039Y1925079D02*
X881890Y1923898D01*
G01X885039Y1930079D02*
X881890Y1928898D01*
G01Y1953032D02*
X885039Y1951851D01*
G01X881890Y1948032D02*
X885039Y1946851D01*
G01X881890Y1943032D02*
X885039Y1941851D01*
G01X881890Y1938032D02*
X887008Y1936851D01*
G01X874016Y1954784D02*
X893701D01*
G01X889764Y1951851D02*
X885039D01*
G01X876456Y1951752D02*
X893701D01*
G01Y1950177D02*
X876456D01*
G01X885039Y1950079D02*
X889764D01*
G01Y1946851D02*
X885039D01*
G01X876456Y1946752D02*
X893701D01*
G01Y1945177D02*
X876456D01*
G01X885039Y1945079D02*
X889764D01*
G01Y1941851D02*
X885039D01*
G01X876456Y1941752D02*
X893701D01*
G01Y1940177D02*
X876456D01*
G01X885039Y1940079D02*
X889764D01*
G01X875000Y1936752D02*
X894882D01*
G01X875000Y1935177D02*
X894882D01*
G01X884134Y1950177D02*
Y1951752D01*
G01Y1945177D02*
Y1946752D01*
G01Y1940177D02*
Y1941752D01*
G01Y1935177D02*
Y1936752D01*
G01X882559Y1950177D02*
Y1951752D01*
G01Y1945177D02*
Y1946752D01*
G01Y1940177D02*
Y1941752D01*
G01Y1935177D02*
Y1936752D01*
G01X881890Y1953032D02*
Y1954784D01*
G01Y1948032D02*
Y1948898D01*
G01Y1943032D02*
Y1943898D01*
G01Y1938032D02*
Y1938898D01*
G01X881771Y1936752D02*
Y1935177D01*
G01Y1941752D02*
Y1940177D01*
G01Y1946752D02*
Y1945177D01*
G01Y1951752D02*
Y1950177D01*
G01X881378Y1936752D02*
Y1935177D01*
G01Y1941752D02*
Y1940177D01*
G01Y1946752D02*
Y1945177D01*
G01Y1951752D02*
Y1950177D01*
G01X876456D02*
Y1951752D01*
G01Y1945177D02*
Y1946752D01*
G01Y1940177D02*
Y1941752D01*
G01X875000Y1935177D02*
Y1936752D01*
G01X874016Y1954784D02*
Y1968051D01*
G01X885039Y1940079D02*
X881890Y1938898D01*
G01X885039Y1945079D02*
X881890Y1943898D01*
G01X885039Y1950079D02*
X881890Y1948898D01*
G01X884046Y1960904D02*
X884047Y1960906D01*
G01X884033Y1960873D02*
X884046Y1960904D01*
G01X884280Y1961441D02*
X884400Y1961693D01*
G01X884163Y1961178D02*
X884280Y1961441D01*
G01X884047Y1960906D02*
X884163Y1961178D01*
G01X884285Y1965084D02*
X884400Y1964843D01*
G01X884167Y1965347D02*
X884285Y1965084D01*
G01X884047Y1965630D02*
X884167Y1965347D01*
G01X884400Y1964843D02*
G03Y1961693I2017J-1575D01*
G01X884047Y1965630D02*
G03Y1960906I2370J-2362D01*
G01X889921Y1963268D02*
G03I-3504J0D01*
G01X883740Y1966417D02*
G03Y1960118I2677J-3149D01*
G01X881890Y1971988D02*
X870079D01*
G01X927953Y1968051D02*
X874016D01*
G01X883740Y1966417D02*
X889095D01*
G01X888788Y1965630D02*
X884047D01*
G01X884400Y1964843D02*
X888434D01*
G01X894488Y1962658D02*
X874016D01*
G01X884400Y1961693D02*
X888434D01*
G01X884047Y1960906D02*
X888788D01*
G01X889095Y1960118D02*
X883740D01*
G01X924016Y1959705D02*
X874016D01*
G01X893701Y1956555D02*
X874016D01*
G01X883970Y1965817D02*
X883899Y1965996D01*
G01X884003Y1965736D02*
X883970Y1965817D01*
G01X884047Y1965630D02*
X884003Y1965736D01*
G01X883794Y1966269D02*
X883740Y1966417D01*
G01X883830Y1966173D02*
X883794Y1966269D01*
G01X883865Y1966082D02*
X883830Y1966173D01*
G01X883899Y1965996D02*
X883865Y1966082D01*
G01X881890Y1971988D02*
Y1984941D01*
G01X883993Y1960775D02*
X884033Y1960873D01*
G01X883958Y1960687D02*
X883993Y1960775D01*
G01X883899Y1960540D02*
X883958Y1960687D01*
G01X883865Y1960454D02*
X883899Y1960540D01*
G01X883830Y1960362D02*
X883865Y1960454D01*
G01X883794Y1960266D02*
X883830Y1960362D01*
G01X883740Y1960118D02*
X883794Y1960266D01*
G01X881890Y1984941D02*
X909449D01*
G01X905849Y-51088D02*
Y-70025D01*
G01X892519Y162835D02*
G03Y164016I0J591D01*
G01X898819D02*
G03Y162835I0J-590D01*
G01Y161260D02*
G03Y160079I0J-591D01*
G01X892519D02*
G03Y161260I0J591D01*
G01X899409Y179803D02*
G03I-3740J0D01*
G01X898901Y163198D02*
X898808Y163087D01*
G01Y163214D02*
X898901Y163325D01*
G01X905512Y173878D02*
Y186831D01*
G01X900393Y159784D02*
Y161752D01*
G01Y164311D02*
Y162343D01*
G01X898901Y163325D02*
Y163198D01*
G01X898819Y164016D02*
Y164606D01*
G01Y161260D02*
Y162835D01*
G01Y159488D02*
Y160079D01*
G01X898808Y163835D02*
Y163214D01*
G01X898714Y163087D02*
Y163835D01*
G01X898622Y178819D02*
Y179016D01*
G01X897834Y164606D02*
Y159488D01*
G01X897638D02*
Y164606D01*
G01X897244Y162343D02*
Y164311D01*
G01Y161752D02*
Y159784D01*
G01X894094Y162343D02*
Y164311D01*
G01Y161752D02*
Y159784D01*
G01X893701Y159488D02*
Y164606D01*
G01X893504D02*
Y159488D01*
G01X892716Y179016D02*
Y178819D01*
G01X892519Y160079D02*
Y159488D01*
G01Y162835D02*
Y161260D01*
G01Y164606D02*
Y164016D01*
G01X890945Y159784D02*
Y161752D01*
G01Y164311D02*
Y162343D01*
G01X885827Y173878D02*
Y186831D01*
G01X905512Y178819D02*
X885827D01*
G01Y177835D02*
X905512D01*
G01X885827Y175847D02*
X905512D01*
G01X885827Y173878D02*
X905512D01*
G01X892519Y164606D02*
X898819D01*
G01Y164311D02*
X900393D01*
G01X897244D02*
X898819D01*
G01X892519D02*
X890945D01*
G01X894094D02*
X892519D01*
G01X898714Y163835D02*
X898808D01*
G01Y163087D02*
X898714D01*
G01X892519Y162343D02*
X894094D01*
G01X890945D02*
X892519D01*
G01X900393D02*
X898819D01*
G01D02*
X897244D01*
G01X892519Y162087D02*
X898819D01*
G01X892519Y161752D02*
X894094D01*
G01X890945D02*
X892519D01*
G01X900393D02*
X898819D01*
G01D02*
X897244D01*
G01X898819Y159784D02*
X900393D01*
G01X897244D02*
X898819D01*
G01X892519D02*
X890945D01*
G01X894094D02*
X892519D01*
G01Y159488D02*
X898819D01*
G01X886492Y187481D02*
G03X886417Y195748I-75J4133D01*
G01X905512Y186831D02*
Y346004D01*
G01X905315Y179016D02*
Y180591D01*
G01X899960D02*
Y179016D01*
G01X898622Y180591D02*
Y180788D01*
G01Y180591D02*
Y179016D01*
G01X898425Y180591D02*
Y179016D01*
G01X897638Y332736D02*
Y200099D01*
G01X896850Y180591D02*
Y179016D01*
G01X896358Y200099D02*
Y332736D01*
G01X894980D02*
Y200099D01*
G01X894488Y186831D02*
Y195177D01*
G01Y180591D02*
Y179016D01*
G01X893701Y198327D02*
Y236378D01*
G01X892913Y179016D02*
Y180591D01*
G01X892716D02*
Y180788D01*
G01Y179016D02*
Y180591D01*
G01X891378Y179016D02*
Y180591D01*
G01X886023D02*
Y179016D01*
G01X896358Y200099D02*
X924803D01*
G01X893701D02*
X894980D01*
G01X894488Y192225D02*
X905512D01*
G01X927953Y188012D02*
X894488D01*
G01X885827Y184862D02*
X905512D01*
G01Y181772D02*
X885827D01*
G01Y180788D02*
X905512D01*
G01X905315Y180591D02*
X886023D01*
G01X905315Y179016D02*
X886023D01*
G01X886342Y195748D02*
X886417D01*
G01X886492Y187481D02*
X886417Y187480D01*
G01X889764Y219705D02*
Y219803D01*
G01Y218032D02*
Y218130D01*
G01D02*
Y219705D01*
G01Y214705D02*
Y214803D01*
G01Y213032D02*
Y213130D01*
G01D02*
Y214705D01*
G01Y209705D02*
Y209803D01*
G01Y208032D02*
Y208130D01*
G01D02*
Y209705D01*
G01Y204705D02*
Y204803D01*
G01Y203032D02*
Y203130D01*
G01D02*
Y204705D01*
G01X893701Y219803D02*
X925984D01*
G01X893701Y219705D02*
X924223D01*
G01X893701Y218130D02*
X924223D01*
G01X893701Y218032D02*
X925984D01*
G01X893701Y214803D02*
X925984D01*
G01X893701Y214705D02*
X924223D01*
G01X893701Y213130D02*
X924223D01*
G01X893701Y213032D02*
X925984D01*
G01X893701Y209803D02*
X925984D01*
G01X893701Y209705D02*
X924223D01*
G01X893701Y208130D02*
X924223D01*
G01X893701Y208032D02*
X925984D01*
G01X893701Y204803D02*
X925984D01*
G01X893701Y204705D02*
X924223D01*
G01X893701Y203130D02*
X924223D01*
G01X893701Y203032D02*
X925984D01*
G01X891338Y236280D02*
X888976Y235591D01*
G01X891338Y239429D02*
X888976Y238740D01*
G01X891338Y242579D02*
X888976Y241890D01*
G01X886094Y235965D02*
X886194Y235997D01*
G01X886261Y237244D02*
X886094Y237178D01*
G01X885859Y238228D02*
X885993Y238294D01*
G01X886194Y237408D02*
X886094Y237343D01*
G01X885926Y238064D02*
X886027Y238130D01*
G01X886395Y235932D02*
X886261Y235801D01*
G01X886362Y237343D02*
X886261Y237244D01*
G01X886295Y237540D02*
X886194Y237408D01*
G01X885826Y237933D02*
X885926Y238064D01*
G01X886194Y235997D02*
X886261Y236096D01*
G01X886462Y237506D02*
X886362Y237343D01*
G01X886462Y236063D02*
X886395Y235932D01*
G01X886261Y236096D02*
X886295Y236194D01*
G01X886496D02*
X886462Y236063D01*
G01X886329Y237671D02*
X886300Y237559D01*
G01D02*
X886295Y237540D01*
G01X885792Y237802D02*
X885826Y237933D01*
G01X886496Y237671D02*
X886473Y237559D01*
G01D02*
X886462Y237506D01*
G01X896456Y234213D02*
Y258622D01*
G01X893701Y239528D02*
Y237559D01*
G01D02*
Y236378D01*
G01Y242677D02*
Y240709D01*
G01D02*
Y239528D01*
G01X891811D02*
Y240709D01*
G01Y236378D02*
Y237559D01*
G01X890236Y239528D02*
Y240709D01*
G01Y236378D02*
Y237559D01*
G01X889764Y234705D02*
Y234803D01*
G01Y233032D02*
Y233130D01*
G01D02*
Y234705D01*
G01Y229705D02*
Y229803D01*
G01Y228032D02*
Y228130D01*
G01D02*
Y229705D01*
G01Y224705D02*
Y224803D01*
G01Y223032D02*
Y223130D01*
G01D02*
Y224705D01*
G01X889449Y237559D02*
Y236378D01*
G01Y240709D02*
Y239528D01*
G01X889055Y237559D02*
Y236378D01*
G01Y240709D02*
Y239528D01*
G01X888976Y241496D02*
Y241890D01*
G01Y235394D02*
Y235591D01*
G01Y238347D02*
Y238740D01*
G01X886811Y227795D02*
Y225040D01*
G01X886496Y237802D02*
Y237671D01*
G01Y236358D02*
Y236194D01*
G01X886329Y237802D02*
Y237671D01*
G01X886295Y236194D02*
Y236378D01*
G01D02*
Y236391D01*
G01X886127Y236588D02*
Y236785D01*
G01X885826Y236378D02*
Y236194D01*
G01Y236391D02*
Y236378D01*
G01X885792Y237671D02*
Y237802D01*
G01X886462Y237966D02*
X886496Y237802D01*
G01X886492Y236378D02*
X886496Y236358D01*
G01X886462Y236522D02*
X886492Y236378D01*
G01X885792Y236555D02*
X885826Y236391D01*
G01X886295Y237933D02*
X886329Y237802D01*
G01X885821Y237559D02*
X885792Y237671D01*
G01X885826Y237540D02*
X885821Y237559D01*
G01X886295Y236391D02*
X886261Y236490D01*
G01X885826Y236194D02*
X885859Y236096D01*
G01X886362Y238130D02*
X886462Y237966D01*
G01X885859Y236096D02*
X885926Y235997D01*
G01X886194Y238064D02*
X886295Y237933D01*
G01X885926Y237408D02*
X885826Y237540D01*
G01X886362Y236654D02*
X886462Y236522D01*
G01X886261Y238228D02*
X886362Y238130D01*
G01X886261Y236490D02*
X886194Y236555D01*
G01X886228Y236752D02*
X886362Y236654D01*
G01X886094Y238130D02*
X886194Y238064D01*
G01X886027Y237343D02*
X885926Y237408D01*
G01X885993Y237178D02*
X885859Y237244D01*
G01X886194Y236555D02*
X886127Y236588D01*
G01X886094Y238294D02*
X886261Y238228D01*
G01X886127Y236785D02*
X886228Y236752D01*
G01X885926Y235997D02*
X886027Y235965D01*
G01X888976Y241496D02*
X891338Y240807D01*
G01X888976Y238347D02*
X891338Y237658D01*
G01X885993Y235768D02*
X885859Y235801D01*
G01X896456Y240807D02*
X925787D01*
G01X891338D02*
X893701D01*
G01X896456Y240709D02*
X922560D01*
G01Y239528D02*
X896456D01*
G01Y239429D02*
X925787D01*
G01X891338D02*
X893701D01*
G01X885993Y238294D02*
X886094D01*
G01X886027Y238130D02*
X886094D01*
G01X891338Y237658D02*
X893701D01*
G01X925787D02*
X896456D01*
G01Y237559D02*
X922560D01*
G01X886094Y237343D02*
X886027D01*
G01X886094Y237178D02*
X885993D01*
G01X924016Y236654D02*
X905512D01*
G01X922560Y236378D02*
X896456D01*
G01X891338Y236280D02*
X893701D01*
G01X925787D02*
X896456D01*
G01X886027Y235965D02*
X886094D01*
G01X886127Y235768D02*
X885993D01*
G01X923031Y234803D02*
X893701D01*
G01Y234705D02*
X924102D01*
G01X893701Y234213D02*
X925984D01*
G01X924102Y233130D02*
X893701D01*
G01Y233032D02*
X923031D01*
G01X925984Y229803D02*
X893701D01*
G01Y229705D02*
X924223D01*
G01X893701Y228130D02*
X924223D01*
G01X893701Y228032D02*
X925984D01*
G01X886811Y227795D02*
X893701D01*
G01Y225040D02*
X886811D01*
G01X893701Y224803D02*
X925984D01*
G01X893701Y224705D02*
X924223D01*
G01X893701Y223130D02*
X924223D01*
G01X893701Y223032D02*
X925984D01*
G01X886261Y235801D02*
X886127Y235768D01*
G01X891338Y245728D02*
X888976Y245040D01*
G01X891338Y248878D02*
X888976Y248189D01*
G01X891338Y252028D02*
X888976Y251339D01*
G01X891338Y255177D02*
X888976Y254488D01*
G01X893701Y256457D02*
Y273130D01*
G01Y243858D02*
Y242677D01*
G01Y245827D02*
Y243858D01*
G01Y248977D02*
Y247008D01*
G01D02*
Y245827D01*
G01Y252126D02*
Y250158D01*
G01D02*
Y248977D01*
G01Y253307D02*
Y252126D01*
G01Y255276D02*
Y253307D01*
G01Y256457D02*
Y255276D01*
G01X891811D02*
Y256457D01*
G01Y248977D02*
Y250158D01*
G01Y252126D02*
Y253307D01*
G01Y245827D02*
Y247008D01*
G01Y242677D02*
Y243858D01*
G01X890236Y255276D02*
Y256457D01*
G01Y252126D02*
Y253307D01*
G01Y248977D02*
Y250158D01*
G01Y245827D02*
Y247008D01*
G01Y242677D02*
Y243858D01*
G01X889764Y263130D02*
Y264705D01*
G01Y263032D02*
Y263130D01*
G01Y259705D02*
Y259803D01*
G01Y258130D02*
Y259705D01*
G01Y258032D02*
Y258130D01*
G01X889449Y243858D02*
Y242677D01*
G01Y247008D02*
Y245827D01*
G01Y250158D02*
Y248977D01*
G01Y253307D02*
Y252126D01*
G01Y256457D02*
Y255276D01*
G01X889055Y243858D02*
Y242677D01*
G01Y247008D02*
Y245827D01*
G01Y250158D02*
Y248977D01*
G01Y253307D02*
Y252126D01*
G01Y256457D02*
Y255276D01*
G01X888976Y254095D02*
Y254488D01*
G01Y257244D02*
Y257441D01*
G01Y250945D02*
Y251339D01*
G01Y244646D02*
Y245040D01*
G01Y247795D02*
Y248189D01*
G01X886811Y262795D02*
Y260040D01*
G01X888976Y257244D02*
X891338Y256555D01*
G01X888976Y254095D02*
X891338Y253406D01*
G01X888976Y250945D02*
X891338Y250256D01*
G01X888976Y247795D02*
X891338Y247106D01*
G01X888976Y244646D02*
X891338Y243957D01*
G01X924223Y263130D02*
X893701D01*
G01Y263032D02*
X925984D01*
G01X886811Y262795D02*
X893701D01*
G01Y260040D02*
X886811D01*
G01X893701Y259803D02*
X923031D01*
G01X893701Y259705D02*
X924102D01*
G01X893701Y258622D02*
X925984D01*
G01X893701Y258130D02*
X924102D01*
G01X893701Y258032D02*
X923031D01*
G01X896456Y256555D02*
X925787D01*
G01X891338D02*
X893701D01*
G01X896456Y256457D02*
X922560D01*
G01X905512Y256181D02*
X924016D01*
G01X922560Y255276D02*
X896456D01*
G01Y255177D02*
X925787D01*
G01X891338D02*
X893701D01*
G01X896456Y253406D02*
X925787D01*
G01X891338D02*
X893701D01*
G01X896456Y253307D02*
X922560D01*
G01Y252126D02*
X896456D01*
G01Y252028D02*
X925787D01*
G01X891338D02*
X893701D01*
G01X896456Y250256D02*
X925787D01*
G01X891338D02*
X893701D01*
G01X896456Y250158D02*
X922560D01*
G01Y248977D02*
X896456D01*
G01Y248878D02*
X925787D01*
G01X891338D02*
X893701D01*
G01X896456Y247106D02*
X925787D01*
G01X891338D02*
X893701D01*
G01X896456Y247008D02*
X922560D01*
G01Y245827D02*
X896456D01*
G01Y245728D02*
X925787D01*
G01X891338D02*
X893701D01*
G01X896456Y243957D02*
X925787D01*
G01X891338D02*
X893701D01*
G01X896456Y243858D02*
X922560D01*
G01Y242677D02*
X896456D01*
G01Y242579D02*
X925787D01*
G01X891338D02*
X893701D01*
G01X894882Y271555D02*
Y276280D01*
G01X893701Y274705D02*
Y313130D01*
G01Y274705D02*
Y273130D01*
G01X891732Y274705D02*
Y274803D01*
G01Y273032D02*
Y273130D01*
G01D02*
Y274705D01*
G01X889764Y284705D02*
Y284803D01*
G01Y283032D02*
Y283130D01*
G01D02*
Y284705D01*
G01Y279705D02*
Y279803D01*
G01Y278032D02*
Y278130D01*
G01D02*
Y279705D01*
G01Y269705D02*
Y269803D01*
G01Y268130D02*
Y269705D01*
G01Y268032D02*
Y268130D01*
G01Y264705D02*
Y264803D01*
G01X893701Y284705D02*
X924223D01*
G01X893701Y283130D02*
X924223D01*
G01X893701Y283032D02*
X925984D01*
G01X893701Y279803D02*
X925984D01*
G01X893701Y279705D02*
X924223D01*
G01X893701Y278130D02*
X924223D01*
G01X893701Y278032D02*
X925984D01*
G01X894882Y276280D02*
X893701D01*
G01X891732Y274803D02*
X887008D01*
G01X925984D02*
X894882D01*
G01Y274705D02*
X924223D01*
G01X894882Y273130D02*
X924223D01*
G01X894882Y273032D02*
X925984D01*
G01X887008D02*
X891732D01*
G01X893701Y271555D02*
X894882D01*
G01X893701Y269803D02*
X925984D01*
G01X893701Y269705D02*
X924223D01*
G01X893701Y268130D02*
X924223D01*
G01X893701Y268032D02*
X925984D01*
G01X893701Y264803D02*
X925984D01*
G01X893701Y264705D02*
X924223D01*
G01X889764Y304705D02*
Y304803D01*
G01Y303032D02*
Y303130D01*
G01D02*
Y304705D01*
G01Y299705D02*
Y299803D01*
G01Y298032D02*
Y298130D01*
G01D02*
Y299705D01*
G01Y294705D02*
Y294803D01*
G01Y293032D02*
Y293130D01*
G01D02*
Y294705D01*
G01Y289705D02*
Y289803D01*
G01Y288032D02*
Y288130D01*
G01D02*
Y289705D01*
G01X886811Y287795D02*
Y285040D01*
G01X893701Y304803D02*
X925984D01*
G01X893701Y304705D02*
X924223D01*
G01X893701Y303130D02*
X924223D01*
G01X893701Y303032D02*
X925984D01*
G01X893701Y299803D02*
X925984D01*
G01X893701Y299705D02*
X924223D01*
G01X893701Y298130D02*
X924223D01*
G01X893701Y298032D02*
X925984D01*
G01X893701Y294803D02*
X925984D01*
G01X893701Y294705D02*
X924223D01*
G01X893701Y293130D02*
X924223D01*
G01X893701Y293032D02*
X925984D01*
G01X893701Y289803D02*
X925984D01*
G01X893701Y289705D02*
X924223D01*
G01X893701Y288130D02*
X924223D01*
G01X893701Y288032D02*
X925984D01*
G01X886811Y287795D02*
X893701D01*
G01Y285040D02*
X886811D01*
G01X893701Y284803D02*
X925984D01*
G01X894882Y311555D02*
Y316280D01*
G01X893701Y314705D02*
Y334508D01*
G01Y314705D02*
Y313130D01*
G01X891732Y314705D02*
Y314803D01*
G01Y313032D02*
Y313130D01*
G01D02*
Y314705D01*
G01X889764Y324705D02*
Y324803D01*
G01Y323130D02*
Y324705D01*
G01Y323032D02*
Y323130D01*
G01Y319705D02*
Y319803D01*
G01Y318130D02*
Y319705D01*
G01Y318032D02*
Y318130D01*
G01Y309705D02*
Y309803D01*
G01Y308032D02*
Y308130D01*
G01D02*
Y309705D01*
G01X886811Y312795D02*
Y310040D01*
G01X893701Y324803D02*
X925984D01*
G01X893701Y324705D02*
X924223D01*
G01X893701Y323130D02*
X924223D01*
G01X893701Y323032D02*
X925984D01*
G01X893701Y319803D02*
X925984D01*
G01X893701Y319705D02*
X924223D01*
G01X893701Y318130D02*
X924223D01*
G01X893701Y318032D02*
X925984D01*
G01X894882Y316280D02*
X893701D01*
G01X891732Y314803D02*
X887008D01*
G01X925984D02*
X894882D01*
G01Y314705D02*
X924223D01*
G01X894882Y313130D02*
X924223D01*
G01X894882Y313032D02*
X925984D01*
G01X887008D02*
X891732D01*
G01X886811Y312795D02*
X893701D01*
G01Y311555D02*
X894882D01*
G01X893701Y310040D02*
X886811D01*
G01X893701Y309803D02*
X925984D01*
G01X893701Y309705D02*
X924223D01*
G01X893701Y308130D02*
X924223D01*
G01X893701Y308032D02*
X925984D01*
G01X888671Y339131D02*
X888788Y338858D01*
G01X888554Y339393D02*
X888671Y339131D01*
G01X888434Y339646D02*
X888554Y339393D01*
G01X888788Y343584D02*
Y343583D01*
G01X888790Y343588D02*
X888788Y343584D01*
G01X888814Y343647D02*
X888790Y343588D01*
G01X888667Y343300D02*
X888788Y343583D01*
G01X888549Y343038D02*
X888667Y343300D01*
G01X888434Y342795D02*
X888549Y343038D01*
G01X888434Y339646D02*
G03Y342795I-2017J1574D01*
G01X888788Y338858D02*
G03Y343583I-2371J2363D01*
G01X889095Y338071D02*
G03Y344370I-2678J3150D01*
G01X888852Y343740D02*
X888814Y343647D01*
G01X888936Y343949D02*
X888852Y343740D01*
G01X888969Y344034D02*
X888936Y343949D01*
G01X889004Y344126D02*
X888969Y344034D01*
G01X889040Y344222D02*
X889004Y344126D01*
G01X889095Y344370D02*
X889040Y344222D01*
G01X905512Y346004D02*
Y358957D01*
G01X894488Y337658D02*
Y346004D01*
G01X889764Y329705D02*
Y329803D01*
G01Y328130D02*
Y329705D01*
G01Y328032D02*
Y328130D01*
G01X885827Y346004D02*
Y358957D01*
G01X889040Y338219D02*
X889095Y338071D01*
G01X889004Y338315D02*
X889040Y338219D01*
G01X888969Y338406D02*
X889004Y338315D01*
G01X888936Y338492D02*
X888969Y338406D01*
G01X888864Y338671D02*
X888936Y338492D01*
G01X888831Y338753D02*
X888864Y338671D01*
G01X888788Y338858D02*
X888831Y338753D01*
G01X905512Y347973D02*
X885827D01*
G01X894488Y344823D02*
X927953D01*
G01X905512Y340610D02*
X894488D01*
G01X893701Y332736D02*
X894980D01*
G01X924803D02*
X896358D01*
G01X925984Y329803D02*
X893701D01*
G01Y329705D02*
X924223D01*
G01X893701Y328130D02*
X924223D01*
G01X893701Y328032D02*
X925984D01*
G01X899409Y353032D02*
G03I-3740J0D01*
G01X905315Y352244D02*
Y353819D01*
G01X899960D02*
Y352244D01*
G01X898622Y353819D02*
Y354016D01*
G01Y352047D02*
Y352244D01*
G01Y353819D02*
Y352244D01*
G01X898425Y353819D02*
Y352244D01*
G01X896850Y353819D02*
Y352244D01*
G01X894488Y353819D02*
Y352244D01*
G01X892913D02*
Y353819D01*
G01X892716D02*
Y354016D01*
G01Y352244D02*
Y353819D01*
G01Y352244D02*
Y352047D01*
G01X891378Y352244D02*
Y353819D01*
G01X886023D02*
Y352244D01*
G01X905512Y358957D02*
X885827D01*
G01X905512Y356988D02*
X885827D01*
G01X905512Y355000D02*
X885827D01*
G01Y354016D02*
X905512D01*
G01X905315Y353819D02*
X886023D01*
G01X905315Y352244D02*
X886023D01*
G01X905512Y352047D02*
X885827D01*
G01Y351063D02*
X905512D01*
G01X898819Y569528D02*
G03Y568347I0J-590D01*
G01Y566772D02*
G03Y565591I0J-591D01*
G01X892519Y568347D02*
G03Y569528I0J590D01*
G01Y565591D02*
G03Y566772I0J591D01*
G01X898901Y568710D02*
X898808Y568599D01*
G01Y568726D02*
X898901Y568837D01*
G01X905512Y579390D02*
Y592343D01*
G01X900393Y565295D02*
Y567264D01*
G01Y569823D02*
Y567854D01*
G01X898901Y568837D02*
Y568710D01*
G01X898819Y569528D02*
Y570118D01*
G01Y566772D02*
Y568347D01*
G01Y565000D02*
Y565591D01*
G01X898808Y569347D02*
Y568726D01*
G01X898714Y568599D02*
Y569347D01*
G01X897834Y570118D02*
Y565000D01*
G01X897638D02*
Y570118D01*
G01X897244Y567854D02*
Y569823D01*
G01Y567264D02*
Y565295D01*
G01X894094Y567854D02*
Y569823D01*
G01Y567264D02*
Y565295D01*
G01X893701Y565000D02*
Y570118D01*
G01X893504D02*
Y565000D01*
G01X892519Y565591D02*
Y565000D01*
G01Y568347D02*
Y566772D01*
G01Y570118D02*
Y569528D01*
G01X890945Y565295D02*
Y567264D01*
G01Y569823D02*
Y567854D01*
G01X885827Y579390D02*
Y592343D01*
G01Y579390D02*
X905512D01*
G01X892519Y570118D02*
X898819D01*
G01Y569823D02*
X900393D01*
G01X897244D02*
X898819D01*
G01X892519D02*
X890945D01*
G01X894094D02*
X892519D01*
G01X898714Y569347D02*
X898808D01*
G01Y568599D02*
X898714D01*
G01X892519Y567854D02*
X894094D01*
G01X890945D02*
X892519D01*
G01X900393D02*
X898819D01*
G01D02*
X897244D01*
G01X892519Y567264D02*
X894094D01*
G01X890945D02*
X892519D01*
G01X900393D02*
X898819D01*
G01D02*
X897244D01*
G01X898819Y565295D02*
X900393D01*
G01X897244D02*
X898819D01*
G01X892519D02*
X890945D01*
G01X894094D02*
X892519D01*
G01Y565000D02*
X898819D01*
G01X899409Y585315D02*
G03I-3740J0D01*
G01X886492Y592993D02*
G03X886417Y601260I-75J4133D01*
G01X905512Y592343D02*
Y751516D01*
G01X905315Y584528D02*
Y586103D01*
G01X899960D02*
Y584528D01*
G01X898622Y586103D02*
Y586299D01*
G01Y584331D02*
Y584528D01*
G01Y586103D02*
Y584528D01*
G01X898425Y586103D02*
Y584528D01*
G01X896850Y586103D02*
Y584528D01*
G01X894488Y592343D02*
Y600689D01*
G01Y586103D02*
Y584528D01*
G01X892913D02*
Y586103D01*
G01X892716D02*
Y586299D01*
G01Y584528D02*
Y586103D01*
G01Y584528D02*
Y584331D01*
G01X891378Y584528D02*
Y586103D01*
G01X886023D02*
Y584528D01*
G01X894488Y597736D02*
X905512D01*
G01X927953Y593524D02*
X894488D01*
G01X885827Y590374D02*
X905512D01*
G01Y587284D02*
X885827D01*
G01Y586299D02*
X905512D01*
G01X905315Y586103D02*
X886023D01*
G01X905315Y584528D02*
X886023D01*
G01X905512Y584331D02*
X885827D01*
G01Y583347D02*
X905512D01*
G01X885827Y581358D02*
X905512D01*
G01X886342Y601260D02*
X886417D01*
G01X886492Y592993D02*
X886417Y592992D01*
G01X897638Y738248D02*
Y605610D01*
G01X896358D02*
Y738248D01*
G01X894980D02*
Y605610D01*
G01X893701Y603839D02*
Y641890D01*
G01X889764Y620217D02*
Y620315D01*
G01Y618642D02*
Y620217D01*
G01Y618543D02*
Y618642D01*
G01Y615217D02*
Y615315D01*
G01Y613642D02*
Y615217D01*
G01Y613543D02*
Y613642D01*
G01Y610217D02*
Y610315D01*
G01Y608642D02*
Y610217D01*
G01Y608543D02*
Y608642D01*
G01X893701Y620315D02*
X925984D01*
G01X893701Y620217D02*
X924223D01*
G01X893701Y618642D02*
X924223D01*
G01X893701Y618543D02*
X925984D01*
G01X893701Y615315D02*
X925984D01*
G01X893701Y615217D02*
X924223D01*
G01X893701Y613642D02*
X924223D01*
G01X893701Y613543D02*
X925984D01*
G01X893701Y610315D02*
X925984D01*
G01X893701Y610217D02*
X924223D01*
G01X893701Y608642D02*
X924223D01*
G01X893701Y608543D02*
X925984D01*
G01X896358Y605610D02*
X924803D01*
G01X893701D02*
X894980D01*
G01X885859Y643740D02*
X885993Y643806D01*
G01X886194Y642920D02*
X886094Y642854D01*
G01X885926Y643576D02*
X886027Y643642D01*
G01X886395Y641443D02*
X886261Y641312D01*
G01X886362Y642854D02*
X886261Y642756D01*
G01X886295Y643051D02*
X886194Y642920D01*
G01X885826Y643445D02*
X885926Y643576D01*
G01X886194Y641509D02*
X886261Y641608D01*
G01X886462Y643018D02*
X886362Y642854D01*
G01X886462Y641575D02*
X886395Y641443D01*
G01X891338Y641791D02*
X888976Y641103D01*
G01X891338Y644941D02*
X888976Y644252D01*
G01X886094Y641477D02*
X886194Y641509D01*
G01X886261Y642756D02*
X886094Y642690D01*
G01X886261Y641608D02*
X886295Y641706D01*
G01X886496D02*
X886462Y641575D01*
G01X886329Y643182D02*
X886300Y643071D01*
G01D02*
X886295Y643051D01*
G01X885792Y643314D02*
X885826Y643445D01*
G01X886496Y643182D02*
X886473Y643071D01*
G01D02*
X886462Y643018D01*
G01X896456Y639725D02*
Y664134D01*
G01X893701Y645040D02*
Y643071D01*
G01D02*
Y641890D01*
G01X891811D02*
Y643071D01*
G01X890236Y641890D02*
Y643071D01*
G01X889764Y640217D02*
Y640315D01*
G01Y638543D02*
Y638642D01*
G01D02*
Y640217D01*
G01Y635217D02*
Y635315D01*
G01Y633543D02*
Y633642D01*
G01D02*
Y635217D01*
G01Y630217D02*
Y630315D01*
G01Y628543D02*
Y628642D01*
G01D02*
Y630217D01*
G01Y625217D02*
Y625315D01*
G01Y623642D02*
Y625217D01*
G01Y623543D02*
Y623642D01*
G01X889449Y643071D02*
Y641890D01*
G01X889055Y643071D02*
Y641890D01*
G01X888976Y643858D02*
Y644252D01*
G01Y640906D02*
Y641103D01*
G01X886811Y633307D02*
Y630551D01*
G01X886496Y641870D02*
Y641706D01*
G01Y643314D02*
Y643182D01*
G01X886329Y643314D02*
Y643182D01*
G01X886295Y641706D02*
Y641890D01*
G01D02*
Y641903D01*
G01X886127Y642100D02*
Y642297D01*
G01X885826Y641890D02*
Y641706D01*
G01Y641903D02*
Y641890D01*
G01X885792Y643182D02*
Y643314D01*
G01X886462Y643478D02*
X886496Y643314D01*
G01X886492Y641890D02*
X886496Y641870D01*
G01X886462Y642034D02*
X886492Y641890D01*
G01X885792Y642067D02*
X885826Y641903D01*
G01X886295Y643445D02*
X886329Y643314D01*
G01X885821Y643071D02*
X885792Y643182D01*
G01X885826Y643051D02*
X885821Y643071D01*
G01X886295Y641903D02*
X886261Y642001D01*
G01X885826Y641706D02*
X885859Y641608D01*
G01X886362Y643642D02*
X886462Y643478D01*
G01X885859Y641608D02*
X885926Y641509D01*
G01X886194Y643576D02*
X886295Y643445D01*
G01X885926Y642920D02*
X885826Y643051D01*
G01X886362Y642166D02*
X886462Y642034D01*
G01X886261Y643740D02*
X886362Y643642D01*
G01X886261Y642001D02*
X886194Y642067D01*
G01X886228Y642264D02*
X886362Y642166D01*
G01X886094Y643642D02*
X886194Y643576D01*
G01X886027Y642854D02*
X885926Y642920D01*
G01X885993Y642690D02*
X885859Y642756D01*
G01X886194Y642067D02*
X886127Y642100D01*
G01X886094Y643806D02*
X886261Y643740D01*
G01X886127Y642297D02*
X886228Y642264D01*
G01X885926Y641509D02*
X886027Y641477D01*
G01X888976Y643858D02*
X891338Y643169D01*
G01X885993Y641280D02*
X885859Y641312D01*
G01X885993Y643806D02*
X886094D01*
G01X886027Y643642D02*
X886094D01*
G01X891338Y643169D02*
X893701D01*
G01X925787D02*
X896456D01*
G01Y643071D02*
X922560D01*
G01X886094Y642854D02*
X886027D01*
G01X886094Y642690D02*
X885993D01*
G01X924016Y642166D02*
X905512D01*
G01X922560Y641890D02*
X896456D01*
G01X891338Y641791D02*
X893701D01*
G01X925787D02*
X896456D01*
G01X886027Y641477D02*
X886094D01*
G01X886127Y641280D02*
X885993D01*
G01X923031Y640315D02*
X893701D01*
G01Y640217D02*
X924102D01*
G01X893701Y639725D02*
X925984D01*
G01X924102Y638642D02*
X893701D01*
G01Y638543D02*
X923031D01*
G01X925984Y635315D02*
X893701D01*
G01Y635217D02*
X924223D01*
G01X893701Y633642D02*
X924223D01*
G01X893701Y633543D02*
X925984D01*
G01X886811Y633307D02*
X893701D01*
G01Y630551D02*
X886811D01*
G01X893701Y630315D02*
X925984D01*
G01X893701Y630217D02*
X924223D01*
G01X893701Y628642D02*
X924223D01*
G01X893701Y628543D02*
X925984D01*
G01X893701Y625315D02*
X925984D01*
G01X893701Y625217D02*
X924223D01*
G01X893701Y623642D02*
X924223D01*
G01X893701Y623543D02*
X925984D01*
G01X886261Y641312D02*
X886127Y641280D01*
G01X891338Y648091D02*
X888976Y647402D01*
G01X891338Y651240D02*
X888976Y650551D01*
G01X891338Y654390D02*
X888976Y653701D01*
G01X891338Y657540D02*
X888976Y656851D01*
G01X891338Y660689D02*
X888976Y660000D01*
G01X893701Y661969D02*
Y678642D01*
G01Y646221D02*
Y645040D01*
G01Y648189D02*
Y646221D01*
G01Y651339D02*
Y649370D01*
G01D02*
Y648189D01*
G01Y654488D02*
Y652520D01*
G01D02*
Y651339D01*
G01Y655669D02*
Y654488D01*
G01Y657638D02*
Y655669D01*
G01Y660788D02*
Y658819D01*
G01D02*
Y657638D01*
G01Y661969D02*
Y660788D01*
G01X891811D02*
Y661969D01*
G01Y657638D02*
Y658819D01*
G01Y654488D02*
Y655669D01*
G01Y651339D02*
Y652520D01*
G01Y648189D02*
Y649370D01*
G01Y645040D02*
Y646221D01*
G01X890236Y660788D02*
Y661969D01*
G01Y657638D02*
Y658819D01*
G01Y654488D02*
Y655669D01*
G01Y651339D02*
Y652520D01*
G01Y648189D02*
Y649370D01*
G01Y645040D02*
Y646221D01*
G01X889764Y665217D02*
Y665315D01*
G01Y663543D02*
Y663642D01*
G01D02*
Y665217D01*
G01X889449Y646221D02*
Y645040D01*
G01Y649370D02*
Y648189D01*
G01Y652520D02*
Y651339D01*
G01Y655669D02*
Y654488D01*
G01Y658819D02*
Y657638D01*
G01Y661969D02*
Y660788D01*
G01X889055Y646221D02*
Y645040D01*
G01Y649370D02*
Y648189D01*
G01Y655669D02*
Y654488D01*
G01Y652520D02*
Y651339D01*
G01Y658819D02*
Y657638D01*
G01Y661969D02*
Y660788D01*
G01X888976Y662756D02*
Y662953D01*
G01Y656457D02*
Y656851D01*
G01Y659606D02*
Y660000D01*
G01Y653307D02*
Y653701D01*
G01Y647008D02*
Y647402D01*
G01Y650158D02*
Y650551D01*
G01Y662756D02*
X891338Y662067D01*
G01X888976Y659606D02*
X891338Y658917D01*
G01X888976Y656457D02*
X891338Y655768D01*
G01X888976Y653307D02*
X891338Y652618D01*
G01X888976Y650158D02*
X891338Y649469D01*
G01X888976Y647008D02*
X891338Y646319D01*
G01X893701Y665315D02*
X923031D01*
G01X893701Y665217D02*
X924102D01*
G01X893701Y664134D02*
X925984D01*
G01X893701Y663642D02*
X924102D01*
G01X893701Y663543D02*
X923031D01*
G01X896456Y662067D02*
X925787D01*
G01X891338D02*
X893701D01*
G01X896456Y661969D02*
X922560D01*
G01X905512Y661693D02*
X924016D01*
G01X922560Y660788D02*
X896456D01*
G01Y660689D02*
X925787D01*
G01X891338D02*
X893701D01*
G01X896456Y658917D02*
X925787D01*
G01X891338D02*
X893701D01*
G01X896456Y658819D02*
X922560D01*
G01Y657638D02*
X896456D01*
G01Y657540D02*
X925787D01*
G01X891338D02*
X893701D01*
G01X896456Y655768D02*
X925787D01*
G01X891338D02*
X893701D01*
G01X896456Y655669D02*
X922560D01*
G01Y654488D02*
X896456D01*
G01Y654390D02*
X925787D01*
G01X891338D02*
X893701D01*
G01X896456Y652618D02*
X925787D01*
G01X891338D02*
X893701D01*
G01X896456Y652520D02*
X922560D01*
G01Y651339D02*
X896456D01*
G01Y651240D02*
X925787D01*
G01X891338D02*
X893701D01*
G01X896456Y649469D02*
X925787D01*
G01X891338D02*
X893701D01*
G01X896456Y649370D02*
X922560D01*
G01Y648189D02*
X896456D01*
G01Y648091D02*
X925787D01*
G01X891338D02*
X893701D01*
G01X896456Y646319D02*
X925787D01*
G01X891338D02*
X893701D01*
G01X896456Y646221D02*
X922560D01*
G01Y645040D02*
X896456D01*
G01Y644941D02*
X925787D01*
G01X891338D02*
X893701D01*
G01X894882Y677067D02*
Y681791D01*
G01X893701Y680217D02*
Y718642D01*
G01Y680217D02*
Y678642D01*
G01X891732Y680217D02*
Y680315D01*
G01Y678642D02*
Y680217D01*
G01Y678543D02*
Y678642D01*
G01X889764Y685217D02*
Y685315D01*
G01Y683642D02*
Y685217D01*
G01Y683543D02*
Y683642D01*
G01Y675217D02*
Y675315D01*
G01Y673543D02*
Y673642D01*
G01D02*
Y675217D01*
G01Y670217D02*
Y670315D01*
G01Y668543D02*
Y668642D01*
G01D02*
Y670217D01*
G01X886811Y668307D02*
Y665551D01*
G01X893701Y685315D02*
X925984D01*
G01X893701Y685217D02*
X924223D01*
G01X893701Y683642D02*
X924223D01*
G01X893701Y683543D02*
X925984D01*
G01X894882Y681791D02*
X893701D01*
G01X891732Y680315D02*
X887008D01*
G01X925984D02*
X894882D01*
G01Y680217D02*
X924223D01*
G01X894882Y678642D02*
X924223D01*
G01X894882Y678543D02*
X925984D01*
G01X887008D02*
X891732D01*
G01X893701Y677067D02*
X894882D01*
G01X893701Y675315D02*
X925984D01*
G01X893701Y675217D02*
X924223D01*
G01X893701Y673642D02*
X924223D01*
G01X893701Y673543D02*
X925984D01*
G01X893701Y670315D02*
X925984D01*
G01X893701Y670217D02*
X924223D01*
G01Y668642D02*
X893701D01*
G01Y668543D02*
X925984D01*
G01X886811Y668307D02*
X893701D01*
G01Y665551D02*
X886811D01*
G01X889764Y705217D02*
Y705315D01*
G01Y703543D02*
Y703642D01*
G01D02*
Y705217D01*
G01Y700217D02*
Y700315D01*
G01Y698642D02*
Y700217D01*
G01Y698543D02*
Y698642D01*
G01Y695217D02*
Y695315D01*
G01Y693642D02*
Y695217D01*
G01Y693543D02*
Y693642D01*
G01Y690217D02*
Y690315D01*
G01Y688642D02*
Y690217D01*
G01Y688543D02*
Y688642D01*
G01X886811Y693307D02*
Y690551D01*
G01X893701Y705315D02*
X925984D01*
G01X893701Y705217D02*
X924223D01*
G01X893701Y703642D02*
X924223D01*
G01X893701Y703543D02*
X925984D01*
G01X893701Y700315D02*
X925984D01*
G01X893701Y700217D02*
X924223D01*
G01X893701Y698642D02*
X924223D01*
G01X893701Y698543D02*
X925984D01*
G01X893701Y695315D02*
X925984D01*
G01X893701Y695217D02*
X924223D01*
G01X893701Y693642D02*
X924223D01*
G01X893701Y693543D02*
X925984D01*
G01X886811Y693307D02*
X893701D01*
G01Y690551D02*
X886811D01*
G01X893701Y690315D02*
X925984D01*
G01X893701Y690217D02*
X924223D01*
G01X893701Y688642D02*
X924223D01*
G01X893701Y688543D02*
X925984D01*
G01X894882Y717067D02*
Y721791D01*
G01X893701Y720217D02*
Y740020D01*
G01Y720217D02*
Y718642D01*
G01X891732Y720217D02*
Y720315D01*
G01Y718543D02*
Y718642D01*
G01D02*
Y720217D01*
G01X889764Y728543D02*
Y728642D01*
G01D02*
Y730217D01*
G01Y725217D02*
Y725315D01*
G01Y723543D02*
Y723642D01*
G01D02*
Y725217D01*
G01Y715217D02*
Y715315D01*
G01Y713543D02*
Y713642D01*
G01D02*
Y715217D01*
G01Y710217D02*
Y710315D01*
G01Y708543D02*
Y708642D01*
G01D02*
Y710217D01*
G01X886811Y718307D02*
Y715551D01*
G01X893701Y728642D02*
X924223D01*
G01X893701Y728543D02*
X925984D01*
G01X893701Y725315D02*
X925984D01*
G01X893701Y725217D02*
X924223D01*
G01X893701Y723642D02*
X924223D01*
G01X893701Y723543D02*
X925984D01*
G01X894882Y721791D02*
X893701D01*
G01X891732Y720315D02*
X887008D01*
G01X925984D02*
X894882D01*
G01Y720217D02*
X924223D01*
G01X894882Y718642D02*
X924223D01*
G01X894882Y718543D02*
X925984D01*
G01X887008D02*
X891732D01*
G01X886811Y718307D02*
X893701D01*
G01Y717067D02*
X894882D01*
G01X893701Y715551D02*
X886811D01*
G01X893701Y715315D02*
X925984D01*
G01X893701Y715217D02*
X924223D01*
G01X893701Y713642D02*
X924223D01*
G01X893701Y713543D02*
X925984D01*
G01X893701Y710315D02*
X925984D01*
G01X893701Y710217D02*
X924223D01*
G01X893701Y708642D02*
X924223D01*
G01X893701Y708543D02*
X925984D01*
G01X888671Y744643D02*
X888788Y744370D01*
G01X888554Y744905D02*
X888671Y744643D01*
G01X888434Y745158D02*
X888554Y744905D01*
G01X888788Y749096D02*
Y749095D01*
G01X888790Y749100D02*
X888788Y749096D01*
G01X888814Y749158D02*
X888790Y749100D01*
G01X888667Y748812D02*
X888788Y749095D01*
G01X888549Y748549D02*
X888667Y748812D01*
G01X888434Y748307D02*
X888549Y748549D01*
G01X888434Y745158D02*
G03Y748307I-2017J1574D01*
G01X888788Y744370D02*
G03Y749095I-2371J2363D01*
G01X889095Y743583D02*
G03Y749882I-2678J3149D01*
G01X888852Y749252D02*
X888814Y749158D01*
G01X888936Y749460D02*
X888852Y749252D01*
G01X888969Y749546D02*
X888936Y749460D01*
G01X889004Y749638D02*
X888969Y749546D01*
G01X889040Y749734D02*
X889004Y749638D01*
G01X889095Y749882D02*
X889040Y749734D01*
G01X894488Y743169D02*
Y751516D01*
G01X889764Y735217D02*
Y735315D01*
G01Y733543D02*
Y733642D01*
G01D02*
Y735217D01*
G01Y730217D02*
Y730315D01*
G01X889040Y743731D02*
X889095Y743583D01*
G01X889004Y743827D02*
X889040Y743731D01*
G01X888969Y743918D02*
X889004Y743827D01*
G01X888936Y744004D02*
X888969Y743918D01*
G01X888864Y744183D02*
X888936Y744004D01*
G01X888831Y744264D02*
X888864Y744183D01*
G01X888788Y744370D02*
X888831Y744264D01*
G01X905512Y746122D02*
X894488D01*
G01X893701Y738248D02*
X894980D01*
G01X924803D02*
X896358D01*
G01X925984Y735315D02*
X893701D01*
G01Y735217D02*
X924223D01*
G01X893701Y733642D02*
X924223D01*
G01X893701Y733543D02*
X925984D01*
G01X893701Y730315D02*
X925984D01*
G01X893701Y730217D02*
X924223D01*
G01X899409Y758543D02*
G03I-3740J0D01*
G01X905512Y751516D02*
Y764469D01*
G01X905315Y757756D02*
Y759331D01*
G01X899960D02*
Y757756D01*
G01X898622Y757559D02*
Y757756D01*
G01Y759331D02*
Y759528D01*
G01Y759331D02*
Y757756D01*
G01X898425Y759331D02*
Y757756D01*
G01X896850Y759331D02*
Y757756D01*
G01X894488Y759331D02*
Y757756D01*
G01X892913D02*
Y759331D01*
G01X892716D02*
Y759528D01*
G01Y757756D02*
Y759331D01*
G01Y757756D02*
Y757559D01*
G01X891378Y757756D02*
Y759331D01*
G01X886023D02*
Y757756D01*
G01X885827Y751516D02*
Y764469D01*
G01X905512D02*
X885827D01*
G01X905512Y762500D02*
X885827D01*
G01X905512Y760512D02*
X885827D01*
G01Y759528D02*
X905512D01*
G01X905315Y759331D02*
X886023D01*
G01X905315Y757756D02*
X886023D01*
G01X905512Y757559D02*
X885827D01*
G01Y756575D02*
X905512D01*
G01Y753484D02*
X885827D01*
G01X894488Y750335D02*
X927953D01*
G01X898819Y975040D02*
G03Y973858I0J-591D01*
G01Y972284D02*
G03Y971103I0J-591D01*
G01X892519Y973858D02*
G03Y975040I0J591D01*
G01Y971103D02*
G03Y972284I0J590D01*
G01X900393Y970807D02*
Y972776D01*
G01Y975335D02*
Y973366D01*
G01X898901Y974349D02*
Y974222D01*
G01X898819Y975040D02*
Y975630D01*
G01Y972284D02*
Y973858D01*
G01Y970512D02*
Y971103D01*
G01X898808Y974858D02*
Y974238D01*
G01X898714Y974110D02*
Y974858D01*
G01X897834Y975630D02*
Y970512D01*
G01X897638D02*
Y975630D01*
G01X897244Y973366D02*
Y975335D01*
G01Y972776D02*
Y970807D01*
G01X894094Y973366D02*
Y975335D01*
G01Y972776D02*
Y970807D01*
G01X893701Y970512D02*
Y975630D01*
G01X893504D02*
Y970512D01*
G01X892519Y973858D02*
Y972284D01*
G01Y971103D02*
Y970512D01*
G01Y975630D02*
Y975040D01*
G01X890945Y970807D02*
Y972776D01*
G01Y975335D02*
Y973366D01*
G01X898901Y974222D02*
X898808Y974110D01*
G01Y974238D02*
X898901Y974349D01*
G01X892519Y975630D02*
X898819D01*
G01Y975335D02*
X900393D01*
G01X897244D02*
X898819D01*
G01X892519D02*
X890945D01*
G01X894094D02*
X892519D01*
G01X898714Y974858D02*
X898808D01*
G01Y974110D02*
X898714D01*
G01X892519Y973366D02*
X894094D01*
G01X890945D02*
X892519D01*
G01X900393D02*
X898819D01*
G01D02*
X897244D01*
G01X892519Y972776D02*
X894094D01*
G01X890945D02*
X892519D01*
G01X900393D02*
X898819D01*
G01D02*
X897244D01*
G01X898819Y970807D02*
X900393D01*
G01X897244D02*
X898819D01*
G01X892519D02*
X890945D01*
G01X894094D02*
X892519D01*
G01Y970512D02*
X898819D01*
G01X886492Y998504D02*
G03X886417Y1006772I-75J4134D01*
G01X899409Y990827D02*
G03I-3740J0D01*
G01X905512Y997854D02*
Y1157028D01*
G01Y984902D02*
Y997854D01*
G01X905315Y990040D02*
Y991614D01*
G01X899960D02*
Y990040D01*
G01X898622Y991614D02*
Y991811D01*
G01Y989843D02*
Y990040D01*
G01Y991614D02*
Y990040D01*
G01X898425Y991614D02*
Y990040D01*
G01X896850Y991614D02*
Y990040D01*
G01X894488Y997854D02*
Y1006201D01*
G01Y991614D02*
Y990040D01*
G01X892913D02*
Y991614D01*
G01X892716D02*
Y991811D01*
G01Y990040D02*
Y991614D01*
G01Y990040D02*
Y989843D01*
G01X891378Y990040D02*
Y991614D01*
G01X886023D02*
Y990040D01*
G01X885827Y984902D02*
Y997854D01*
G01X894488Y1003248D02*
X905512D01*
G01X927953Y999036D02*
X894488D01*
G01X885827Y995886D02*
X905512D01*
G01Y992795D02*
X885827D01*
G01Y991811D02*
X905512D01*
G01X905315Y991614D02*
X886023D01*
G01X905315Y990040D02*
X886023D01*
G01X905512Y989843D02*
X885827D01*
G01Y988858D02*
X905512D01*
G01X885827Y986870D02*
X905512D01*
G01X885827Y984902D02*
X905512D01*
G01X886492Y998504D02*
X886417D01*
G01X897638Y1143760D02*
Y1011122D01*
G01X896358D02*
Y1143760D01*
G01X894980D02*
Y1011122D01*
G01X893701Y1009351D02*
Y1047402D01*
G01X889764Y1024055D02*
Y1024154D01*
G01D02*
Y1025728D01*
G01Y1020728D02*
Y1020827D01*
G01Y1019055D02*
Y1019154D01*
G01D02*
Y1020728D01*
G01Y1015728D02*
Y1015827D01*
G01Y1014055D02*
Y1014154D01*
G01D02*
Y1015728D01*
G01X893701Y1024154D02*
X924223D01*
G01X893701Y1024055D02*
X925984D01*
G01X893701Y1020827D02*
X925984D01*
G01X893701Y1020728D02*
X924223D01*
G01X893701Y1019154D02*
X924223D01*
G01X893701Y1019055D02*
X925984D01*
G01X893701Y1015827D02*
X925984D01*
G01X893701Y1015728D02*
X924223D01*
G01X893701Y1014154D02*
X924223D01*
G01X893701Y1014055D02*
X925984D01*
G01X896358Y1011122D02*
X924803D01*
G01X893701D02*
X894980D01*
G01X886342Y1006771D02*
X886417D01*
G01X896456Y1045236D02*
Y1069646D01*
G01X889764Y1045728D02*
Y1045827D01*
G01Y1044154D02*
Y1045728D01*
G01Y1044055D02*
Y1044154D01*
G01Y1040728D02*
Y1040827D01*
G01Y1039154D02*
Y1040728D01*
G01Y1039055D02*
Y1039154D01*
G01Y1035728D02*
Y1035827D01*
G01Y1034055D02*
Y1034154D01*
G01D02*
Y1035728D01*
G01Y1030728D02*
Y1030827D01*
G01Y1029055D02*
Y1029154D01*
G01D02*
Y1030728D01*
G01Y1025728D02*
Y1025827D01*
G01X886811Y1038819D02*
Y1036063D01*
G01X923031Y1045827D02*
X893701D01*
G01Y1045728D02*
X924102D01*
G01X893701Y1045236D02*
X925984D01*
G01X924102Y1044154D02*
X893701D01*
G01Y1044055D02*
X923031D01*
G01X925984Y1040827D02*
X893701D01*
G01Y1040728D02*
X924223D01*
G01X893701Y1039154D02*
X924223D01*
G01X893701Y1039055D02*
X925984D01*
G01X886811Y1038819D02*
X893701D01*
G01Y1036063D02*
X886811D01*
G01X893701Y1035827D02*
X925984D01*
G01X893701Y1035728D02*
X924223D01*
G01X893701Y1034154D02*
X924223D01*
G01X893701Y1034055D02*
X925984D01*
G01X893701Y1030827D02*
X925984D01*
G01X893701Y1030728D02*
X924223D01*
G01X893701Y1029154D02*
X924223D01*
G01X893701Y1029055D02*
X925984D01*
G01X893701Y1025827D02*
X925984D01*
G01X893701Y1025728D02*
X924223D01*
G01X886462Y1048990D02*
X886496Y1048825D01*
G01X886492Y1047402D02*
X886496Y1047382D01*
G01X886462Y1047546D02*
X886492Y1047402D01*
G01X885792Y1047579D02*
X885826Y1047415D01*
G01X886295Y1048957D02*
X886329Y1048825D01*
G01X885821Y1048583D02*
X885792Y1048694D01*
G01X885826Y1048563D02*
X885821Y1048583D01*
G01X886295Y1047415D02*
X886261Y1047513D01*
G01X885826Y1047218D02*
X885859Y1047119D01*
G01X886362Y1049154D02*
X886462Y1048990D01*
G01X885859Y1047119D02*
X885926Y1047021D01*
G01X886194Y1049088D02*
X886295Y1048957D01*
G01X885926Y1048432D02*
X885826Y1048563D01*
G01X886362Y1047677D02*
X886462Y1047546D01*
G01X886261Y1047119D02*
X886295Y1047218D01*
G01X886496D02*
X886462Y1047087D01*
G01X886329Y1048694D02*
X886300Y1048583D01*
G01D02*
X886295Y1048563D01*
G01X885792Y1048825D02*
X885826Y1048957D01*
G01X886496Y1048694D02*
X886473Y1048583D01*
G01D02*
X886462Y1048530D01*
G01X893701Y1048583D02*
Y1047402D01*
G01Y1050551D02*
Y1048583D01*
G01Y1053701D02*
Y1051732D01*
G01D02*
Y1050551D01*
G01Y1056851D02*
Y1054882D01*
G01D02*
Y1053701D01*
G01Y1058032D02*
Y1056851D01*
G01Y1060000D02*
Y1058032D01*
G01Y1063150D02*
Y1061181D01*
G01D02*
Y1060000D01*
G01Y1066299D02*
Y1064331D01*
G01D02*
Y1063150D01*
G01Y1067480D02*
Y1066299D01*
G01X891811D02*
Y1067480D01*
G01Y1063150D02*
Y1064331D01*
G01Y1060000D02*
Y1061181D01*
G01Y1053701D02*
Y1054882D01*
G01Y1056851D02*
Y1058032D01*
G01Y1050551D02*
Y1051732D01*
G01Y1047402D02*
Y1048583D01*
G01X890236Y1066299D02*
Y1067480D01*
G01Y1063150D02*
Y1064331D01*
G01Y1060000D02*
Y1061181D01*
G01Y1056851D02*
Y1058032D01*
G01Y1053701D02*
Y1054882D01*
G01Y1050551D02*
Y1051732D01*
G01Y1047402D02*
Y1048583D01*
G01X889449D02*
Y1047402D01*
G01Y1051732D02*
Y1050551D01*
G01Y1054882D02*
Y1053701D01*
G01Y1058032D02*
Y1056851D01*
G01Y1061181D02*
Y1060000D01*
G01Y1064331D02*
Y1063150D01*
G01Y1067480D02*
Y1066299D01*
G01X889055Y1048583D02*
Y1047402D01*
G01Y1051732D02*
Y1050551D01*
G01Y1054882D02*
Y1053701D01*
G01Y1058032D02*
Y1056851D01*
G01Y1061181D02*
Y1060000D01*
G01Y1067480D02*
Y1066299D01*
G01Y1064331D02*
Y1063150D01*
G01X888976Y1065118D02*
Y1065512D01*
G01Y1061969D02*
Y1062362D01*
G01Y1055669D02*
Y1056063D01*
G01Y1058819D02*
Y1059213D01*
G01Y1052520D02*
Y1052914D01*
G01Y1046417D02*
Y1046614D01*
G01Y1049370D02*
Y1049764D01*
G01X886496Y1048825D02*
Y1048694D01*
G01Y1047382D02*
Y1047218D01*
G01X886329Y1048825D02*
Y1048694D01*
G01X886295Y1047218D02*
Y1047402D01*
G01D02*
Y1047415D01*
G01X886127Y1047612D02*
Y1047808D01*
G01X885826Y1047402D02*
Y1047218D01*
G01Y1047415D02*
Y1047402D01*
G01X885792Y1048694D02*
Y1048825D01*
G01X886261Y1049252D02*
X886362Y1049154D01*
G01X886261Y1047513D02*
X886194Y1047579D01*
G01X886228Y1047776D02*
X886362Y1047677D01*
G01X886094Y1049154D02*
X886194Y1049088D01*
G01X886027Y1048366D02*
X885926Y1048432D01*
G01X886295Y1048563D02*
X886194Y1048432D01*
G01X885826Y1048957D02*
X885926Y1049088D01*
G01X886194Y1047021D02*
X886261Y1047119D01*
G01X886462Y1048530D02*
X886362Y1048366D01*
G01X886462Y1047087D02*
X886395Y1046955D01*
G01X885993Y1048202D02*
X885859Y1048268D01*
G01X886194Y1047579D02*
X886127Y1047612D01*
G01X886094Y1049317D02*
X886261Y1049252D01*
G01X886127Y1047808D02*
X886228Y1047776D01*
G01X888976Y1065118D02*
X891338Y1064429D01*
G01X888976Y1061969D02*
X891338Y1061280D01*
G01X888976Y1058819D02*
X891338Y1058130D01*
G01X886395Y1046955D02*
X886261Y1046824D01*
G01X886362Y1048366D02*
X886261Y1048268D01*
G01X885926Y1047021D02*
X886027Y1046988D01*
G01X888976Y1055669D02*
X891338Y1054980D01*
G01X888976Y1052520D02*
X891338Y1051831D01*
G01X888976Y1049370D02*
X891338Y1048681D01*
G01X885993Y1046791D02*
X885859Y1046824D01*
G01Y1049252D02*
X885993Y1049317D01*
G01X886194Y1048432D02*
X886094Y1048366D01*
G01X885926Y1049088D02*
X886027Y1049154D01*
G01X905512Y1067205D02*
X924016D01*
G01X922560Y1066299D02*
X896456D01*
G01Y1066201D02*
X925787D01*
G01X891338D02*
X893701D01*
G01X896456Y1064429D02*
X925787D01*
G01X891338D02*
X893701D01*
G01X896456Y1064331D02*
X922560D01*
G01Y1063150D02*
X896456D01*
G01Y1063051D02*
X925787D01*
G01X891338D02*
X893701D01*
G01X896456Y1061280D02*
X925787D01*
G01X891338D02*
X893701D01*
G01X896456Y1061181D02*
X922560D01*
G01Y1060000D02*
X896456D01*
G01Y1059902D02*
X925787D01*
G01X891338D02*
X893701D01*
G01X896456Y1058130D02*
X925787D01*
G01X891338D02*
X893701D01*
G01X896456Y1058032D02*
X922560D01*
G01Y1056851D02*
X896456D01*
G01Y1056752D02*
X925787D01*
G01X891338D02*
X893701D01*
G01X896456Y1054980D02*
X925787D01*
G01X891338D02*
X893701D01*
G01X896456Y1054882D02*
X922560D01*
G01Y1053701D02*
X896456D01*
G01Y1053603D02*
X925787D01*
G01X891338D02*
X893701D01*
G01X896456Y1051831D02*
X925787D01*
G01X891338D02*
X893701D01*
G01X896456Y1051732D02*
X922560D01*
G01Y1050551D02*
X896456D01*
G01Y1050453D02*
X925787D01*
G01X891338D02*
X893701D01*
G01X885993Y1049317D02*
X886094D01*
G01X886027Y1049154D02*
X886094D01*
G01X891338Y1048681D02*
X893701D01*
G01X925787D02*
X896456D01*
G01Y1048583D02*
X922560D01*
G01X886094Y1048366D02*
X886027D01*
G01X886094Y1048202D02*
X885993D01*
G01X924016Y1047677D02*
X905512D01*
G01X922560Y1047402D02*
X896456D01*
G01X891338Y1047303D02*
X893701D01*
G01X925787D02*
X896456D01*
G01X886027Y1046988D02*
X886094D01*
G01X886127Y1046791D02*
X885993D01*
G01X891338Y1047303D02*
X888976Y1046614D01*
G01X891338Y1050453D02*
X888976Y1049764D01*
G01X891338Y1053603D02*
X888976Y1052914D01*
G01X891338Y1056752D02*
X888976Y1056063D01*
G01X891338Y1059902D02*
X888976Y1059213D01*
G01X891338Y1063051D02*
X888976Y1062362D01*
G01X891338Y1066201D02*
X888976Y1065512D01*
G01X886094Y1046988D02*
X886194Y1047021D01*
G01X886261Y1048268D02*
X886094Y1048202D01*
G01X886261Y1046824D02*
X886127Y1046791D01*
G01X894882Y1082579D02*
Y1087303D01*
G01X893701Y1085728D02*
Y1124154D01*
G01Y1067480D02*
Y1084154D01*
G01Y1085728D02*
Y1084154D01*
G01X891732Y1085728D02*
Y1085827D01*
G01Y1084055D02*
Y1084154D01*
G01D02*
Y1085728D01*
G01X889764Y1080728D02*
Y1080827D01*
G01Y1079055D02*
Y1079154D01*
G01D02*
Y1080728D01*
G01Y1075728D02*
Y1075827D01*
G01Y1074055D02*
Y1074154D01*
G01D02*
Y1075728D01*
G01Y1070728D02*
Y1070827D01*
G01Y1069055D02*
Y1069154D01*
G01D02*
Y1070728D01*
G01X888976Y1068268D02*
Y1068465D01*
G01X886811Y1073819D02*
Y1071063D01*
G01X888976Y1068268D02*
X891338Y1067579D01*
G01X894882Y1087303D02*
X893701D01*
G01X891732Y1085827D02*
X887008D01*
G01X925984D02*
X894882D01*
G01Y1085728D02*
X924223D01*
G01X894882Y1084154D02*
X924223D01*
G01X894882Y1084055D02*
X925984D01*
G01X887008D02*
X891732D01*
G01X893701Y1082579D02*
X894882D01*
G01X893701Y1080827D02*
X925984D01*
G01X893701Y1080728D02*
X924223D01*
G01X893701Y1079154D02*
X924223D01*
G01X893701Y1079055D02*
X925984D01*
G01X893701Y1075827D02*
X925984D01*
G01X893701Y1075728D02*
X924223D01*
G01Y1074154D02*
X893701D01*
G01Y1074055D02*
X925984D01*
G01X886811Y1073819D02*
X893701D01*
G01Y1071063D02*
X886811D01*
G01X893701Y1070827D02*
X923031D01*
G01X893701Y1070728D02*
X924102D01*
G01X893701Y1069646D02*
X925984D01*
G01X893701Y1069154D02*
X924102D01*
G01X893701Y1069055D02*
X923031D01*
G01X896456Y1067579D02*
X925787D01*
G01X891338D02*
X893701D01*
G01X896456Y1067480D02*
X922560D01*
G01X889764Y1109055D02*
Y1109154D01*
G01D02*
Y1110728D01*
G01Y1105728D02*
Y1105827D01*
G01Y1104055D02*
Y1104154D01*
G01D02*
Y1105728D01*
G01Y1100728D02*
Y1100827D01*
G01Y1099055D02*
Y1099154D01*
G01D02*
Y1100728D01*
G01Y1095728D02*
Y1095827D01*
G01Y1094055D02*
Y1094154D01*
G01D02*
Y1095728D01*
G01Y1090728D02*
Y1090827D01*
G01Y1089055D02*
Y1089154D01*
G01D02*
Y1090728D01*
G01X886811Y1098819D02*
Y1096063D01*
G01X893701Y1109154D02*
X924223D01*
G01X893701Y1109055D02*
X925984D01*
G01X893701Y1105827D02*
X925984D01*
G01X893701Y1105728D02*
X924223D01*
G01X893701Y1104154D02*
X924223D01*
G01X893701Y1104055D02*
X925984D01*
G01X893701Y1100827D02*
X925984D01*
G01X893701Y1100728D02*
X924223D01*
G01X893701Y1099154D02*
X924223D01*
G01X893701Y1099055D02*
X925984D01*
G01X886811Y1098819D02*
X893701D01*
G01Y1096063D02*
X886811D01*
G01X893701Y1095827D02*
X925984D01*
G01X893701Y1095728D02*
X924223D01*
G01X893701Y1094154D02*
X924223D01*
G01X893701Y1094055D02*
X925984D01*
G01X893701Y1090827D02*
X925984D01*
G01X893701Y1090728D02*
X924223D01*
G01X893701Y1089154D02*
X924223D01*
G01X893701Y1089055D02*
X925984D01*
G01X894882Y1122579D02*
Y1127303D01*
G01X893701Y1125728D02*
Y1145532D01*
G01Y1125728D02*
Y1124154D01*
G01X891732Y1125728D02*
Y1125827D01*
G01Y1124154D02*
Y1125728D01*
G01Y1124055D02*
Y1124154D01*
G01X889764Y1130728D02*
Y1130827D01*
G01Y1129154D02*
Y1130728D01*
G01Y1129055D02*
Y1129154D01*
G01Y1120728D02*
Y1120827D01*
G01Y1119154D02*
Y1120728D01*
G01Y1119055D02*
Y1119154D01*
G01Y1115728D02*
Y1115827D01*
G01Y1114154D02*
Y1115728D01*
G01Y1114055D02*
Y1114154D01*
G01Y1110728D02*
Y1110827D01*
G01X886811Y1123819D02*
Y1121063D01*
G01X893701Y1130728D02*
X924223D01*
G01X893701Y1129154D02*
X924223D01*
G01X893701Y1129055D02*
X925984D01*
G01X894882Y1127303D02*
X893701D01*
G01X891732Y1125827D02*
X887008D01*
G01X925984D02*
X894882D01*
G01Y1125728D02*
X924223D01*
G01X894882Y1124154D02*
X924223D01*
G01X894882Y1124055D02*
X925984D01*
G01X887008D02*
X891732D01*
G01X886811Y1123819D02*
X893701D01*
G01Y1122579D02*
X894882D01*
G01X893701Y1121063D02*
X886811D01*
G01X893701Y1120827D02*
X925984D01*
G01X893701Y1120728D02*
X924223D01*
G01X893701Y1119154D02*
X924223D01*
G01X893701Y1119055D02*
X925984D01*
G01X893701Y1115827D02*
X925984D01*
G01X893701Y1115728D02*
X924223D01*
G01X893701Y1114154D02*
X924223D01*
G01X893701Y1114055D02*
X925984D01*
G01X893701Y1110827D02*
X925984D01*
G01X893701Y1110728D02*
X924223D01*
G01X888671Y1150154D02*
X888788Y1149882D01*
G01X888554Y1150417D02*
X888671Y1150154D01*
G01X888434Y1150669D02*
X888554Y1150417D01*
G01X888434Y1150669D02*
G03Y1153819I-2017J1575D01*
G01X888788Y1149882D02*
G03Y1154606I-2371J2362D01*
G01X889095Y1149095D02*
G03Y1155394I-2678J3149D01*
G01X889040Y1149243D02*
X889095Y1149095D01*
G01X889004Y1149338D02*
X889040Y1149243D01*
G01X888969Y1149430D02*
X889004Y1149338D01*
G01X888936Y1149516D02*
X888969Y1149430D01*
G01X888864Y1149695D02*
X888936Y1149516D01*
G01X888831Y1149776D02*
X888864Y1149695D01*
G01X888788Y1149882D02*
X888831Y1149776D01*
G01X894488Y1148681D02*
Y1157028D01*
G01X889764Y1140728D02*
Y1140827D01*
G01Y1139055D02*
Y1139154D01*
G01D02*
Y1140728D01*
G01Y1135728D02*
Y1135827D01*
G01Y1134154D02*
Y1135728D01*
G01Y1134055D02*
Y1134154D01*
G01X905512Y1151634D02*
X894488D01*
G01X893701Y1143760D02*
X894980D01*
G01X924803D02*
X896358D01*
G01X925984Y1140827D02*
X893701D01*
G01Y1140728D02*
X924223D01*
G01X893701Y1139154D02*
X924223D01*
G01X893701Y1139055D02*
X925984D01*
G01X893701Y1135827D02*
X925984D01*
G01X893701Y1135728D02*
X924223D01*
G01X893701Y1134154D02*
X924223D01*
G01X893701Y1134055D02*
X925984D01*
G01X893701Y1130827D02*
X925984D01*
G01X888788Y1154608D02*
Y1154606D01*
G01X888801Y1154639D02*
X888788Y1154608D01*
G01X888667Y1154324D02*
X888788Y1154606D01*
G01X888549Y1154061D02*
X888667Y1154324D01*
G01X888434Y1153819D02*
X888549Y1154061D01*
G01X899409Y1164055D02*
G03I-3740J0D01*
G01X905512Y1157028D02*
Y1169980D01*
G01X905315Y1163268D02*
Y1164843D01*
G01X899960D02*
Y1163268D01*
G01X898622Y1163071D02*
Y1163268D01*
G01Y1164843D02*
Y1165040D01*
G01Y1164843D02*
Y1163268D01*
G01X898425Y1164843D02*
Y1163268D01*
G01X896850Y1164843D02*
Y1163268D01*
G01X894488Y1164843D02*
Y1163268D01*
G01X892913D02*
Y1164843D01*
G01X892716D02*
Y1165040D01*
G01Y1163268D02*
Y1164843D01*
G01Y1163268D02*
Y1163071D01*
G01X891378Y1163268D02*
Y1164843D01*
G01X886023D02*
Y1163268D01*
G01X885827Y1157028D02*
Y1169980D01*
G01X888841Y1154737D02*
X888801Y1154639D01*
G01X888877Y1154825D02*
X888841Y1154737D01*
G01X888936Y1154972D02*
X888877Y1154825D01*
G01X888969Y1155058D02*
X888936Y1154972D01*
G01X889004Y1155150D02*
X888969Y1155058D01*
G01X889040Y1155246D02*
X889004Y1155150D01*
G01X889095Y1155394D02*
X889040Y1155246D01*
G01X905512Y1169980D02*
X885827D01*
G01X905512Y1168012D02*
X885827D01*
G01X905512Y1166024D02*
X885827D01*
G01Y1165040D02*
X905512D01*
G01X905315Y1164843D02*
X886023D01*
G01X905315Y1163268D02*
X886023D01*
G01X905512Y1163071D02*
X885827D01*
G01Y1162087D02*
X905512D01*
G01Y1158996D02*
X885827D01*
G01X894488Y1155847D02*
X927953D01*
G01X898819Y1380551D02*
G03Y1379370I0J-591D01*
G01Y1377795D02*
G03Y1376614I0J-591D01*
G01X892519Y1379370D02*
G03Y1380551I0J590D01*
G01Y1376614D02*
G03Y1377795I0J591D01*
G01Y1381142D02*
X898819D01*
G01Y1380847D02*
X900393D01*
G01X897244D02*
X898819D01*
G01X892519D02*
X890945D01*
G01X894094D02*
X892519D01*
G01X898714Y1380370D02*
X898808D01*
G01Y1379622D02*
X898714D01*
G01X892519Y1378878D02*
X894094D01*
G01X890945D02*
X892519D01*
G01X900393D02*
X898819D01*
G01D02*
X897244D01*
G01X892519Y1378288D02*
X894094D01*
G01X890945D02*
X892519D01*
G01X900393D02*
X898819D01*
G01D02*
X897244D01*
G01X898819Y1376319D02*
X900393D01*
G01X897244D02*
X898819D01*
G01X892519D02*
X890945D01*
G01X894094D02*
X892519D01*
G01Y1376024D02*
X898819D01*
G01X900393Y1376319D02*
Y1378288D01*
G01Y1380847D02*
Y1378878D01*
G01X898901Y1379861D02*
Y1379734D01*
G01X898819Y1380551D02*
Y1381142D01*
G01Y1377795D02*
Y1379370D01*
G01Y1376024D02*
Y1376614D01*
G01X898808Y1380370D02*
Y1379749D01*
G01X898714Y1379622D02*
Y1380370D01*
G01X897834Y1381142D02*
Y1376024D01*
G01X897638D02*
Y1381142D01*
G01X897244Y1378878D02*
Y1380847D01*
G01Y1378288D02*
Y1376319D01*
G01X894094Y1378878D02*
Y1380847D01*
G01Y1378288D02*
Y1376319D01*
G01X893701Y1376024D02*
Y1381142D01*
G01X893504D02*
Y1376024D01*
G01X892519Y1376614D02*
Y1376024D01*
G01Y1379370D02*
Y1377795D01*
G01Y1381142D02*
Y1380551D01*
G01X890945Y1376319D02*
Y1378288D01*
G01Y1380847D02*
Y1378878D01*
G01X898901Y1379734D02*
X898808Y1379622D01*
G01Y1379749D02*
X898901Y1379861D01*
G01X899409Y1396339D02*
G03I-3740J0D01*
G01X886492Y1404016D02*
G03X886417Y1412284I-75J4134D01*
G01X927953Y1404547D02*
X894488D01*
G01X885827Y1401398D02*
X905512D01*
G01Y1398307D02*
X885827D01*
G01Y1397323D02*
X905512D01*
G01X905315Y1397126D02*
X886023D01*
G01X905315Y1395551D02*
X886023D01*
G01X905512Y1395354D02*
X885827D01*
G01Y1394370D02*
X905512D01*
G01X885827Y1392382D02*
X905512D01*
G01X885827Y1390414D02*
X905512D01*
G01X886492Y1404016D02*
X886417D01*
G01X905512Y1403366D02*
Y1562540D01*
G01Y1390414D02*
Y1403366D01*
G01X905315Y1395551D02*
Y1397126D01*
G01X899960D02*
Y1395551D01*
G01X898622Y1397126D02*
Y1397323D01*
G01Y1395354D02*
Y1395551D01*
G01Y1397126D02*
Y1395551D01*
G01X898425Y1397126D02*
Y1395551D01*
G01X896850Y1397126D02*
Y1395551D01*
G01X894488Y1403366D02*
Y1411713D01*
G01Y1397126D02*
Y1395551D01*
G01X892913D02*
Y1397126D01*
G01X892716D02*
Y1397323D01*
G01Y1395551D02*
Y1397126D01*
G01Y1395551D02*
Y1395354D01*
G01X891378Y1395551D02*
Y1397126D01*
G01X886023D02*
Y1395551D01*
G01X885827Y1390414D02*
Y1403366D01*
G01X893701Y1426339D02*
X925984D01*
G01X893701Y1426240D02*
X924223D01*
G01X893701Y1424666D02*
X924223D01*
G01X893701Y1424567D02*
X925984D01*
G01X893701Y1421339D02*
X925984D01*
G01X893701Y1421240D02*
X924223D01*
G01X893701Y1419666D02*
X924223D01*
G01X893701Y1419567D02*
X925984D01*
G01X896358Y1416634D02*
X924803D01*
G01X893701D02*
X894980D01*
G01X894488Y1408760D02*
X905512D01*
G01X886342Y1412283D02*
X886417D01*
G01X897638Y1549272D02*
Y1416634D01*
G01X896358D02*
Y1549272D01*
G01X894980D02*
Y1416634D01*
G01X893701Y1414862D02*
Y1452914D01*
G01X889764Y1426240D02*
Y1426339D01*
G01Y1424567D02*
Y1424666D01*
G01D02*
Y1426240D01*
G01Y1421240D02*
Y1421339D01*
G01Y1419666D02*
Y1421240D01*
G01Y1419567D02*
Y1419666D01*
G01X925984Y1446339D02*
X893701D01*
G01Y1446240D02*
X924223D01*
G01X893701Y1444666D02*
X924223D01*
G01X893701Y1444567D02*
X925984D01*
G01X886811Y1444331D02*
X893701D01*
G01Y1441575D02*
X886811D01*
G01X893701Y1441339D02*
X925984D01*
G01X893701Y1441240D02*
X924223D01*
G01X893701Y1439666D02*
X924223D01*
G01X893701Y1439567D02*
X925984D01*
G01X893701Y1436339D02*
X925984D01*
G01X893701Y1436240D02*
X924223D01*
G01X893701Y1434666D02*
X924223D01*
G01X893701Y1434567D02*
X925984D01*
G01X893701Y1431339D02*
X925984D01*
G01X893701Y1431240D02*
X924223D01*
G01X893701Y1429666D02*
X924223D01*
G01X893701Y1429567D02*
X925984D01*
G01X889764Y1446240D02*
Y1446339D01*
G01Y1444567D02*
Y1444666D01*
G01D02*
Y1446240D01*
G01Y1441240D02*
Y1441339D01*
G01Y1439567D02*
Y1439666D01*
G01D02*
Y1441240D01*
G01Y1436240D02*
Y1436339D01*
G01Y1434567D02*
Y1434666D01*
G01D02*
Y1436240D01*
G01Y1431240D02*
Y1431339D01*
G01Y1429567D02*
Y1429666D01*
G01D02*
Y1431240D01*
G01X886811Y1444331D02*
Y1441575D01*
G01X886362Y1454666D02*
X886462Y1454501D01*
G01X885859Y1452631D02*
X885926Y1452533D01*
G01X886194Y1454600D02*
X886295Y1454469D01*
G01X885926Y1453943D02*
X885826Y1454075D01*
G01X886362Y1453189D02*
X886462Y1453058D01*
G01X886261Y1454764D02*
X886362Y1454666D01*
G01X886261Y1453025D02*
X886194Y1453091D01*
G01X886228Y1453288D02*
X886362Y1453189D01*
G01X886094Y1454666D02*
X886194Y1454600D01*
G01X886027Y1453878D02*
X885926Y1453943D01*
G01X885993Y1453714D02*
X885859Y1453780D01*
G01X886194Y1453091D02*
X886127Y1453123D01*
G01X886094Y1454829D02*
X886261Y1454764D01*
G01X886127Y1453320D02*
X886228Y1453288D01*
G01X885926Y1452533D02*
X886027Y1452500D01*
G01X888976Y1467480D02*
X891338Y1466791D01*
G01X888976Y1464331D02*
X891338Y1463642D01*
G01X888976Y1461181D02*
X891338Y1460492D01*
G01X888976Y1458032D02*
X891338Y1457343D01*
G01X888976Y1454882D02*
X891338Y1454193D01*
G01X886295Y1454469D02*
X886329Y1454337D01*
G01X885821Y1454095D02*
X885792Y1454206D01*
G01X885826Y1454075D02*
X885821Y1454095D01*
G01X886295Y1452927D02*
X886261Y1453025D01*
G01X885826Y1452730D02*
X885859Y1452631D01*
G01X885993Y1452303D02*
X885859Y1452336D01*
G01X922560Y1468662D02*
X896456D01*
G01Y1468563D02*
X925787D01*
G01X891338D02*
X893701D01*
G01X896456Y1466791D02*
X925787D01*
G01X891338D02*
X893701D01*
G01X896456Y1466693D02*
X922560D01*
G01Y1465512D02*
X896456D01*
G01Y1465414D02*
X925787D01*
G01X891338D02*
X893701D01*
G01X896456Y1463642D02*
X925787D01*
G01X891338D02*
X893701D01*
G01X896456Y1463543D02*
X922560D01*
G01X886462Y1454501D02*
X886496Y1454337D01*
G01X886492Y1452914D02*
X886496Y1452894D01*
G01X886462Y1453058D02*
X886492Y1452914D01*
G01X885792Y1453091D02*
X885826Y1452927D01*
G01X922560Y1462362D02*
X896456D01*
G01Y1462264D02*
X925787D01*
G01X891338D02*
X893701D01*
G01X896456Y1460492D02*
X925787D01*
G01X891338D02*
X893701D01*
G01X896456Y1460394D02*
X922560D01*
G01Y1459213D02*
X896456D01*
G01Y1459114D02*
X925787D01*
G01X891338D02*
X893701D01*
G01X896456Y1457343D02*
X925787D01*
G01X891338D02*
X893701D01*
G01X896456Y1457244D02*
X922560D01*
G01Y1456063D02*
X896456D01*
G01Y1455965D02*
X925787D01*
G01X891338D02*
X893701D01*
G01X885993Y1454829D02*
X886094D01*
G01X886027Y1454666D02*
X886094D01*
G01X891338Y1454193D02*
X893701D01*
G01X925787D02*
X896456D01*
G01Y1454095D02*
X922560D01*
G01X886094Y1453878D02*
X886027D01*
G01X886094Y1453714D02*
X885993D01*
G01X924016Y1453189D02*
X905512D01*
G01X922560Y1452914D02*
X896456D01*
G01X891338Y1452815D02*
X893701D01*
G01X925787D02*
X896456D01*
G01X886027Y1452500D02*
X886094D01*
G01X886127Y1452303D02*
X885993D01*
G01X923031Y1451339D02*
X893701D01*
G01Y1451240D02*
X924102D01*
G01X893701Y1450748D02*
X925984D01*
G01X924102Y1449666D02*
X893701D01*
G01Y1449567D02*
X923031D01*
G01X886261Y1452336D02*
X886127Y1452303D01*
G01X896456Y1450748D02*
Y1475158D01*
G01X893701Y1456063D02*
Y1454095D01*
G01D02*
Y1452914D01*
G01Y1459213D02*
Y1457244D01*
G01D02*
Y1456063D01*
G01Y1460394D02*
Y1459213D01*
G01Y1462362D02*
Y1460394D01*
G01Y1465512D02*
Y1463543D01*
G01D02*
Y1462362D01*
G01Y1468662D02*
Y1466693D01*
G01D02*
Y1465512D01*
G01Y1469843D02*
Y1468662D01*
G01X891811Y1465512D02*
Y1466693D01*
G01Y1468662D02*
Y1469843D01*
G01Y1462362D02*
Y1463543D01*
G01Y1459213D02*
Y1460394D01*
G01Y1456063D02*
Y1457244D01*
G01Y1452914D02*
Y1454095D01*
G01X890236Y1468662D02*
Y1469843D01*
G01Y1465512D02*
Y1466693D01*
G01Y1462362D02*
Y1463543D01*
G01Y1459213D02*
Y1460394D01*
G01Y1456063D02*
Y1457244D01*
G01Y1452914D02*
Y1454095D01*
G01X889764Y1451240D02*
Y1451339D01*
G01Y1449567D02*
Y1449666D01*
G01D02*
Y1451240D01*
G01X889449Y1454095D02*
Y1452914D01*
G01Y1457244D02*
Y1456063D01*
G01Y1460394D02*
Y1459213D01*
G01Y1463543D02*
Y1462362D01*
G01Y1466693D02*
Y1465512D01*
G01Y1469843D02*
Y1468662D01*
G01X889055Y1454095D02*
Y1452914D01*
G01Y1460394D02*
Y1459213D01*
G01Y1457244D02*
Y1456063D01*
G01Y1463543D02*
Y1462362D01*
G01Y1466693D02*
Y1465512D01*
G01Y1469843D02*
Y1468662D01*
G01X888976Y1467480D02*
Y1467874D01*
G01Y1464331D02*
Y1464725D01*
G01Y1458032D02*
Y1458425D01*
G01Y1461181D02*
Y1461575D01*
G01Y1454882D02*
Y1455276D01*
G01Y1451929D02*
Y1452126D01*
G01X886496Y1454337D02*
Y1454206D01*
G01Y1452894D02*
Y1452730D01*
G01X886329Y1454337D02*
Y1454206D01*
G01X886295Y1452730D02*
Y1452914D01*
G01D02*
Y1452927D01*
G01X886127Y1453123D02*
Y1453320D01*
G01X885826Y1452914D02*
Y1452730D01*
G01Y1452927D02*
Y1452914D01*
G01X885792Y1454206D02*
Y1454337D01*
G01X886496Y1452730D02*
X886462Y1452599D01*
G01X886329Y1454206D02*
X886300Y1454095D01*
G01D02*
X886295Y1454075D01*
G01X885792Y1454337D02*
X885826Y1454469D01*
G01X886496Y1454206D02*
X886473Y1454095D01*
G01D02*
X886462Y1454042D01*
G01X886261Y1452631D02*
X886295Y1452730D01*
G01X886462Y1452599D02*
X886395Y1452467D01*
G01X886295Y1454075D02*
X886194Y1453943D01*
G01X885826Y1454469D02*
X885926Y1454600D01*
G01X886194Y1452533D02*
X886261Y1452631D01*
G01X886462Y1454042D02*
X886362Y1453878D01*
G01X886395Y1452467D02*
X886261Y1452336D01*
G01X886362Y1453878D02*
X886261Y1453780D01*
G01X886194Y1453943D02*
X886094Y1453878D01*
G01X885926Y1454600D02*
X886027Y1454666D01*
G01X886261Y1453780D02*
X886094Y1453714D01*
G01X885859Y1454764D02*
X885993Y1454829D01*
G01X891338Y1452815D02*
X888976Y1452126D01*
G01X891338Y1455965D02*
X888976Y1455276D01*
G01X891338Y1459114D02*
X888976Y1458425D01*
G01X891338Y1462264D02*
X888976Y1461575D01*
G01X891338Y1465414D02*
X888976Y1464725D01*
G01X891338Y1468563D02*
X888976Y1467874D01*
G01X886094Y1452500D02*
X886194Y1452533D01*
G01X888976Y1473780D02*
X891338Y1473091D01*
G01X888976Y1470630D02*
X891338Y1469941D01*
G01X894882Y1489666D02*
X924223D01*
G01X894882Y1489567D02*
X925984D01*
G01X887008D02*
X891732D01*
G01X893701Y1488091D02*
X894882D01*
G01X893701Y1486339D02*
X925984D01*
G01X893701Y1486240D02*
X924223D01*
G01X893701Y1484666D02*
X924223D01*
G01X893701Y1484567D02*
X925984D01*
G01X893701Y1481339D02*
X925984D01*
G01X893701Y1481240D02*
X924223D01*
G01Y1479666D02*
X893701D01*
G01Y1479567D02*
X925984D01*
G01X886811Y1479331D02*
X893701D01*
G01Y1476575D02*
X886811D01*
G01X893701Y1476339D02*
X923031D01*
G01X893701Y1476240D02*
X924102D01*
G01X893701Y1475158D02*
X925984D01*
G01X893701Y1474666D02*
X924102D01*
G01X893701Y1474567D02*
X923031D01*
G01X896456Y1473091D02*
X925787D01*
G01X891338D02*
X893701D01*
G01X896456Y1472992D02*
X922560D01*
G01X905512Y1472717D02*
X924016D01*
G01X922560Y1471811D02*
X896456D01*
G01Y1471713D02*
X925787D01*
G01X891338D02*
X893701D01*
G01X896456Y1469941D02*
X925787D01*
G01X891338D02*
X893701D01*
G01X896456Y1469843D02*
X922560D01*
G01X894882Y1488091D02*
Y1492815D01*
G01X893701Y1472992D02*
Y1489666D01*
G01Y1471811D02*
Y1469843D01*
G01Y1472992D02*
Y1471811D01*
G01Y1491240D02*
Y1489666D01*
G01X891811Y1471811D02*
Y1472992D01*
G01X891732Y1489666D02*
Y1491240D01*
G01Y1489567D02*
Y1489666D01*
G01X890236Y1471811D02*
Y1472992D01*
G01X889764Y1486240D02*
Y1486339D01*
G01Y1484666D02*
Y1486240D01*
G01Y1484567D02*
Y1484666D01*
G01Y1481240D02*
Y1481339D01*
G01Y1479666D02*
Y1481240D01*
G01Y1479567D02*
Y1479666D01*
G01Y1476240D02*
Y1476339D01*
G01Y1474666D02*
Y1476240D01*
G01Y1474567D02*
Y1474666D01*
G01X889449Y1472992D02*
Y1471811D01*
G01X889055Y1472992D02*
Y1471811D01*
G01X888976Y1473780D02*
Y1473977D01*
G01Y1470630D02*
Y1471024D01*
G01X886811Y1479331D02*
Y1476575D01*
G01X891338Y1471713D02*
X888976Y1471024D01*
G01X893701Y1511339D02*
X925984D01*
G01X893701Y1511240D02*
X924223D01*
G01X893701Y1509666D02*
X924223D01*
G01X893701Y1509567D02*
X925984D01*
G01X893701Y1506339D02*
X925984D01*
G01X893701Y1506240D02*
X924223D01*
G01X893701Y1504666D02*
X924223D01*
G01X893701Y1504567D02*
X925984D01*
G01X886811Y1504331D02*
X893701D01*
G01Y1501575D02*
X886811D01*
G01X893701Y1501339D02*
X925984D01*
G01X893701Y1501240D02*
X924223D01*
G01X893701Y1499666D02*
X924223D01*
G01X893701Y1499567D02*
X925984D01*
G01X893701Y1496339D02*
X925984D01*
G01X893701Y1496240D02*
X924223D01*
G01X893701Y1494666D02*
X924223D01*
G01X893701Y1494567D02*
X925984D01*
G01X894882Y1492815D02*
X893701D01*
G01X891732Y1491339D02*
X887008D01*
G01X925984D02*
X894882D01*
G01Y1491240D02*
X924223D01*
G01X893701D02*
Y1529666D01*
G01X891732Y1491240D02*
Y1491339D01*
G01X889764Y1511240D02*
Y1511339D01*
G01Y1509567D02*
Y1509666D01*
G01D02*
Y1511240D01*
G01Y1506240D02*
Y1506339D01*
G01Y1504567D02*
Y1504666D01*
G01D02*
Y1506240D01*
G01Y1501240D02*
Y1501339D01*
G01Y1499567D02*
Y1499666D01*
G01D02*
Y1501240D01*
G01Y1496240D02*
Y1496339D01*
G01Y1494567D02*
Y1494666D01*
G01D02*
Y1496240D01*
G01X886811Y1504331D02*
Y1501575D01*
G01X891732Y1531339D02*
X887008D01*
G01X925984D02*
X894882D01*
G01Y1531240D02*
X924223D01*
G01X894882Y1529666D02*
X924223D01*
G01X894882Y1529567D02*
X925984D01*
G01X887008D02*
X891732D01*
G01X886811Y1529331D02*
X893701D01*
G01Y1528091D02*
X894882D01*
G01X893701Y1526575D02*
X886811D01*
G01X893701Y1526339D02*
X925984D01*
G01X893701Y1526240D02*
X924223D01*
G01X893701Y1524666D02*
X924223D01*
G01X893701Y1524567D02*
X925984D01*
G01X893701Y1521339D02*
X925984D01*
G01X893701Y1521240D02*
X924223D01*
G01X893701Y1519666D02*
X924223D01*
G01X893701Y1519567D02*
X925984D01*
G01X893701Y1516339D02*
X925984D01*
G01X893701Y1516240D02*
X924223D01*
G01X893701Y1514666D02*
X924223D01*
G01X893701Y1514567D02*
X925984D01*
G01X894882Y1528091D02*
Y1532815D01*
G01X893701Y1531240D02*
Y1551043D01*
G01Y1531240D02*
Y1529666D01*
G01X891732Y1531240D02*
Y1531339D01*
G01Y1529567D02*
Y1529666D01*
G01D02*
Y1531240D01*
G01X889764Y1526240D02*
Y1526339D01*
G01Y1524567D02*
Y1524666D01*
G01D02*
Y1526240D01*
G01Y1521240D02*
Y1521339D01*
G01Y1519567D02*
Y1519666D01*
G01D02*
Y1521240D01*
G01Y1516240D02*
Y1516339D01*
G01Y1514567D02*
Y1514666D01*
G01D02*
Y1516240D01*
G01X886811Y1529331D02*
Y1526575D01*
G01X893701Y1549272D02*
X894980D01*
G01X924803D02*
X896358D01*
G01X925984Y1546339D02*
X893701D01*
G01Y1546240D02*
X924223D01*
G01X893701Y1544666D02*
X924223D01*
G01X893701Y1544567D02*
X925984D01*
G01X893701Y1541339D02*
X925984D01*
G01X893701Y1541240D02*
X924223D01*
G01X893701Y1539666D02*
X924223D01*
G01X893701Y1539567D02*
X925984D01*
G01X893701Y1536339D02*
X925984D01*
G01X893701Y1536240D02*
X924223D01*
G01X893701Y1534666D02*
X924223D01*
G01X893701Y1534567D02*
X925984D01*
G01X894882Y1532815D02*
X893701D01*
G01X889764Y1546240D02*
Y1546339D01*
G01Y1544666D02*
Y1546240D01*
G01Y1544567D02*
Y1544666D01*
G01Y1541240D02*
Y1541339D01*
G01Y1539567D02*
Y1539666D01*
G01D02*
Y1541240D01*
G01Y1536240D02*
Y1536339D01*
G01Y1534567D02*
Y1534666D01*
G01D02*
Y1536240D01*
G01X888788Y1560119D02*
Y1560118D01*
G01X888801Y1560151D02*
X888788Y1560119D01*
G01X888667Y1559836D02*
X888788Y1560118D01*
G01X888549Y1559573D02*
X888667Y1559836D01*
G01X888434Y1559331D02*
X888549Y1559573D01*
G01X888671Y1555666D02*
X888788Y1555394D01*
G01X888554Y1555929D02*
X888671Y1555666D01*
G01X888434Y1556181D02*
X888554Y1555929D01*
G01X888434Y1556181D02*
G03Y1559331I-2017J1575D01*
G01X888788Y1555394D02*
G03Y1560118I-2371J2362D01*
G01X899409Y1569567D02*
G03I-3740J0D01*
G01X889095Y1554606D02*
G03Y1560906I-2678J3150D01*
G01X888969Y1554942D02*
X889004Y1554850D01*
G01X888936Y1555028D02*
X888969Y1554942D01*
G01X888864Y1555207D02*
X888936Y1555028D01*
G01X888831Y1555288D02*
X888864Y1555207D01*
G01X888788Y1555394D02*
X888831Y1555288D01*
G01X905512Y1573524D02*
X885827D01*
G01X905512Y1571536D02*
X885827D01*
G01Y1570551D02*
X905512D01*
G01X905315Y1570354D02*
X886023D01*
G01X905315Y1568780D02*
X886023D01*
G01X905512Y1568583D02*
X885827D01*
G01Y1567599D02*
X905512D01*
G01Y1564508D02*
X885827D01*
G01X894488Y1561358D02*
X927953D01*
G01X905512Y1557146D02*
X894488D01*
G01X889040Y1554754D02*
X889095Y1554606D01*
G01X889004Y1554850D02*
X889040Y1554754D01*
G01X905512Y1562540D02*
Y1575492D01*
G01X905315Y1568780D02*
Y1570354D01*
G01X899960D02*
Y1568780D01*
G01X898622Y1570354D02*
Y1570551D01*
G01Y1568583D02*
Y1568780D01*
G01Y1570354D02*
Y1568780D01*
G01X898425Y1570354D02*
Y1568780D01*
G01X896850Y1570354D02*
Y1568780D01*
G01X894488Y1554193D02*
Y1562540D01*
G01Y1570354D02*
Y1568780D01*
G01X892913D02*
Y1570354D01*
G01X892716D02*
Y1570551D01*
G01Y1568780D02*
Y1570354D01*
G01Y1568780D02*
Y1568583D01*
G01X891378Y1568780D02*
Y1570354D01*
G01X886023D02*
Y1568780D01*
G01X885827Y1562540D02*
Y1575492D01*
G01X888841Y1560249D02*
X888801Y1560151D01*
G01X888877Y1560337D02*
X888841Y1560249D01*
G01X888936Y1560484D02*
X888877Y1560337D01*
G01X888969Y1560570D02*
X888936Y1560484D01*
G01X889004Y1560662D02*
X888969Y1560570D01*
G01X889040Y1560758D02*
X889004Y1560662D01*
G01X889095Y1560906D02*
X889040Y1560758D01*
G01X905512Y1575492D02*
X885827D01*
G01X898819Y1786063D02*
G03Y1784882I0J-591D01*
G01Y1783307D02*
G03Y1782126I0J-590D01*
G01X892519Y1784882D02*
G03Y1786063I0J590D01*
G01Y1782126D02*
G03Y1783307I0J591D01*
G01X898819Y1786358D02*
X900393D01*
G01X897244D02*
X898819D01*
G01X892519D02*
X890945D01*
G01X894094D02*
X892519D01*
G01X898714Y1785882D02*
X898808D01*
G01Y1785134D02*
X898714D01*
G01X892519Y1784390D02*
X894094D01*
G01X890945D02*
X892519D01*
G01X900393D02*
X898819D01*
G01D02*
X897244D01*
G01X892519Y1783799D02*
X894094D01*
G01X890945D02*
X892519D01*
G01X900393D02*
X898819D01*
G01D02*
X897244D01*
G01X898819Y1781831D02*
X900393D01*
G01X897244D02*
X898819D01*
G01X892519D02*
X890945D01*
G01X894094D02*
X892519D01*
G01Y1781536D02*
X898819D01*
G01X900393Y1781831D02*
Y1783799D01*
G01Y1786358D02*
Y1784390D01*
G01X898901Y1785373D02*
Y1785245D01*
G01X898819Y1786063D02*
Y1786654D01*
G01Y1783307D02*
Y1784882D01*
G01Y1781536D02*
Y1782126D01*
G01X898808Y1785882D02*
Y1785261D01*
G01X898714Y1785134D02*
Y1785882D01*
G01X897834Y1786654D02*
Y1781536D01*
G01X897638D02*
Y1786654D01*
G01X897244Y1784390D02*
Y1786358D01*
G01Y1783799D02*
Y1781831D01*
G01X894094Y1784390D02*
Y1786358D01*
G01Y1783799D02*
Y1781831D01*
G01X893701Y1781536D02*
Y1786654D01*
G01X893504D02*
Y1781536D01*
G01X892519Y1782126D02*
Y1781536D01*
G01Y1784882D02*
Y1783307D01*
G01Y1786654D02*
Y1786063D01*
G01X890945Y1781831D02*
Y1783799D01*
G01Y1786358D02*
Y1784390D01*
G01X898901Y1785245D02*
X898808Y1785134D01*
G01Y1785261D02*
X898901Y1785373D01*
G01X899409Y1801851D02*
G03I-3740J0D01*
G01X885827Y1806910D02*
X905512D01*
G01Y1803819D02*
X885827D01*
G01Y1802835D02*
X905512D01*
G01X905315Y1802638D02*
X886023D01*
G01X905315Y1801063D02*
X886023D01*
G01X905512Y1800866D02*
X885827D01*
G01Y1799882D02*
X905512D01*
G01X885827Y1797894D02*
X905512D01*
G01X885827Y1795925D02*
X905512D01*
G01X892519Y1786654D02*
X898819D01*
G01X905512Y1795925D02*
Y1808878D01*
G01X905315Y1801063D02*
Y1802638D01*
G01X899960D02*
Y1801063D01*
G01X898622Y1802638D02*
Y1802835D01*
G01Y1800866D02*
Y1801063D01*
G01Y1802638D02*
Y1801063D01*
G01X898425Y1802638D02*
Y1801063D01*
G01X896850Y1802638D02*
Y1801063D01*
G01X894488Y1802638D02*
Y1801063D01*
G01X892913D02*
Y1802638D01*
G01X892716D02*
Y1802835D01*
G01Y1801063D02*
Y1802638D01*
G01Y1801063D02*
Y1800866D01*
G01X891378Y1801063D02*
Y1802638D01*
G01X886023D02*
Y1801063D01*
G01X885827Y1795925D02*
Y1808878D01*
G01X886492Y1809528D02*
G03X886417Y1817795I-75J4133D01*
G01X893701Y1826851D02*
X925984D01*
G01X893701Y1826752D02*
X924223D01*
G01X893701Y1825177D02*
X924223D01*
G01X893701Y1825079D02*
X925984D01*
G01X896358Y1822146D02*
X924803D01*
G01X893701D02*
X894980D01*
G01X894488Y1814272D02*
X905512D01*
G01X927953Y1810059D02*
X894488D01*
G01X886342Y1817795D02*
X886417D01*
G01X886492Y1809528D02*
X886417D01*
G01X905512Y1808878D02*
Y1968051D01*
G01X897638Y1954784D02*
Y1822146D01*
G01X896358D02*
Y1954784D01*
G01X894980D02*
Y1822146D01*
G01X894488Y1808878D02*
Y1817225D01*
G01X893701Y1820374D02*
Y1858425D01*
G01X889764Y1826752D02*
Y1826851D01*
G01Y1825079D02*
Y1825177D01*
G01D02*
Y1826752D01*
G01X886811Y1849843D02*
X893701D01*
G01Y1847087D02*
X886811D01*
G01X893701Y1846851D02*
X925984D01*
G01X893701Y1846752D02*
X924223D01*
G01X893701Y1845177D02*
X924223D01*
G01X893701Y1845079D02*
X925984D01*
G01X893701Y1841851D02*
X925984D01*
G01X893701Y1841752D02*
X924223D01*
G01X893701Y1840177D02*
X924223D01*
G01X893701Y1840079D02*
X925984D01*
G01X893701Y1836851D02*
X925984D01*
G01X893701Y1836752D02*
X924223D01*
G01X893701Y1835177D02*
X924223D01*
G01X893701Y1835079D02*
X925984D01*
G01X893701Y1831851D02*
X925984D01*
G01X893701Y1831752D02*
X924223D01*
G01X893701Y1830177D02*
X924223D01*
G01X893701Y1830079D02*
X925984D01*
G01X889764Y1846752D02*
Y1846851D01*
G01Y1845177D02*
Y1846752D01*
G01Y1845079D02*
Y1845177D01*
G01Y1841752D02*
Y1841851D01*
G01Y1840177D02*
Y1841752D01*
G01Y1840079D02*
Y1840177D01*
G01Y1836752D02*
Y1836851D01*
G01Y1835177D02*
Y1836752D01*
G01Y1835079D02*
Y1835177D01*
G01Y1831752D02*
Y1831851D01*
G01Y1830177D02*
Y1831752D01*
G01Y1830079D02*
Y1830177D01*
G01X886811Y1849843D02*
Y1847087D01*
G01X885993Y1859226D02*
X885859Y1859291D01*
G01X886194Y1858603D02*
X886127Y1858635D01*
G01X886094Y1860341D02*
X886261Y1860276D01*
G01X886127Y1858832D02*
X886228Y1858799D01*
G01X885926Y1858045D02*
X886027Y1858012D01*
G01X888976Y1869843D02*
X891338Y1869154D01*
G01X888976Y1866693D02*
X891338Y1866004D01*
G01X888976Y1863543D02*
X891338Y1862854D01*
G01X888976Y1860394D02*
X891338Y1859705D01*
G01X886261Y1860276D02*
X886362Y1860177D01*
G01X886261Y1858537D02*
X886194Y1858603D01*
G01X886228Y1858799D02*
X886362Y1858701D01*
G01X886094Y1860177D02*
X886194Y1860112D01*
G01X886027Y1859390D02*
X885926Y1859455D01*
G01X885993Y1857815D02*
X885859Y1857848D01*
G01X922560Y1871024D02*
X896456D01*
G01Y1870925D02*
X925787D01*
G01X891338D02*
X893701D01*
G01X896456Y1869154D02*
X925787D01*
G01X891338D02*
X893701D01*
G01X896456Y1869055D02*
X922560D01*
G01Y1867874D02*
X896456D01*
G01Y1867776D02*
X925787D01*
G01X891338D02*
X893701D01*
G01X896456Y1866004D02*
X925787D01*
G01X891338D02*
X893701D01*
G01X896456Y1865906D02*
X922560D01*
G01Y1864725D02*
X896456D01*
G01Y1864626D02*
X925787D01*
G01X891338D02*
X893701D01*
G01X896456Y1862854D02*
X925787D01*
G01X891338D02*
X893701D01*
G01X896456Y1862756D02*
X922560D01*
G01Y1861575D02*
X896456D01*
G01Y1861477D02*
X925787D01*
G01X891338D02*
X893701D01*
G01X885993Y1860341D02*
X886094D01*
G01X886027Y1860177D02*
X886094D01*
G01X891338Y1859705D02*
X893701D01*
G01X925787D02*
X896456D01*
G01Y1859606D02*
X922560D01*
G01X886094Y1859390D02*
X886027D01*
G01X886094Y1859226D02*
X885993D01*
G01X924016Y1858701D02*
X905512D01*
G01X922560Y1858425D02*
X896456D01*
G01X891338Y1858327D02*
X893701D01*
G01X925787D02*
X896456D01*
G01X886027Y1858012D02*
X886094D01*
G01X886127Y1857815D02*
X885993D01*
G01X923031Y1856851D02*
X893701D01*
G01Y1856752D02*
X924102D01*
G01X893701Y1856260D02*
X925984D01*
G01X924102Y1855177D02*
X893701D01*
G01Y1855079D02*
X923031D01*
G01X925984Y1851851D02*
X893701D01*
G01Y1851752D02*
X924223D01*
G01X893701Y1850177D02*
X924223D01*
G01X893701Y1850079D02*
X925984D01*
G01X885859Y1858143D02*
X885926Y1858045D01*
G01X886194Y1860112D02*
X886295Y1859980D01*
G01X885926Y1859455D02*
X885826Y1859587D01*
G01X886362Y1858701D02*
X886462Y1858569D01*
G01X886362Y1860177D02*
X886462Y1860013D01*
G01X886261Y1857848D02*
X886127Y1857815D01*
G01X886295Y1858438D02*
X886261Y1858537D01*
G01X885826Y1858241D02*
X885859Y1858143D01*
G01X886295Y1859980D02*
X886329Y1859849D01*
G01X885821Y1859606D02*
X885792Y1859718D01*
G01X885826Y1859587D02*
X885821Y1859606D01*
G01X886462Y1860013D02*
X886496Y1859849D01*
G01X886492Y1858425D02*
X886496Y1858406D01*
G01X886462Y1858569D02*
X886492Y1858425D01*
G01X885792Y1858603D02*
X885826Y1858438D01*
G01X896456Y1856260D02*
Y1880669D01*
G01X893701Y1859606D02*
Y1858425D01*
G01Y1861575D02*
Y1859606D01*
G01Y1862756D02*
Y1861575D01*
G01Y1864725D02*
Y1862756D01*
G01Y1867874D02*
Y1865906D01*
G01D02*
Y1864725D01*
G01Y1869055D02*
Y1867874D01*
G01Y1871024D02*
Y1869055D01*
G01Y1872205D02*
Y1871024D01*
G01X891811D02*
Y1872205D01*
G01Y1864725D02*
Y1865906D01*
G01Y1867874D02*
Y1869055D01*
G01Y1861575D02*
Y1862756D01*
G01Y1858425D02*
Y1859606D01*
G01X890236Y1871024D02*
Y1872205D01*
G01Y1867874D02*
Y1869055D01*
G01Y1864725D02*
Y1865906D01*
G01Y1861575D02*
Y1862756D01*
G01Y1858425D02*
Y1859606D01*
G01X889764Y1856752D02*
Y1856851D01*
G01Y1855079D02*
Y1855177D01*
G01D02*
Y1856752D01*
G01Y1851752D02*
Y1851851D01*
G01Y1850177D02*
Y1851752D01*
G01Y1850079D02*
Y1850177D01*
G01X889449Y1859606D02*
Y1858425D01*
G01Y1862756D02*
Y1861575D01*
G01Y1865906D02*
Y1864725D01*
G01Y1869055D02*
Y1867874D01*
G01Y1872205D02*
Y1871024D01*
G01X889055Y1859606D02*
Y1858425D01*
G01Y1862756D02*
Y1861575D01*
G01Y1865906D02*
Y1864725D01*
G01Y1869055D02*
Y1867874D01*
G01Y1872205D02*
Y1871024D01*
G01X888976Y1869843D02*
Y1870236D01*
G01Y1866693D02*
Y1867087D01*
G01Y1860394D02*
Y1860788D01*
G01Y1863543D02*
Y1863937D01*
G01Y1857441D02*
Y1857638D01*
G01X886496Y1858406D02*
Y1858241D01*
G01Y1859849D02*
Y1859718D01*
G01X886329Y1859849D02*
Y1859718D01*
G01X886295Y1858241D02*
Y1858425D01*
G01D02*
Y1858438D01*
G01X886127Y1858635D02*
Y1858832D01*
G01X885826Y1858425D02*
Y1858241D01*
G01Y1858438D02*
Y1858425D01*
G01X885792Y1859718D02*
Y1859849D01*
G01X886496Y1859718D02*
X886473Y1859606D01*
G01D02*
X886462Y1859554D01*
G01X886496Y1858241D02*
X886462Y1858110D01*
G01X886329Y1859718D02*
X886300Y1859606D01*
G01D02*
X886295Y1859587D01*
G01X885792Y1859849D02*
X885826Y1859980D01*
G01X886261Y1858143D02*
X886295Y1858241D01*
G01X886462Y1858110D02*
X886395Y1857979D01*
G01X886462Y1859554D02*
X886362Y1859390D01*
G01X886194Y1858045D02*
X886261Y1858143D01*
G01X886295Y1859587D02*
X886194Y1859455D01*
G01X885826Y1859980D02*
X885926Y1860112D01*
G01X886395Y1857979D02*
X886261Y1857848D01*
G01X886362Y1859390D02*
X886261Y1859291D01*
G01X886194Y1859455D02*
X886094Y1859390D01*
G01X885926Y1860112D02*
X886027Y1860177D01*
G01X886261Y1859291D02*
X886094Y1859226D01*
G01X885859Y1860276D02*
X885993Y1860341D01*
G01X891338Y1858327D02*
X888976Y1857638D01*
G01X891338Y1861477D02*
X888976Y1860788D01*
G01X891338Y1864626D02*
X888976Y1863937D01*
G01X891338Y1867776D02*
X888976Y1867087D01*
G01X891338Y1870925D02*
X888976Y1870236D01*
G01X886094Y1858012D02*
X886194Y1858045D01*
G01X888976Y1879291D02*
X891338Y1878603D01*
G01X888976Y1876142D02*
X891338Y1875453D01*
G01X888976Y1872992D02*
X891338Y1872303D01*
G01X893701Y1891851D02*
X925984D01*
G01X893701Y1891752D02*
X924223D01*
G01X893701Y1890177D02*
X924223D01*
G01X893701Y1890079D02*
X925984D01*
G01X893701Y1886851D02*
X925984D01*
G01X893701Y1886752D02*
X924223D01*
G01Y1885177D02*
X893701D01*
G01Y1885079D02*
X925984D01*
G01X886811Y1884843D02*
X893701D01*
G01Y1882087D02*
X886811D01*
G01X893701Y1881851D02*
X923031D01*
G01X893701Y1881752D02*
X924102D01*
G01X893701Y1880669D02*
X925984D01*
G01X893701Y1880177D02*
X924102D01*
G01X893701Y1880079D02*
X923031D01*
G01X896456Y1878603D02*
X925787D01*
G01X891338D02*
X893701D01*
G01X896456Y1878504D02*
X922560D01*
G01X905512Y1878228D02*
X924016D01*
G01X922560Y1877323D02*
X896456D01*
G01Y1877225D02*
X925787D01*
G01X891338D02*
X893701D01*
G01X896456Y1875453D02*
X925787D01*
G01X891338D02*
X893701D01*
G01X896456Y1875354D02*
X922560D01*
G01Y1874173D02*
X896456D01*
G01Y1874075D02*
X925787D01*
G01X891338D02*
X893701D01*
G01X896456Y1872303D02*
X925787D01*
G01X891338D02*
X893701D01*
G01X896456Y1872205D02*
X922560D01*
G01X893701Y1878504D02*
Y1895177D01*
G01Y1874173D02*
Y1872205D01*
G01Y1877323D02*
Y1875354D01*
G01D02*
Y1874173D01*
G01Y1878504D02*
Y1877323D01*
G01X891811D02*
Y1878504D01*
G01Y1874173D02*
Y1875354D01*
G01X890236Y1877323D02*
Y1878504D01*
G01Y1874173D02*
Y1875354D01*
G01X889764Y1891752D02*
Y1891851D01*
G01Y1890079D02*
Y1890177D01*
G01D02*
Y1891752D01*
G01Y1886752D02*
Y1886851D01*
G01Y1885079D02*
Y1885177D01*
G01D02*
Y1886752D01*
G01Y1881752D02*
Y1881851D01*
G01Y1880079D02*
Y1880177D01*
G01D02*
Y1881752D01*
G01X889449Y1875354D02*
Y1874173D01*
G01Y1878504D02*
Y1877323D01*
G01X889055Y1875354D02*
Y1874173D01*
G01Y1878504D02*
Y1877323D01*
G01X888976Y1879291D02*
Y1879488D01*
G01Y1876142D02*
Y1876536D01*
G01Y1872992D02*
Y1873386D01*
G01X886811Y1884843D02*
Y1882087D01*
G01X891338Y1874075D02*
X888976Y1873386D01*
G01X891338Y1877225D02*
X888976Y1876536D01*
G01X893701Y1911851D02*
X925984D01*
G01X893701Y1911752D02*
X924223D01*
G01X893701Y1910177D02*
X924223D01*
G01X893701Y1910079D02*
X925984D01*
G01X886811Y1909843D02*
X893701D01*
G01Y1907087D02*
X886811D01*
G01X893701Y1906851D02*
X925984D01*
G01X893701Y1906752D02*
X924223D01*
G01X893701Y1905177D02*
X924223D01*
G01X893701Y1905079D02*
X925984D01*
G01X893701Y1901851D02*
X925984D01*
G01X893701Y1901752D02*
X924223D01*
G01X893701Y1900177D02*
X924223D01*
G01X893701Y1900079D02*
X925984D01*
G01X894882Y1898327D02*
X893701D01*
G01X891732Y1896851D02*
X887008D01*
G01X925984D02*
X894882D01*
G01Y1896752D02*
X924223D01*
G01X894882Y1895177D02*
X924223D01*
G01X894882Y1895079D02*
X925984D01*
G01X887008D02*
X891732D01*
G01X893701Y1893603D02*
X894882D01*
G01D02*
Y1898327D01*
G01X893701Y1896752D02*
Y1935177D01*
G01Y1896752D02*
Y1895177D01*
G01X891732Y1896752D02*
Y1896851D01*
G01Y1895079D02*
Y1895177D01*
G01D02*
Y1896752D01*
G01X889764Y1911752D02*
Y1911851D01*
G01Y1910177D02*
Y1911752D01*
G01Y1910079D02*
Y1910177D01*
G01Y1906752D02*
Y1906851D01*
G01Y1905177D02*
Y1906752D01*
G01Y1905079D02*
Y1905177D01*
G01Y1901752D02*
Y1901851D01*
G01Y1900079D02*
Y1900177D01*
G01D02*
Y1901752D01*
G01X886811Y1909843D02*
Y1907087D01*
G01X893701Y1933603D02*
X894882D01*
G01X893701Y1932087D02*
X886811D01*
G01X893701Y1931851D02*
X925984D01*
G01X893701Y1931752D02*
X924223D01*
G01X893701Y1930177D02*
X924223D01*
G01X893701Y1930079D02*
X925984D01*
G01X893701Y1926851D02*
X925984D01*
G01X893701Y1926752D02*
X924223D01*
G01X893701Y1925177D02*
X924223D01*
G01X893701Y1925079D02*
X925984D01*
G01X893701Y1921851D02*
X925984D01*
G01X893701Y1921752D02*
X924223D01*
G01X893701Y1920177D02*
X924223D01*
G01X893701Y1920079D02*
X925984D01*
G01X893701Y1916851D02*
X925984D01*
G01X893701Y1916752D02*
X924223D01*
G01X893701Y1915177D02*
X924223D01*
G01X893701Y1915079D02*
X925984D01*
G01X894882Y1933603D02*
Y1938327D01*
G01X889764Y1931752D02*
Y1931851D01*
G01Y1930079D02*
Y1930177D01*
G01D02*
Y1931752D01*
G01Y1926752D02*
Y1926851D01*
G01Y1925177D02*
Y1926752D01*
G01Y1925079D02*
Y1925177D01*
G01Y1921752D02*
Y1921851D01*
G01Y1920177D02*
Y1921752D01*
G01Y1920079D02*
Y1920177D01*
G01Y1916752D02*
Y1916851D01*
G01Y1915177D02*
Y1916752D01*
G01Y1915079D02*
Y1915177D01*
G01X886811Y1934843D02*
Y1932087D01*
G01X893701Y1954784D02*
X894980D01*
G01X924803D02*
X896358D01*
G01X925984Y1951851D02*
X893701D01*
G01Y1951752D02*
X924223D01*
G01X893701Y1950177D02*
X924223D01*
G01X893701Y1950079D02*
X925984D01*
G01X893701Y1946851D02*
X925984D01*
G01X893701Y1946752D02*
X924223D01*
G01X893701Y1945177D02*
X924223D01*
G01X893701Y1945079D02*
X925984D01*
G01X893701Y1941851D02*
X925984D01*
G01X893701Y1941752D02*
X924223D01*
G01X893701Y1940177D02*
X924223D01*
G01X893701Y1940079D02*
X925984D01*
G01X894882Y1938327D02*
X893701D01*
G01X891732Y1936851D02*
X887008D01*
G01X925984D02*
X894882D01*
G01Y1936752D02*
X924223D01*
G01X894882Y1935177D02*
X924223D01*
G01X894882Y1935079D02*
X925984D01*
G01X887008D02*
X891732D01*
G01X886811Y1934843D02*
X893701D01*
G01Y1936752D02*
Y1956555D01*
G01Y1936752D02*
Y1935177D01*
G01X891732Y1936752D02*
Y1936851D01*
G01Y1935079D02*
Y1935177D01*
G01D02*
Y1936752D01*
G01X889764Y1951752D02*
Y1951851D01*
G01Y1950079D02*
Y1950177D01*
G01D02*
Y1951752D01*
G01Y1946752D02*
Y1946851D01*
G01Y1945079D02*
Y1945177D01*
G01D02*
Y1946752D01*
G01Y1941752D02*
Y1941851D01*
G01Y1940079D02*
Y1940177D01*
G01D02*
Y1941752D01*
G01X888667Y1965347D02*
X888788Y1965630D01*
G01X888549Y1965085D02*
X888667Y1965347D01*
G01X888434Y1964843D02*
X888549Y1965085D01*
G01X888788Y1965631D02*
Y1965630D01*
G01X888801Y1965662D02*
X888788Y1965631D01*
G01X888671Y1961178D02*
X888788Y1960906D01*
G01X888554Y1961441D02*
X888671Y1961178D01*
G01X888434Y1961693D02*
X888554Y1961441D01*
G01X888936Y1960540D02*
X888952Y1960497D01*
G01X888864Y1960719D02*
X888936Y1960540D01*
G01X899409Y1975079D02*
G03I-3740J0D01*
G01X888434Y1961693D02*
G03Y1964843I-2017J1575D01*
G01X888788Y1960906D02*
G03Y1965630I-2371J2362D01*
G01X889095Y1960118D02*
G03Y1966417I-2678J3149D01*
G01X885827Y1976063D02*
X905512D01*
G01X905315Y1975866D02*
X886023D01*
G01X905315Y1974291D02*
X886023D01*
G01X905512Y1974095D02*
X885827D01*
G01Y1973110D02*
X905512D01*
G01Y1970020D02*
X885827D01*
G01X894488Y1966870D02*
X927953D01*
G01X905512Y1962658D02*
X894488D01*
G01X888831Y1960800D02*
X888864Y1960719D01*
G01X888788Y1960906D02*
X888831Y1960800D01*
G01X889058Y1960217D02*
X889095Y1960118D01*
G01X889022Y1960314D02*
X889058Y1960217D01*
G01X888986Y1960408D02*
X889022Y1960314D01*
G01X888952Y1960497D02*
X888986Y1960408D01*
G01X905512Y1968051D02*
Y1981004D01*
G01X905315Y1974291D02*
Y1975866D01*
G01X899960D02*
Y1974291D01*
G01X898622Y1974095D02*
Y1974291D01*
G01Y1975866D02*
Y1976063D01*
G01Y1975866D02*
Y1974291D01*
G01X898425Y1975866D02*
Y1974291D01*
G01X896850Y1975866D02*
Y1974291D01*
G01X894488Y1959705D02*
Y1968051D01*
G01Y1975866D02*
Y1974291D01*
G01X892913D02*
Y1975866D01*
G01X892716D02*
Y1976063D01*
G01Y1974291D02*
Y1975866D01*
G01Y1974291D02*
Y1974095D01*
G01X891378Y1974291D02*
Y1975866D01*
G01X886023D02*
Y1974291D01*
G01X885827Y1968051D02*
Y1981004D01*
G01X889095Y1966417D02*
X889058Y1966318D01*
G01X888841Y1965760D02*
X888801Y1965662D01*
G01X888877Y1965849D02*
X888841Y1965760D01*
G01X888919Y1965955D02*
X888877Y1965849D01*
G01X888952Y1966038D02*
X888919Y1965955D01*
G01X888986Y1966127D02*
X888952Y1966038D01*
G01X889022Y1966221D02*
X888986Y1966127D01*
G01X889058Y1966318D02*
X889022Y1966221D01*
G01X905512Y1981004D02*
X885827D01*
G01X905512Y1979036D02*
X885827D01*
G01X905512Y1977047D02*
X885827D01*
G01X905849Y2126667D02*
Y2107730D01*
G01X909449Y182894D02*
Y169941D01*
G01X927997Y186877D02*
X927984Y186862D01*
G01X928009Y186896D02*
X927997Y186877D01*
G01X928019Y186917D02*
X928009Y186896D01*
G01X928028Y186941D02*
X928019Y186917D01*
G01X928036Y186969D02*
X928028Y186941D01*
G01X928041Y186999D02*
X928036Y186969D01*
G01X928045Y187032D02*
X928041Y186999D01*
G01X928049Y187067D02*
X928045Y187032D01*
G01X928050Y187106D02*
X928049Y187067D01*
G01X928051Y187147D02*
X928050Y187106D01*
G01X928049Y187190D02*
X928051Y187147D01*
G01X928047Y187236D02*
X928049Y187190D01*
G01X928043Y187285D02*
X928047Y187236D01*
G01X928039Y187336D02*
X928043Y187285D01*
G01X928033Y187389D02*
X928039Y187336D01*
G01X928027Y187444D02*
X928033Y187389D01*
G01X928019Y187502D02*
X928027Y187444D01*
G01X928010Y187561D02*
X928019Y187502D01*
G01X927973Y187812D02*
X928010Y187561D01*
G01X927965Y187875D02*
X927973Y187812D01*
G01X927957Y187938D02*
X927965Y187875D01*
G01X928010Y187561D02*
X927983Y187748D01*
G01X928019Y187502D02*
X928010Y187561D01*
G01X928027Y187444D02*
X928019Y187502D01*
G01X928033Y187389D02*
X928027Y187444D01*
G01X928039Y187336D02*
X928033Y187389D01*
G01X928043Y187285D02*
X928039Y187336D01*
G01X928047Y187236D02*
X928043Y187285D01*
G01X928049Y187190D02*
X928047Y187236D01*
G01X928051Y187147D02*
X928049Y187190D01*
G01X928050Y187106D02*
X928051Y187147D01*
G01X928049Y187068D02*
X928050Y187106D01*
G01X932677Y191477D02*
X927953Y186831D01*
G01X927957Y187938D02*
X932677Y192580D01*
G01X924016Y195177D02*
X925984Y197146D01*
G01X927997Y186877D02*
X928009Y186896D01*
G01X927953Y195177D02*
Y188012D01*
G01X925984Y195177D02*
Y337658D01*
G01X924803Y200099D02*
Y332736D01*
G01X927983Y187748D02*
X927973Y187812D01*
G01X924803Y200099D02*
X925984Y198917D01*
G01Y195177D02*
X929267D01*
G01X936614Y182894D02*
X909449D01*
G01X924223Y218130D02*
Y219705D01*
G01Y213130D02*
Y214705D01*
G01Y208130D02*
Y209705D01*
G01Y203130D02*
Y204705D01*
G01X923541D02*
Y203130D01*
G01Y209705D02*
Y208130D01*
G01Y214705D02*
Y213130D01*
G01Y219705D02*
Y218130D01*
G01X923031Y218032D02*
Y219803D01*
G01Y213032D02*
Y214803D01*
G01Y208032D02*
Y209803D01*
G01Y203032D02*
Y204803D01*
G01X919366Y218130D02*
Y219705D01*
G01Y213130D02*
Y214705D01*
G01Y208130D02*
Y209705D01*
G01Y203130D02*
Y204705D01*
G01X919120Y218130D02*
Y219705D01*
G01Y213130D02*
Y214705D01*
G01Y208130D02*
Y209705D01*
G01Y203130D02*
Y204705D01*
G01X918014D02*
Y203130D01*
G01Y209705D02*
Y208130D01*
G01Y214705D02*
Y213130D01*
G01Y219705D02*
Y218130D01*
G01X925787Y237658D02*
Y236280D01*
G01Y240807D02*
Y239429D01*
G01X924223Y228130D02*
Y229705D01*
G01Y223130D02*
Y224705D01*
G01X924102Y233130D02*
Y234705D01*
G01X924016Y258622D02*
Y234213D01*
G01X923541Y224705D02*
Y223130D01*
G01Y229705D02*
Y228130D01*
G01X923113Y234705D02*
Y233130D01*
G01X923031Y233032D02*
Y234803D01*
G01Y228032D02*
Y229803D01*
G01Y223032D02*
Y224803D01*
G01X922560Y237559D02*
Y236378D01*
G01Y240709D02*
Y239528D01*
G01X921823D02*
Y240709D01*
G01Y236378D02*
Y237559D01*
G01X919366Y228130D02*
Y229705D01*
G01Y223130D02*
Y224705D01*
G01Y234705D02*
Y233130D01*
G01X919120D02*
Y234705D01*
G01Y228130D02*
Y229705D01*
G01Y223130D02*
Y224705D01*
G01X918014D02*
Y223130D01*
G01Y229705D02*
Y228130D01*
G01Y234705D02*
Y233130D01*
G01X917008Y239429D02*
Y240807D01*
G01Y237658D02*
Y236280D01*
G01X916264Y237559D02*
Y236378D01*
G01Y240709D02*
Y239528D01*
G01X915767D02*
Y240709D01*
G01Y236378D02*
Y237559D01*
G01X913528D02*
Y236378D01*
G01Y240709D02*
Y239528D01*
G01X924016Y236654D02*
X925984Y234685D01*
G01Y240807D02*
X925787D01*
G01Y239429D02*
X925984D01*
G01Y237658D02*
X925787D01*
G01Y236280D02*
X925984D01*
G01X924016Y256181D02*
X925984Y258150D01*
G01X925787Y255177D02*
Y256555D01*
G01Y243957D02*
Y242579D01*
G01Y247106D02*
Y245728D01*
G01Y253406D02*
Y252028D01*
G01Y250256D02*
Y248878D01*
G01X924223Y263130D02*
Y264705D01*
G01X924102Y258130D02*
Y259705D01*
G01X923541Y264705D02*
Y263130D01*
G01X923113Y259705D02*
Y258130D01*
G01X923031Y263032D02*
Y264803D01*
G01Y258032D02*
Y259803D01*
G01X922560Y243858D02*
Y242677D01*
G01Y247008D02*
Y245827D01*
G01Y250158D02*
Y248977D01*
G01Y253307D02*
Y252126D01*
G01Y256457D02*
Y255276D01*
G01X921823D02*
Y256457D01*
G01Y248977D02*
Y250158D01*
G01Y252126D02*
Y253307D01*
G01Y245827D02*
Y247008D01*
G01Y242677D02*
Y243858D01*
G01X919366Y263130D02*
Y264705D01*
G01Y259705D02*
Y258130D01*
G01X919120Y263130D02*
Y264705D01*
G01Y258130D02*
Y259705D01*
G01X918014D02*
Y258130D01*
G01Y264705D02*
Y263130D01*
G01X917008Y248878D02*
Y250256D01*
G01Y252028D02*
Y253406D01*
G01Y245728D02*
Y247106D01*
G01Y242579D02*
Y243957D01*
G01Y256555D02*
Y255177D01*
G01X916264Y243858D02*
Y242677D01*
G01Y247008D02*
Y245827D01*
G01Y250158D02*
Y248977D01*
G01Y253307D02*
Y252126D01*
G01Y256457D02*
Y255276D01*
G01X915767D02*
Y256457D01*
G01Y252126D02*
Y253307D01*
G01Y248977D02*
Y250158D01*
G01Y245827D02*
Y247008D01*
G01Y242677D02*
Y243858D01*
G01X913528D02*
Y242677D01*
G01Y247008D02*
Y245827D01*
G01Y250158D02*
Y248977D01*
G01Y253307D02*
Y252126D01*
G01Y256457D02*
Y255276D01*
G01X925984Y256555D02*
X925787D01*
G01Y255177D02*
X925984D01*
G01Y253406D02*
X925787D01*
G01Y252028D02*
X925984D01*
G01Y250256D02*
X925787D01*
G01Y248878D02*
X925984D01*
G01Y247106D02*
X925787D01*
G01Y245728D02*
X925984D01*
G01Y243957D02*
X925787D01*
G01Y242579D02*
X925984D01*
G01X924223Y283130D02*
Y284705D01*
G01Y278130D02*
Y279705D01*
G01Y273130D02*
Y274705D01*
G01Y268130D02*
Y269705D01*
G01X923541D02*
Y268130D01*
G01Y274705D02*
Y273130D01*
G01Y279705D02*
Y278130D01*
G01Y284705D02*
Y283130D01*
G01X923031Y283032D02*
Y284803D01*
G01Y278032D02*
Y279803D01*
G01Y273032D02*
Y274803D01*
G01Y268032D02*
Y269803D01*
G01X919366Y283130D02*
Y284705D01*
G01Y278130D02*
Y279705D01*
G01Y273130D02*
Y274705D01*
G01Y268130D02*
Y269705D01*
G01X919120Y283130D02*
Y284705D01*
G01Y278130D02*
Y279705D01*
G01Y273130D02*
Y274705D01*
G01Y268130D02*
Y269705D01*
G01X918014D02*
Y268130D01*
G01Y274705D02*
Y273130D01*
G01Y279705D02*
Y278130D01*
G01Y284705D02*
Y283130D01*
G01X924223Y303130D02*
Y304705D01*
G01Y298130D02*
Y299705D01*
G01Y293130D02*
Y294705D01*
G01Y288130D02*
Y289705D01*
G01X923541D02*
Y288130D01*
G01Y294705D02*
Y293130D01*
G01Y299705D02*
Y298130D01*
G01Y304705D02*
Y303130D01*
G01X923031Y303032D02*
Y304803D01*
G01Y298032D02*
Y299803D01*
G01Y293032D02*
Y294803D01*
G01Y288032D02*
Y289803D01*
G01X919366Y303130D02*
Y304705D01*
G01Y298130D02*
Y299705D01*
G01Y293130D02*
Y294705D01*
G01Y288130D02*
Y289705D01*
G01X919120Y303130D02*
Y304705D01*
G01Y298130D02*
Y299705D01*
G01Y293130D02*
Y294705D01*
G01Y288130D02*
Y289705D01*
G01X918014D02*
Y288130D01*
G01Y294705D02*
Y293130D01*
G01Y299705D02*
Y298130D01*
G01Y304705D02*
Y303130D01*
G01X924223Y323130D02*
Y324705D01*
G01Y318130D02*
Y319705D01*
G01Y313130D02*
Y314705D01*
G01Y308130D02*
Y309705D01*
G01X923541D02*
Y308130D01*
G01Y314705D02*
Y313130D01*
G01Y319705D02*
Y318130D01*
G01Y324705D02*
Y323130D01*
G01X923031Y323032D02*
Y324803D01*
G01Y318032D02*
Y319803D01*
G01Y313032D02*
Y314803D01*
G01Y308032D02*
Y309803D01*
G01X919366Y323130D02*
Y324705D01*
G01Y318130D02*
Y319705D01*
G01Y313130D02*
Y314705D01*
G01Y308130D02*
Y309705D01*
G01X919120Y323130D02*
Y324705D01*
G01Y318130D02*
Y319705D01*
G01Y313130D02*
Y314705D01*
G01Y308130D02*
Y309705D01*
G01X918014D02*
Y308130D01*
G01Y314705D02*
Y313130D01*
G01Y319705D02*
Y318130D01*
G01Y324705D02*
Y323130D01*
G01X928019Y345333D02*
X928010Y345274D01*
G01X928027Y345390D02*
X928019Y345333D01*
G01X928033Y345446D02*
X928027Y345390D01*
G01X928039Y345499D02*
X928033Y345446D01*
G01X928043Y345550D02*
X928039Y345499D01*
G01X928047Y345598D02*
X928043Y345550D01*
G01X928049Y345644D02*
X928047Y345598D01*
G01X928051Y345688D02*
X928049Y345644D01*
G01X928050Y345729D02*
X928051Y345688D01*
G01X928049Y345767D02*
X928050Y345729D01*
G01X928046Y345803D02*
X928049Y345767D01*
G01X928041Y345836D02*
X928046Y345803D01*
G01X928036Y345866D02*
X928041Y345836D01*
G01X928028Y345893D02*
X928036Y345866D01*
G01X928019Y345917D02*
X928028Y345893D01*
G01X928009Y345939D02*
X928019Y345917D01*
G01X927997Y345957D02*
X928009Y345939D01*
G01X927984Y345973D02*
X927997Y345957D01*
G01X927965Y344960D02*
X927957Y344897D01*
G01X927973Y345023D02*
X927965Y344960D01*
G01X928049Y345644D02*
X928051Y345688D01*
G01X928047Y345598D02*
X928049Y345644D01*
G01X928043Y345550D02*
X928047Y345598D01*
G01X928039Y345499D02*
X928043Y345550D01*
G01X928033Y345446D02*
X928039Y345499D01*
G01X928027Y345391D02*
X928033Y345446D01*
G01X928019Y345333D02*
X928027Y345391D01*
G01X928010Y345274D02*
X928019Y345333D01*
G01X924803Y332736D02*
X925984Y333917D01*
G01X928010Y345274D02*
X927973Y345023D01*
G01X927953Y344823D02*
Y337658D01*
G01X924223Y328130D02*
Y329705D01*
G01X923541D02*
Y328130D01*
G01X923031Y328032D02*
Y329803D01*
G01X919366Y328130D02*
Y329705D01*
G01X919120Y328130D02*
Y329705D01*
G01X918014D02*
Y328130D01*
G01X928049Y345767D02*
X928045Y345803D01*
G01X928019Y345917D02*
X928009Y345939D01*
G01X927997Y345957D02*
X927984Y345973D01*
G01X925984Y335689D02*
X924016Y337658D01*
G01X927953Y346004D02*
X932677Y341358D01*
G01Y340255D02*
X927957Y344897D01*
G01X925984Y337658D02*
X929267D01*
G01X909449Y362894D02*
Y349941D01*
G01D02*
X936614D01*
G01X909449Y588406D02*
Y575453D01*
G01X927997Y592389D02*
X927984Y592374D01*
G01X928009Y592408D02*
X927997Y592389D01*
G01X928019Y592429D02*
X928009Y592408D01*
G01X928028Y592453D02*
X928019Y592429D01*
G01X928036Y592481D02*
X928028Y592453D01*
G01X928041Y592511D02*
X928036Y592481D01*
G01X928045Y592544D02*
X928041Y592511D01*
G01X928049Y592579D02*
X928045Y592544D01*
G01X928050Y592618D02*
X928049Y592579D01*
G01X928051Y592659D02*
X928050Y592618D01*
G01X928049Y592702D02*
X928051Y592659D01*
G01X928047Y592748D02*
X928049Y592702D01*
G01X928043Y592797D02*
X928047Y592748D01*
G01X928039Y592848D02*
X928043Y592797D01*
G01X928033Y592901D02*
X928039Y592848D01*
G01X928027Y592956D02*
X928033Y592901D01*
G01X928019Y593014D02*
X928027Y592956D01*
G01X928010Y593073D02*
X928019Y593014D01*
G01X927973Y593323D02*
X928010Y593073D01*
G01X927965Y593387D02*
X927973Y593323D01*
G01X927957Y593450D02*
X927965Y593387D01*
G01X928010Y593073D02*
X928002Y593134D01*
G01X928019Y593014D02*
X928010Y593073D01*
G01X928027Y592956D02*
X928019Y593014D01*
G01X928033Y592901D02*
X928027Y592956D01*
G01X928039Y592848D02*
X928033Y592901D01*
G01X928043Y592797D02*
X928039Y592848D01*
G01X928047Y592748D02*
X928043Y592797D01*
G01X928049Y592702D02*
X928047Y592748D01*
G01X928051Y592659D02*
X928049Y592702D01*
G01X928050Y592618D02*
X928051Y592659D01*
G01X928049Y592580D02*
X928050Y592618D01*
G01X932677Y596988D02*
X927953Y592343D01*
G01X927957Y593450D02*
X932677Y598091D01*
G01X924016Y600689D02*
X925984Y602658D01*
G01X927997Y592389D02*
X928009Y592408D01*
G01X927953Y600689D02*
Y593524D01*
G01X925984Y600689D02*
Y743169D01*
G01Y600689D02*
X929267D01*
G01X936614Y588406D02*
X909449D01*
G01X924803Y605610D02*
Y738248D01*
G01X924223Y618642D02*
Y620217D01*
G01Y613642D02*
Y615217D01*
G01Y608642D02*
Y610217D01*
G01X923541D02*
Y608642D01*
G01Y615217D02*
Y613642D01*
G01Y620217D02*
Y618642D01*
G01X923031Y618543D02*
Y620315D01*
G01Y613543D02*
Y615315D01*
G01Y608543D02*
Y610315D01*
G01X919366Y618642D02*
Y620217D01*
G01Y613642D02*
Y615217D01*
G01Y608642D02*
Y610217D01*
G01X919120Y618642D02*
Y620217D01*
G01Y613642D02*
Y615217D01*
G01Y608642D02*
Y610217D01*
G01X918014D02*
Y608642D01*
G01Y615217D02*
Y613642D01*
G01Y620217D02*
Y618642D01*
G01X924803Y605610D02*
X925984Y604429D01*
G01X925787Y643169D02*
Y641791D01*
G01X924223Y633642D02*
Y635217D01*
G01Y628642D02*
Y630217D01*
G01Y623642D02*
Y625217D01*
G01X924102Y638642D02*
Y640217D01*
G01X924016Y664134D02*
Y639725D01*
G01X923541Y625217D02*
Y623642D01*
G01Y630217D02*
Y628642D01*
G01Y635217D02*
Y633642D01*
G01X923113Y640217D02*
Y638642D01*
G01X923031Y638543D02*
Y640315D01*
G01Y633543D02*
Y635315D01*
G01Y628543D02*
Y630315D01*
G01Y623543D02*
Y625315D01*
G01X922560Y643071D02*
Y641890D01*
G01X921823D02*
Y643071D01*
G01X919366Y633642D02*
Y635217D01*
G01Y628642D02*
Y630217D01*
G01Y623642D02*
Y625217D01*
G01Y640217D02*
Y638642D01*
G01X919120D02*
Y640217D01*
G01Y633642D02*
Y635217D01*
G01Y628642D02*
Y630217D01*
G01Y623642D02*
Y625217D01*
G01X918014D02*
Y623642D01*
G01Y630217D02*
Y628642D01*
G01Y635217D02*
Y633642D01*
G01Y640217D02*
Y638642D01*
G01X917008Y643169D02*
Y641791D01*
G01X916264Y643071D02*
Y641890D01*
G01X915767D02*
Y643071D01*
G01X913528D02*
Y641890D01*
G01X924016Y642166D02*
X925984Y640197D01*
G01Y643169D02*
X925787D01*
G01Y641791D02*
X925984D01*
G01X924016Y661693D02*
X925984Y663662D01*
G01X925787Y660689D02*
Y662067D01*
G01Y646319D02*
Y644941D01*
G01Y649469D02*
Y648091D01*
G01Y655768D02*
Y654390D01*
G01Y652618D02*
Y651240D01*
G01Y658917D02*
Y657540D01*
G01X924102Y663642D02*
Y665217D01*
G01X923113D02*
Y663642D01*
G01X923031Y663543D02*
Y665315D01*
G01X922560Y646221D02*
Y645040D01*
G01Y649370D02*
Y648189D01*
G01Y652520D02*
Y651339D01*
G01Y655669D02*
Y654488D01*
G01Y658819D02*
Y657638D01*
G01Y661969D02*
Y660788D01*
G01X921823D02*
Y661969D01*
G01Y657638D02*
Y658819D01*
G01Y651339D02*
Y652520D01*
G01Y654488D02*
Y655669D01*
G01Y648189D02*
Y649370D01*
G01Y645040D02*
Y646221D01*
G01X919366Y665217D02*
Y663642D01*
G01X919120D02*
Y665217D01*
G01X918014D02*
Y663642D01*
G01X917008Y657540D02*
Y658917D01*
G01Y651240D02*
Y652618D01*
G01Y654390D02*
Y655768D01*
G01Y648091D02*
Y649469D01*
G01Y644941D02*
Y646319D01*
G01Y662067D02*
Y660689D01*
G01X916264Y646221D02*
Y645040D01*
G01Y649370D02*
Y648189D01*
G01Y652520D02*
Y651339D01*
G01Y655669D02*
Y654488D01*
G01Y658819D02*
Y657638D01*
G01Y661969D02*
Y660788D01*
G01X915767D02*
Y661969D01*
G01Y657638D02*
Y658819D01*
G01Y654488D02*
Y655669D01*
G01Y651339D02*
Y652520D01*
G01Y648189D02*
Y649370D01*
G01Y645040D02*
Y646221D01*
G01X913528D02*
Y645040D01*
G01Y649370D02*
Y648189D01*
G01Y652520D02*
Y651339D01*
G01Y655669D02*
Y654488D01*
G01Y658819D02*
Y657638D01*
G01Y661969D02*
Y660788D01*
G01X925984Y662067D02*
X925787D01*
G01Y660689D02*
X925984D01*
G01Y658917D02*
X925787D01*
G01Y657540D02*
X925984D01*
G01Y655768D02*
X925787D01*
G01Y654390D02*
X925984D01*
G01Y652618D02*
X925787D01*
G01Y651240D02*
X925984D01*
G01Y649469D02*
X925787D01*
G01Y648091D02*
X925984D01*
G01Y646319D02*
X925787D01*
G01Y644941D02*
X925984D01*
G01X924223Y683642D02*
Y685217D01*
G01Y678642D02*
Y680217D01*
G01Y673642D02*
Y675217D01*
G01Y668642D02*
Y670217D01*
G01X923541D02*
Y668642D01*
G01Y675217D02*
Y673642D01*
G01Y680217D02*
Y678642D01*
G01Y685217D02*
Y683642D01*
G01X923031Y683543D02*
Y685315D01*
G01Y678543D02*
Y680315D01*
G01Y673543D02*
Y675315D01*
G01Y668543D02*
Y670315D01*
G01X919366Y683642D02*
Y685217D01*
G01Y678642D02*
Y680217D01*
G01Y673642D02*
Y675217D01*
G01Y668642D02*
Y670217D01*
G01X919120Y683642D02*
Y685217D01*
G01Y678642D02*
Y680217D01*
G01Y673642D02*
Y675217D01*
G01Y668642D02*
Y670217D01*
G01X918014D02*
Y668642D01*
G01Y675217D02*
Y673642D01*
G01Y680217D02*
Y678642D01*
G01Y685217D02*
Y683642D01*
G01X924223Y703642D02*
Y705217D01*
G01Y698642D02*
Y700217D01*
G01Y693642D02*
Y695217D01*
G01Y688642D02*
Y690217D01*
G01X923541D02*
Y688642D01*
G01Y695217D02*
Y693642D01*
G01Y700217D02*
Y698642D01*
G01Y705217D02*
Y703642D01*
G01X923031Y703543D02*
Y705315D01*
G01Y698543D02*
Y700315D01*
G01Y693543D02*
Y695315D01*
G01Y688543D02*
Y690315D01*
G01X919366Y703642D02*
Y705217D01*
G01Y698642D02*
Y700217D01*
G01Y693642D02*
Y695217D01*
G01Y688642D02*
Y690217D01*
G01X919120Y703642D02*
Y705217D01*
G01Y698642D02*
Y700217D01*
G01Y693642D02*
Y695217D01*
G01Y688642D02*
Y690217D01*
G01X918014D02*
Y688642D01*
G01Y695217D02*
Y693642D01*
G01Y700217D02*
Y698642D01*
G01Y705217D02*
Y703642D01*
G01X924223Y728642D02*
Y730217D01*
G01Y723642D02*
Y725217D01*
G01Y718642D02*
Y720217D01*
G01Y713642D02*
Y715217D01*
G01Y708642D02*
Y710217D01*
G01X923541D02*
Y708642D01*
G01Y715217D02*
Y713642D01*
G01Y720217D02*
Y718642D01*
G01Y725217D02*
Y723642D01*
G01Y730217D02*
Y728642D01*
G01X923031Y728543D02*
Y730315D01*
G01Y723543D02*
Y725315D01*
G01Y718543D02*
Y720315D01*
G01Y713543D02*
Y715315D01*
G01Y708543D02*
Y710315D01*
G01X919366Y728642D02*
Y730217D01*
G01Y723642D02*
Y725217D01*
G01Y718642D02*
Y720217D01*
G01Y713642D02*
Y715217D01*
G01Y708642D02*
Y710217D01*
G01X919120Y728642D02*
Y730217D01*
G01Y723642D02*
Y725217D01*
G01Y718642D02*
Y720217D01*
G01Y713642D02*
Y715217D01*
G01Y708642D02*
Y710217D01*
G01X918014D02*
Y708642D01*
G01Y715217D02*
Y713642D01*
G01Y720217D02*
Y718642D01*
G01Y725217D02*
Y723642D01*
G01Y730217D02*
Y728642D01*
G01X924803Y738248D02*
X925984Y739429D01*
G01X927953Y750335D02*
Y743169D01*
G01X924223Y733642D02*
Y735217D01*
G01X923541D02*
Y733642D01*
G01X923031Y733543D02*
Y735315D01*
G01X919366Y733642D02*
Y735217D01*
G01X919120Y733642D02*
Y735217D01*
G01X918014D02*
Y733642D01*
G01X925984Y741201D02*
X924016Y743169D01*
G01X925984D02*
X929267D01*
G01X928019Y750845D02*
X928010Y750786D01*
G01X928027Y750902D02*
X928019Y750845D01*
G01X928033Y750958D02*
X928027Y750902D01*
G01X928039Y751011D02*
X928033Y750958D01*
G01X928043Y751062D02*
X928039Y751011D01*
G01X928047Y751110D02*
X928043Y751062D01*
G01X928049Y751156D02*
X928047Y751110D01*
G01X928051Y751200D02*
X928049Y751156D01*
G01X928050Y751241D02*
X928051Y751200D01*
G01X928049Y751279D02*
X928050Y751241D01*
G01X928046Y751315D02*
X928049Y751279D01*
G01X928041Y751347D02*
X928046Y751315D01*
G01X928036Y751378D02*
X928041Y751347D01*
G01X928028Y751405D02*
X928036Y751378D01*
G01X928019Y751429D02*
X928028Y751405D01*
G01X928009Y751451D02*
X928019Y751429D01*
G01X927997Y751469D02*
X928009Y751451D01*
G01X927984Y751485D02*
X927997Y751469D01*
G01X927965Y750471D02*
X927957Y750408D01*
G01X927973Y750535D02*
X927965Y750471D01*
G01X928049Y751156D02*
X928051Y751200D01*
G01X928047Y751110D02*
X928049Y751156D01*
G01X928043Y751062D02*
X928047Y751110D01*
G01X928039Y751011D02*
X928043Y751062D01*
G01X928033Y750958D02*
X928039Y751011D01*
G01X928027Y750903D02*
X928033Y750958D01*
G01X928019Y750845D02*
X928027Y750903D01*
G01X928010Y750786D02*
X928019Y750845D01*
G01X928010Y750786D02*
X927973Y750535D01*
G01X909449Y768406D02*
Y755453D01*
G01X928049Y751279D02*
X928045Y751315D01*
G01X928019Y751429D02*
X928009Y751451D01*
G01X927997Y751469D02*
X927984Y751485D01*
G01X927953Y751516D02*
X932677Y746870D01*
G01Y745767D02*
X927957Y750408D01*
G01X909449Y755453D02*
X936614D01*
G01X909449Y993917D02*
Y980965D01*
G01X927997Y997901D02*
X927984Y997886D01*
G01X928009Y997919D02*
X927997Y997901D01*
G01X928019Y997941D02*
X928009Y997919D01*
G01X928028Y997965D02*
X928019Y997941D01*
G01X928036Y997993D02*
X928028Y997965D01*
G01X928041Y998023D02*
X928036Y997993D01*
G01X928045Y998056D02*
X928041Y998023D01*
G01X928049Y998091D02*
X928045Y998056D01*
G01X928050Y998130D02*
X928049Y998091D01*
G01X928051Y998171D02*
X928050Y998130D01*
G01X928049Y998214D02*
X928051Y998171D01*
G01X928047Y998260D02*
X928049Y998214D01*
G01X928043Y998308D02*
X928047Y998260D01*
G01X928039Y998360D02*
X928043Y998308D01*
G01X928033Y998413D02*
X928039Y998360D01*
G01X928027Y998468D02*
X928033Y998413D01*
G01X928019Y998525D02*
X928027Y998468D01*
G01X928010Y998585D02*
X928019Y998525D01*
G01X927973Y998835D02*
X928010Y998585D01*
G01X927965Y998899D02*
X927973Y998835D01*
G01X927957Y998962D02*
X927965Y998899D01*
G01X928049Y998091D02*
X928050Y998130D01*
G01X927953Y1006201D02*
Y999036D01*
G01X927997Y997901D02*
X928009Y997919D01*
G01X932677Y1002500D02*
X927953Y997854D01*
G01X927957Y998962D02*
X932677Y1003603D01*
G01X936614Y993917D02*
X909449D01*
G01X925984Y1006201D02*
Y1148681D01*
G01X924803Y1011122D02*
Y1143760D01*
G01X924223Y1024154D02*
Y1025728D01*
G01Y1019154D02*
Y1020728D01*
G01Y1014154D02*
Y1015728D01*
G01X923541D02*
Y1014154D01*
G01Y1020728D02*
Y1019154D01*
G01Y1025728D02*
Y1024154D01*
G01X923031Y1024055D02*
Y1025827D01*
G01Y1019055D02*
Y1020827D01*
G01Y1014055D02*
Y1015827D01*
G01X919366Y1024154D02*
Y1025728D01*
G01Y1019154D02*
Y1020728D01*
G01Y1014154D02*
Y1015728D01*
G01X919120Y1024154D02*
Y1025728D01*
G01Y1019154D02*
Y1020728D01*
G01Y1014154D02*
Y1015728D01*
G01X918014D02*
Y1014154D01*
G01Y1020728D02*
Y1019154D01*
G01Y1025728D02*
Y1024154D01*
G01X924803Y1011122D02*
X925984Y1009941D01*
G01X924016Y1006201D02*
X925984Y1008169D01*
G01Y1006201D02*
X929267D01*
G01X924223Y1039154D02*
Y1040728D01*
G01Y1034154D02*
Y1035728D01*
G01Y1029154D02*
Y1030728D01*
G01X924102Y1044154D02*
Y1045728D01*
G01X924016Y1069646D02*
Y1045236D01*
G01X923541Y1030728D02*
Y1029154D01*
G01Y1035728D02*
Y1034154D01*
G01Y1040728D02*
Y1039154D01*
G01X923113Y1045728D02*
Y1044154D01*
G01X923031Y1044055D02*
Y1045827D01*
G01Y1039055D02*
Y1040827D01*
G01Y1034055D02*
Y1035827D01*
G01Y1029055D02*
Y1030827D01*
G01X919366Y1039154D02*
Y1040728D01*
G01Y1034154D02*
Y1035728D01*
G01Y1029154D02*
Y1030728D01*
G01Y1045728D02*
Y1044154D01*
G01X919120D02*
Y1045728D01*
G01Y1039154D02*
Y1040728D01*
G01Y1034154D02*
Y1035728D01*
G01Y1029154D02*
Y1030728D01*
G01X918014D02*
Y1029154D01*
G01Y1035728D02*
Y1034154D01*
G01Y1040728D02*
Y1039154D01*
G01Y1045728D02*
Y1044154D01*
G01X925984Y1045709D02*
X924016Y1047677D01*
G01X925787Y1066201D02*
Y1067579D01*
G01Y1048681D02*
Y1047303D01*
G01Y1051831D02*
Y1050453D01*
G01Y1058130D02*
Y1056752D01*
G01Y1054980D02*
Y1053603D01*
G01Y1061280D02*
Y1059902D01*
G01Y1064429D02*
Y1063051D01*
G01X922560Y1048583D02*
Y1047402D01*
G01Y1051732D02*
Y1050551D01*
G01Y1054882D02*
Y1053701D01*
G01Y1058032D02*
Y1056851D01*
G01Y1061181D02*
Y1060000D01*
G01Y1064331D02*
Y1063150D01*
G01Y1067480D02*
Y1066299D01*
G01X921823D02*
Y1067480D01*
G01Y1063150D02*
Y1064331D01*
G01Y1060000D02*
Y1061181D01*
G01Y1053701D02*
Y1054882D01*
G01Y1056851D02*
Y1058032D01*
G01Y1050551D02*
Y1051732D01*
G01Y1047402D02*
Y1048583D01*
G01X917008Y1063051D02*
Y1064429D01*
G01Y1059902D02*
Y1061280D01*
G01Y1053603D02*
Y1054980D01*
G01Y1056752D02*
Y1058130D01*
G01Y1050453D02*
Y1051831D01*
G01Y1048681D02*
Y1047303D01*
G01Y1067579D02*
Y1066201D01*
G01X916264Y1048583D02*
Y1047402D01*
G01Y1051732D02*
Y1050551D01*
G01Y1054882D02*
Y1053701D01*
G01Y1058032D02*
Y1056851D01*
G01Y1061181D02*
Y1060000D01*
G01Y1067480D02*
Y1066299D01*
G01Y1064331D02*
Y1063150D01*
G01X915767Y1066299D02*
Y1067480D01*
G01Y1063150D02*
Y1064331D01*
G01Y1060000D02*
Y1061181D01*
G01Y1056851D02*
Y1058032D01*
G01Y1053701D02*
Y1054882D01*
G01Y1050551D02*
Y1051732D01*
G01Y1047402D02*
Y1048583D01*
G01X913528D02*
Y1047402D01*
G01Y1051732D02*
Y1050551D01*
G01Y1054882D02*
Y1053701D01*
G01Y1058032D02*
Y1056851D01*
G01Y1061181D02*
Y1060000D01*
G01Y1064331D02*
Y1063150D01*
G01Y1067480D02*
Y1066299D01*
G01X924016Y1067205D02*
X925984Y1069173D01*
G01X925787Y1066201D02*
X925984D01*
G01Y1064429D02*
X925787D01*
G01Y1063051D02*
X925984D01*
G01Y1061280D02*
X925787D01*
G01Y1059902D02*
X925984D01*
G01Y1058130D02*
X925787D01*
G01Y1056752D02*
X925984D01*
G01Y1054980D02*
X925787D01*
G01Y1053603D02*
X925984D01*
G01Y1051831D02*
X925787D01*
G01Y1050453D02*
X925984D01*
G01Y1048681D02*
X925787D01*
G01Y1047303D02*
X925984D01*
G01X924223Y1084154D02*
Y1085728D01*
G01Y1079154D02*
Y1080728D01*
G01Y1074154D02*
Y1075728D01*
G01X924102Y1069154D02*
Y1070728D01*
G01X923541Y1075728D02*
Y1074154D01*
G01Y1080728D02*
Y1079154D01*
G01Y1085728D02*
Y1084154D01*
G01X923113Y1070728D02*
Y1069154D01*
G01X923031Y1084055D02*
Y1085827D01*
G01Y1079055D02*
Y1080827D01*
G01Y1074055D02*
Y1075827D01*
G01Y1069055D02*
Y1070827D01*
G01X919366Y1084154D02*
Y1085728D01*
G01Y1079154D02*
Y1080728D01*
G01Y1074154D02*
Y1075728D01*
G01Y1070728D02*
Y1069154D01*
G01X919120Y1084154D02*
Y1085728D01*
G01Y1079154D02*
Y1080728D01*
G01Y1074154D02*
Y1075728D01*
G01Y1069154D02*
Y1070728D01*
G01X918014D02*
Y1069154D01*
G01Y1075728D02*
Y1074154D01*
G01Y1080728D02*
Y1079154D01*
G01Y1085728D02*
Y1084154D01*
G01X925984Y1067579D02*
X925787D01*
G01X924223Y1109154D02*
Y1110728D01*
G01Y1104154D02*
Y1105728D01*
G01Y1099154D02*
Y1100728D01*
G01Y1094154D02*
Y1095728D01*
G01Y1089154D02*
Y1090728D01*
G01X923541D02*
Y1089154D01*
G01Y1095728D02*
Y1094154D01*
G01Y1100728D02*
Y1099154D01*
G01Y1105728D02*
Y1104154D01*
G01Y1110728D02*
Y1109154D01*
G01X923031Y1109055D02*
Y1110827D01*
G01Y1104055D02*
Y1105827D01*
G01Y1099055D02*
Y1100827D01*
G01Y1094055D02*
Y1095827D01*
G01Y1089055D02*
Y1090827D01*
G01X919366Y1109154D02*
Y1110728D01*
G01Y1104154D02*
Y1105728D01*
G01Y1099154D02*
Y1100728D01*
G01Y1094154D02*
Y1095728D01*
G01Y1089154D02*
Y1090728D01*
G01X919120Y1109154D02*
Y1110728D01*
G01Y1104154D02*
Y1105728D01*
G01Y1099154D02*
Y1100728D01*
G01Y1094154D02*
Y1095728D01*
G01Y1089154D02*
Y1090728D01*
G01X918014D02*
Y1089154D01*
G01Y1095728D02*
Y1094154D01*
G01Y1100728D02*
Y1099154D01*
G01Y1105728D02*
Y1104154D01*
G01Y1110728D02*
Y1109154D01*
G01X924223Y1129154D02*
Y1130728D01*
G01Y1124154D02*
Y1125728D01*
G01Y1119154D02*
Y1120728D01*
G01Y1114154D02*
Y1115728D01*
G01X923541D02*
Y1114154D01*
G01Y1120728D02*
Y1119154D01*
G01Y1125728D02*
Y1124154D01*
G01Y1130728D02*
Y1129154D01*
G01X923031Y1129055D02*
Y1130827D01*
G01Y1124055D02*
Y1125827D01*
G01Y1119055D02*
Y1120827D01*
G01Y1114055D02*
Y1115827D01*
G01X919366Y1129154D02*
Y1130728D01*
G01Y1124154D02*
Y1125728D01*
G01Y1119154D02*
Y1120728D01*
G01Y1114154D02*
Y1115728D01*
G01X919120Y1129154D02*
Y1130728D01*
G01Y1124154D02*
Y1125728D01*
G01Y1119154D02*
Y1120728D01*
G01Y1114154D02*
Y1115728D01*
G01X918014D02*
Y1114154D01*
G01Y1120728D02*
Y1119154D01*
G01Y1125728D02*
Y1124154D01*
G01Y1130728D02*
Y1129154D01*
G01X925984Y1146713D02*
X924016Y1148681D01*
G01X927953Y1155847D02*
Y1148681D01*
G01X924223Y1139154D02*
Y1140728D01*
G01Y1134154D02*
Y1135728D01*
G01X923541D02*
Y1134154D01*
G01Y1140728D02*
Y1139154D01*
G01X923031Y1139055D02*
Y1140827D01*
G01Y1134055D02*
Y1135827D01*
G01X919366Y1139154D02*
Y1140728D01*
G01Y1134154D02*
Y1135728D01*
G01X919120Y1139154D02*
Y1140728D01*
G01Y1134154D02*
Y1135728D01*
G01X918014D02*
Y1134154D01*
G01Y1140728D02*
Y1139154D01*
G01X924803Y1143760D02*
X925984Y1144941D01*
G01Y1148681D02*
X929267D01*
G01X927965Y1155983D02*
X927957Y1155920D01*
G01X927973Y1156047D02*
X927965Y1155983D01*
G01X928049Y1156668D02*
X928051Y1156712D01*
G01X928047Y1156622D02*
X928049Y1156668D01*
G01X928043Y1156573D02*
X928047Y1156622D01*
G01X928039Y1156523D02*
X928043Y1156573D01*
G01X928033Y1156469D02*
X928039Y1156523D01*
G01X928027Y1156414D02*
X928033Y1156469D01*
G01X928019Y1156357D02*
X928027Y1156414D01*
G01X928010Y1156297D02*
X928019Y1156357D01*
G01Y1156356D02*
X928010Y1156297D01*
G01X928027Y1156414D02*
X928019Y1156356D01*
G01X928033Y1156469D02*
X928027Y1156414D01*
G01X928039Y1156523D02*
X928033Y1156469D01*
G01X928043Y1156573D02*
X928039Y1156523D01*
G01X928047Y1156622D02*
X928043Y1156573D01*
G01X928049Y1156668D02*
X928047Y1156622D01*
G01X928051Y1156712D02*
X928049Y1156668D01*
G01X928050Y1156753D02*
X928051Y1156712D01*
G01X928049Y1156791D02*
X928050Y1156753D01*
G01X928046Y1156827D02*
X928049Y1156791D01*
G01X928041Y1156859D02*
X928046Y1156827D01*
G01X928036Y1156890D02*
X928041Y1156859D01*
G01X928028Y1156917D02*
X928036Y1156890D01*
G01X928019Y1156941D02*
X928028Y1156917D01*
G01X928009Y1156962D02*
X928019Y1156941D01*
G01X927997Y1156981D02*
X928009Y1156962D01*
G01X927984Y1156997D02*
X927997Y1156981D01*
G01X928019Y1156941D02*
X928009Y1156963D01*
G01X927997Y1156981D02*
X927984Y1156997D01*
G01X927953Y1157028D02*
X932677Y1152382D01*
G01Y1151278D02*
X927957Y1155920D01*
G01X928049Y1156791D02*
X928045Y1156827D01*
G01X928010Y1156297D02*
X927973Y1156047D01*
G01X909449Y1173917D02*
Y1160965D01*
G01D02*
X936614D01*
G01X928019Y1404037D02*
X928010Y1404097D01*
G01X928027Y1403980D02*
X928019Y1404037D01*
G01X928033Y1403925D02*
X928027Y1403980D01*
G01X928039Y1403871D02*
X928033Y1403925D01*
G01X928043Y1403821D02*
X928039Y1403871D01*
G01X928047Y1403772D02*
X928043Y1403821D01*
G01X928049Y1403726D02*
X928047Y1403772D01*
G01X928051Y1403682D02*
X928049Y1403726D01*
G01X928050Y1403641D02*
X928051Y1403682D01*
G01X928049Y1403603D02*
X928050Y1403641D01*
G01X927997Y1403413D02*
X927984Y1403397D01*
G01X928009Y1403431D02*
X927997Y1403413D01*
G01X928019Y1403453D02*
X928009Y1403431D01*
G01X928028Y1403477D02*
X928019Y1403453D01*
G01X928036Y1403504D02*
X928028Y1403477D01*
G01X928041Y1403534D02*
X928036Y1403504D01*
G01X928045Y1403567D02*
X928041Y1403534D01*
G01X928049Y1403603D02*
X928045Y1403567D01*
G01X928050Y1403641D02*
X928049Y1403603D01*
G01X928051Y1403682D02*
X928050Y1403641D01*
G01X928049Y1403726D02*
X928051Y1403682D01*
G01X928047Y1403772D02*
X928049Y1403726D01*
G01X928043Y1403820D02*
X928047Y1403772D01*
G01X928039Y1403871D02*
X928043Y1403820D01*
G01X928033Y1403925D02*
X928039Y1403871D01*
G01X928027Y1403980D02*
X928033Y1403925D01*
G01X928019Y1404037D02*
X928027Y1403980D01*
G01X928010Y1404097D02*
X928019Y1404037D01*
G01X927973Y1404347D02*
X928010Y1404097D01*
G01X927965Y1404411D02*
X927973Y1404347D01*
G01X927957Y1404474D02*
X927965Y1404411D01*
G01X936614Y1399429D02*
X909449D01*
G01X927953Y1411713D02*
Y1404547D01*
G01X909449Y1399429D02*
Y1386477D01*
G01X927997Y1403413D02*
X928009Y1403431D01*
G01X932677Y1408012D02*
X927953Y1403366D01*
G01X927957Y1404474D02*
X932677Y1409115D01*
G01X924803Y1416634D02*
X925984Y1415453D01*
G01Y1411713D02*
X929267D01*
G01X925984D02*
Y1554193D01*
G01X924803Y1416634D02*
Y1549272D01*
G01X924223Y1424666D02*
Y1426240D01*
G01Y1419666D02*
Y1421240D01*
G01X923541D02*
Y1419666D01*
G01Y1426240D02*
Y1424666D01*
G01X923031Y1424567D02*
Y1426339D01*
G01Y1419567D02*
Y1421339D01*
G01X919366Y1424666D02*
Y1426240D01*
G01Y1419666D02*
Y1421240D01*
G01X919120Y1424666D02*
Y1426240D01*
G01Y1419666D02*
Y1421240D01*
G01X918014D02*
Y1419666D01*
G01Y1426240D02*
Y1424666D01*
G01X924016Y1411713D02*
X925984Y1413681D01*
G01X924223Y1444666D02*
Y1446240D01*
G01Y1439666D02*
Y1441240D01*
G01Y1434666D02*
Y1436240D01*
G01Y1429666D02*
Y1431240D01*
G01X923541D02*
Y1429666D01*
G01Y1436240D02*
Y1434666D01*
G01Y1441240D02*
Y1439666D01*
G01Y1446240D02*
Y1444666D01*
G01X923031Y1444567D02*
Y1446339D01*
G01Y1439567D02*
Y1441339D01*
G01Y1434567D02*
Y1436339D01*
G01Y1429567D02*
Y1431339D01*
G01X919366Y1444666D02*
Y1446240D01*
G01Y1439666D02*
Y1441240D01*
G01Y1434666D02*
Y1436240D01*
G01Y1429666D02*
Y1431240D01*
G01X919120Y1444666D02*
Y1446240D01*
G01Y1439666D02*
Y1441240D01*
G01Y1434666D02*
Y1436240D01*
G01Y1429666D02*
Y1431240D01*
G01X918014D02*
Y1429666D01*
G01Y1436240D02*
Y1434666D01*
G01Y1441240D02*
Y1439666D01*
G01Y1446240D02*
Y1444666D01*
G01X925984Y1451221D02*
X924016Y1453189D01*
G01X925787Y1468563D02*
X925984D01*
G01Y1466791D02*
X925787D01*
G01Y1465414D02*
X925984D01*
G01Y1463642D02*
X925787D01*
G01Y1462264D02*
X925984D01*
G01Y1460492D02*
X925787D01*
G01Y1459114D02*
X925984D01*
G01Y1457343D02*
X925787D01*
G01Y1455965D02*
X925984D01*
G01Y1454193D02*
X925787D01*
G01Y1452815D02*
X925984D01*
G01X925787Y1454193D02*
Y1452815D01*
G01Y1460492D02*
Y1459114D01*
G01Y1457343D02*
Y1455965D01*
G01Y1463642D02*
Y1462264D01*
G01Y1469941D02*
Y1468563D01*
G01Y1466791D02*
Y1465414D01*
G01X924102Y1449666D02*
Y1451240D01*
G01X924016Y1475158D02*
Y1450748D01*
G01X923113Y1451240D02*
Y1449666D01*
G01X923031Y1449567D02*
Y1451339D01*
G01X922560Y1454095D02*
Y1452914D01*
G01Y1457244D02*
Y1456063D01*
G01Y1460394D02*
Y1459213D01*
G01Y1463543D02*
Y1462362D01*
G01Y1466693D02*
Y1465512D01*
G01Y1469843D02*
Y1468662D01*
G01X921823Y1465512D02*
Y1466693D01*
G01Y1468662D02*
Y1469843D01*
G01Y1462362D02*
Y1463543D01*
G01Y1459213D02*
Y1460394D01*
G01Y1456063D02*
Y1457244D01*
G01Y1452914D02*
Y1454095D01*
G01X919366Y1451240D02*
Y1449666D01*
G01X919120D02*
Y1451240D01*
G01X918014D02*
Y1449666D01*
G01X917008Y1465414D02*
Y1466791D01*
G01Y1468563D02*
Y1469941D01*
G01Y1462264D02*
Y1463642D01*
G01Y1455965D02*
Y1457343D01*
G01Y1459114D02*
Y1460492D01*
G01Y1454193D02*
Y1452815D01*
G01X916264Y1454095D02*
Y1452914D01*
G01Y1460394D02*
Y1459213D01*
G01Y1457244D02*
Y1456063D01*
G01Y1463543D02*
Y1462362D01*
G01Y1466693D02*
Y1465512D01*
G01Y1469843D02*
Y1468662D01*
G01X915767D02*
Y1469843D01*
G01Y1465512D02*
Y1466693D01*
G01Y1462362D02*
Y1463543D01*
G01Y1459213D02*
Y1460394D01*
G01Y1456063D02*
Y1457244D01*
G01Y1452914D02*
Y1454095D01*
G01X913528D02*
Y1452914D01*
G01Y1457244D02*
Y1456063D01*
G01Y1460394D02*
Y1459213D01*
G01Y1463543D02*
Y1462362D01*
G01Y1466693D02*
Y1465512D01*
G01Y1469843D02*
Y1468662D01*
G01X925984Y1473091D02*
X925787D01*
G01Y1471713D02*
X925984D01*
G01Y1469941D02*
X925787D01*
G01Y1471713D02*
Y1473091D01*
G01X924223Y1489666D02*
Y1491240D01*
G01Y1484666D02*
Y1486240D01*
G01Y1479666D02*
Y1481240D01*
G01X924102Y1474666D02*
Y1476240D01*
G01X923541Y1481240D02*
Y1479666D01*
G01Y1486240D02*
Y1484666D01*
G01Y1491240D02*
Y1489666D01*
G01X923113Y1476240D02*
Y1474666D01*
G01X923031Y1489567D02*
Y1491339D01*
G01Y1484567D02*
Y1486339D01*
G01Y1479567D02*
Y1481339D01*
G01Y1474567D02*
Y1476339D01*
G01X922560Y1472992D02*
Y1471811D01*
G01X921823D02*
Y1472992D01*
G01X919366Y1489666D02*
Y1491240D01*
G01Y1484666D02*
Y1486240D01*
G01Y1479666D02*
Y1481240D01*
G01Y1476240D02*
Y1474666D01*
G01X919120Y1489666D02*
Y1491240D01*
G01Y1484666D02*
Y1486240D01*
G01Y1479666D02*
Y1481240D01*
G01Y1474666D02*
Y1476240D01*
G01X918014D02*
Y1474666D01*
G01Y1481240D02*
Y1479666D01*
G01Y1486240D02*
Y1484666D01*
G01Y1491240D02*
Y1489666D01*
G01X917008Y1473091D02*
Y1471713D01*
G01X916264Y1472992D02*
Y1471811D01*
G01X915767D02*
Y1472992D01*
G01X913528D02*
Y1471811D01*
G01X924016Y1472717D02*
X925984Y1474685D01*
G01X924223Y1509666D02*
Y1511240D01*
G01Y1504666D02*
Y1506240D01*
G01Y1499666D02*
Y1501240D01*
G01Y1494666D02*
Y1496240D01*
G01X923541D02*
Y1494666D01*
G01Y1501240D02*
Y1499666D01*
G01Y1506240D02*
Y1504666D01*
G01Y1511240D02*
Y1509666D01*
G01X923031Y1509567D02*
Y1511339D01*
G01Y1504567D02*
Y1506339D01*
G01Y1499567D02*
Y1501339D01*
G01Y1494567D02*
Y1496339D01*
G01X919366Y1509666D02*
Y1511240D01*
G01Y1504666D02*
Y1506240D01*
G01Y1499666D02*
Y1501240D01*
G01Y1494666D02*
Y1496240D01*
G01X919120Y1509666D02*
Y1511240D01*
G01Y1504666D02*
Y1506240D01*
G01Y1499666D02*
Y1501240D01*
G01Y1494666D02*
Y1496240D01*
G01X918014D02*
Y1494666D01*
G01Y1501240D02*
Y1499666D01*
G01Y1506240D02*
Y1504666D01*
G01Y1511240D02*
Y1509666D01*
G01X924223Y1529666D02*
Y1531240D01*
G01Y1524666D02*
Y1526240D01*
G01Y1519666D02*
Y1521240D01*
G01Y1514666D02*
Y1516240D01*
G01X923541D02*
Y1514666D01*
G01Y1521240D02*
Y1519666D01*
G01Y1526240D02*
Y1524666D01*
G01Y1531240D02*
Y1529666D01*
G01X923031Y1529567D02*
Y1531339D01*
G01Y1524567D02*
Y1526339D01*
G01Y1519567D02*
Y1521339D01*
G01Y1514567D02*
Y1516339D01*
G01X919366Y1529666D02*
Y1531240D01*
G01Y1524666D02*
Y1526240D01*
G01Y1519666D02*
Y1521240D01*
G01Y1514666D02*
Y1516240D01*
G01X919120Y1529666D02*
Y1531240D01*
G01Y1524666D02*
Y1526240D01*
G01Y1519666D02*
Y1521240D01*
G01Y1514666D02*
Y1516240D01*
G01X918014D02*
Y1514666D01*
G01Y1521240D02*
Y1519666D01*
G01Y1526240D02*
Y1524666D01*
G01Y1531240D02*
Y1529666D01*
G01X925984Y1552225D02*
X924016Y1554193D01*
G01X924223Y1544666D02*
Y1546240D01*
G01Y1539666D02*
Y1541240D01*
G01Y1534666D02*
Y1536240D01*
G01X923541D02*
Y1534666D01*
G01Y1541240D02*
Y1539666D01*
G01Y1546240D02*
Y1544666D01*
G01X923031Y1544567D02*
Y1546339D01*
G01Y1539567D02*
Y1541339D01*
G01Y1534567D02*
Y1536339D01*
G01X919366Y1544666D02*
Y1546240D01*
G01Y1539666D02*
Y1541240D01*
G01Y1534666D02*
Y1536240D01*
G01X919120Y1544666D02*
Y1546240D01*
G01Y1539666D02*
Y1541240D01*
G01Y1534666D02*
Y1536240D01*
G01X918014D02*
Y1534666D01*
G01Y1541240D02*
Y1539666D01*
G01Y1546240D02*
Y1544666D01*
G01X924803Y1549272D02*
X925984Y1550453D01*
G01X927965Y1561495D02*
X927957Y1561432D01*
G01X927973Y1561559D02*
X927965Y1561495D01*
G01X928049Y1562180D02*
X928051Y1562223D01*
G01X928047Y1562134D02*
X928049Y1562180D01*
G01X928043Y1562085D02*
X928047Y1562134D01*
G01X928039Y1562034D02*
X928043Y1562085D01*
G01X928033Y1561981D02*
X928039Y1562034D01*
G01X928027Y1561926D02*
X928033Y1561981D01*
G01X928019Y1561869D02*
X928027Y1561926D01*
G01X928010Y1561809D02*
X928019Y1561869D01*
G01Y1561868D02*
X928010Y1561809D01*
G01X928027Y1561926D02*
X928019Y1561868D01*
G01X928033Y1561981D02*
X928027Y1561926D01*
G01X928039Y1562034D02*
X928033Y1561981D01*
G01X928043Y1562085D02*
X928039Y1562034D01*
G01X928047Y1562134D02*
X928043Y1562085D01*
G01X928049Y1562180D02*
X928047Y1562134D01*
G01X928051Y1562223D02*
X928049Y1562180D01*
G01X928050Y1562264D02*
X928051Y1562223D01*
G01X928049Y1562303D02*
X928050Y1562264D01*
G01X928046Y1562338D02*
X928049Y1562303D01*
G01X928041Y1562371D02*
X928046Y1562338D01*
G01X928036Y1562401D02*
X928041Y1562371D01*
G01X928028Y1562428D02*
X928036Y1562401D01*
G01X928019Y1562453D02*
X928028Y1562428D01*
G01X928009Y1562474D02*
X928019Y1562453D01*
G01X927997Y1562493D02*
X928009Y1562474D01*
G01X927984Y1562508D02*
X927997Y1562493D01*
G01D02*
X927984Y1562508D01*
G01X927953Y1562540D02*
X932677Y1557894D01*
G01Y1556790D02*
X927957Y1561432D01*
G01X928019Y1562453D02*
X928009Y1562475D01*
G01X909449Y1566477D02*
X936614D01*
G01X925984Y1554193D02*
X929267D01*
G01X927953Y1561358D02*
Y1554193D01*
G01X928049Y1562303D02*
X928045Y1562338D01*
G01X928010Y1561809D02*
X927973Y1561559D01*
G01X909449Y1579429D02*
Y1566477D01*
G01X936614Y1804941D02*
X909449D01*
G01D02*
Y1791988D01*
G01X928019Y1809549D02*
X928010Y1809608D01*
G01X928027Y1809491D02*
X928019Y1809549D01*
G01X928033Y1809436D02*
X928027Y1809491D01*
G01X928039Y1809383D02*
X928033Y1809436D01*
G01X928043Y1809332D02*
X928039Y1809383D01*
G01X928047Y1809284D02*
X928043Y1809332D01*
G01X928049Y1809238D02*
X928047Y1809284D01*
G01X928051Y1809194D02*
X928049Y1809238D01*
G01X928050Y1809153D02*
X928051Y1809194D01*
G01X928049Y1809115D02*
X928050Y1809153D01*
G01X927997Y1808925D02*
X927984Y1808909D01*
G01X928009Y1808943D02*
X927997Y1808925D01*
G01X928019Y1808964D02*
X928009Y1808943D01*
G01X928028Y1808989D02*
X928019Y1808964D01*
G01X928036Y1809016D02*
X928028Y1808989D01*
G01X928041Y1809046D02*
X928036Y1809016D01*
G01X928045Y1809079D02*
X928041Y1809046D01*
G01X928049Y1809115D02*
X928045Y1809079D01*
G01X928050Y1809153D02*
X928049Y1809115D01*
G01X928051Y1809194D02*
X928050Y1809153D01*
G01X928049Y1809238D02*
X928051Y1809194D01*
G01X928047Y1809284D02*
X928049Y1809238D01*
G01X928043Y1809332D02*
X928047Y1809284D01*
G01X928039Y1809383D02*
X928043Y1809332D01*
G01X928033Y1809436D02*
X928039Y1809383D01*
G01X928027Y1809491D02*
X928033Y1809436D01*
G01X928019Y1809549D02*
X928027Y1809491D01*
G01X928010Y1809608D02*
X928019Y1809549D01*
G01X927973Y1809859D02*
X928010Y1809608D01*
G01X927965Y1809923D02*
X927973Y1809859D01*
G01X927957Y1809986D02*
X927965Y1809923D01*
G01X924803Y1822146D02*
X925984Y1820965D01*
G01Y1817225D02*
X929267D01*
G01X927983Y1809795D02*
X927973Y1809859D01*
G01X927953Y1817225D02*
Y1810059D01*
G01X925984Y1817225D02*
Y1959705D01*
G01X924803Y1822146D02*
Y1954784D01*
G01X924223Y1825177D02*
Y1826752D01*
G01X923541D02*
Y1825177D01*
G01X923031Y1825079D02*
Y1826851D01*
G01X919366Y1825177D02*
Y1826752D01*
G01X919120Y1825177D02*
Y1826752D01*
G01X918014D02*
Y1825177D01*
G01X927997Y1808925D02*
X928009Y1808943D01*
G01X932677Y1813524D02*
X927953Y1808878D01*
G01X927957Y1809986D02*
X932677Y1814627D01*
G01X924016Y1817225D02*
X925984Y1819193D01*
G01X924223Y1845177D02*
Y1846752D01*
G01Y1840177D02*
Y1841752D01*
G01Y1835177D02*
Y1836752D01*
G01Y1830177D02*
Y1831752D01*
G01X923541D02*
Y1830177D01*
G01Y1836752D02*
Y1835177D01*
G01Y1841752D02*
Y1840177D01*
G01Y1846752D02*
Y1845177D01*
G01X923031Y1845079D02*
Y1846851D01*
G01Y1840079D02*
Y1841851D01*
G01Y1835079D02*
Y1836851D01*
G01Y1830079D02*
Y1831851D01*
G01X919366Y1845177D02*
Y1846752D01*
G01Y1840177D02*
Y1841752D01*
G01Y1835177D02*
Y1836752D01*
G01Y1830177D02*
Y1831752D01*
G01X919120Y1845177D02*
Y1846752D01*
G01Y1840177D02*
Y1841752D01*
G01Y1835177D02*
Y1836752D01*
G01Y1830177D02*
Y1831752D01*
G01X918014D02*
Y1830177D01*
G01Y1836752D02*
Y1835177D01*
G01Y1841752D02*
Y1840177D01*
G01Y1846752D02*
Y1845177D01*
G01X925984Y1856732D02*
X924016Y1858701D01*
G01X925787Y1870925D02*
X925984D01*
G01Y1869154D02*
X925787D01*
G01Y1867776D02*
X925984D01*
G01Y1866004D02*
X925787D01*
G01Y1864626D02*
X925984D01*
G01Y1862854D02*
X925787D01*
G01Y1861477D02*
X925984D01*
G01Y1859705D02*
X925787D01*
G01Y1858327D02*
X925984D01*
G01X925787Y1859705D02*
Y1858327D01*
G01Y1862854D02*
Y1861477D01*
G01Y1866004D02*
Y1864626D01*
G01Y1872303D02*
Y1870925D01*
G01Y1869154D02*
Y1867776D01*
G01X924223Y1850177D02*
Y1851752D01*
G01X924102Y1855177D02*
Y1856752D01*
G01X924016Y1880669D02*
Y1856260D01*
G01X923541Y1851752D02*
Y1850177D01*
G01X923113Y1856752D02*
Y1855177D01*
G01X923031Y1855079D02*
Y1856851D01*
G01Y1850079D02*
Y1851851D01*
G01X922560Y1859606D02*
Y1858425D01*
G01Y1862756D02*
Y1861575D01*
G01Y1865906D02*
Y1864725D01*
G01Y1869055D02*
Y1867874D01*
G01Y1872205D02*
Y1871024D01*
G01X921823D02*
Y1872205D01*
G01Y1864725D02*
Y1865906D01*
G01Y1867874D02*
Y1869055D01*
G01Y1861575D02*
Y1862756D01*
G01Y1858425D02*
Y1859606D01*
G01X919366Y1850177D02*
Y1851752D01*
G01Y1856752D02*
Y1855177D01*
G01X919120D02*
Y1856752D01*
G01Y1850177D02*
Y1851752D01*
G01X918014D02*
Y1850177D01*
G01Y1856752D02*
Y1855177D01*
G01X917008Y1867776D02*
Y1869154D01*
G01Y1870925D02*
Y1872303D01*
G01Y1864626D02*
Y1866004D01*
G01Y1861477D02*
Y1862854D01*
G01Y1859705D02*
Y1858327D01*
G01X916264Y1859606D02*
Y1858425D01*
G01Y1862756D02*
Y1861575D01*
G01Y1865906D02*
Y1864725D01*
G01Y1869055D02*
Y1867874D01*
G01Y1872205D02*
Y1871024D01*
G01X915767D02*
Y1872205D01*
G01Y1867874D02*
Y1869055D01*
G01Y1864725D02*
Y1865906D01*
G01Y1861575D02*
Y1862756D01*
G01Y1858425D02*
Y1859606D01*
G01X913528D02*
Y1858425D01*
G01Y1862756D02*
Y1861575D01*
G01Y1865906D02*
Y1864725D01*
G01Y1869055D02*
Y1867874D01*
G01Y1872205D02*
Y1871024D01*
G01X925984Y1878603D02*
X925787D01*
G01Y1877225D02*
X925984D01*
G01Y1875453D02*
X925787D01*
G01Y1874075D02*
X925984D01*
G01Y1872303D02*
X925787D01*
G01Y1877225D02*
Y1878603D01*
G01Y1875453D02*
Y1874075D01*
G01X924223Y1890177D02*
Y1891752D01*
G01Y1885177D02*
Y1886752D01*
G01X924102Y1880177D02*
Y1881752D01*
G01X923541Y1886752D02*
Y1885177D01*
G01Y1891752D02*
Y1890177D01*
G01X923113Y1881752D02*
Y1880177D01*
G01X923031Y1890079D02*
Y1891851D01*
G01Y1885079D02*
Y1886851D01*
G01Y1880079D02*
Y1881851D01*
G01X922560Y1875354D02*
Y1874173D01*
G01Y1878504D02*
Y1877323D01*
G01X921823D02*
Y1878504D01*
G01Y1874173D02*
Y1875354D01*
G01X919366Y1890177D02*
Y1891752D01*
G01Y1885177D02*
Y1886752D01*
G01Y1881752D02*
Y1880177D01*
G01X919120Y1890177D02*
Y1891752D01*
G01Y1885177D02*
Y1886752D01*
G01Y1880177D02*
Y1881752D01*
G01X918014D02*
Y1880177D01*
G01Y1886752D02*
Y1885177D01*
G01Y1891752D02*
Y1890177D01*
G01X917008Y1874075D02*
Y1875453D01*
G01Y1878603D02*
Y1877225D01*
G01X916264Y1875354D02*
Y1874173D01*
G01Y1878504D02*
Y1877323D01*
G01X915767D02*
Y1878504D01*
G01Y1874173D02*
Y1875354D01*
G01X913528D02*
Y1874173D01*
G01Y1878504D02*
Y1877323D01*
G01X924016Y1878228D02*
X925984Y1880197D01*
G01X924223Y1910177D02*
Y1911752D01*
G01Y1905177D02*
Y1906752D01*
G01Y1900177D02*
Y1901752D01*
G01Y1895177D02*
Y1896752D01*
G01X923541D02*
Y1895177D01*
G01Y1901752D02*
Y1900177D01*
G01Y1906752D02*
Y1905177D01*
G01Y1911752D02*
Y1910177D01*
G01X923031Y1910079D02*
Y1911851D01*
G01Y1905079D02*
Y1906851D01*
G01Y1900079D02*
Y1901851D01*
G01Y1895079D02*
Y1896851D01*
G01X919366Y1910177D02*
Y1911752D01*
G01Y1905177D02*
Y1906752D01*
G01Y1900177D02*
Y1901752D01*
G01Y1895177D02*
Y1896752D01*
G01X919120Y1910177D02*
Y1911752D01*
G01Y1905177D02*
Y1906752D01*
G01Y1900177D02*
Y1901752D01*
G01Y1895177D02*
Y1896752D01*
G01X918014D02*
Y1895177D01*
G01Y1901752D02*
Y1900177D01*
G01Y1906752D02*
Y1905177D01*
G01Y1911752D02*
Y1910177D01*
G01X924223Y1930177D02*
Y1931752D01*
G01Y1925177D02*
Y1926752D01*
G01Y1920177D02*
Y1921752D01*
G01Y1915177D02*
Y1916752D01*
G01X923541D02*
Y1915177D01*
G01Y1921752D02*
Y1920177D01*
G01Y1926752D02*
Y1925177D01*
G01Y1931752D02*
Y1930177D01*
G01X923031Y1930079D02*
Y1931851D01*
G01Y1925079D02*
Y1926851D01*
G01Y1920079D02*
Y1921851D01*
G01Y1915079D02*
Y1916851D01*
G01X919366Y1930177D02*
Y1931752D01*
G01Y1925177D02*
Y1926752D01*
G01Y1920177D02*
Y1921752D01*
G01Y1915177D02*
Y1916752D01*
G01X919120Y1930177D02*
Y1931752D01*
G01Y1925177D02*
Y1926752D01*
G01Y1920177D02*
Y1921752D01*
G01Y1915177D02*
Y1916752D01*
G01X918014D02*
Y1915177D01*
G01Y1921752D02*
Y1920177D01*
G01Y1926752D02*
Y1925177D01*
G01Y1931752D02*
Y1930177D01*
G01X924223Y1950177D02*
Y1951752D01*
G01Y1945177D02*
Y1946752D01*
G01Y1940177D02*
Y1941752D01*
G01Y1935177D02*
Y1936752D01*
G01X923541D02*
Y1935177D01*
G01Y1941752D02*
Y1940177D01*
G01Y1946752D02*
Y1945177D01*
G01Y1951752D02*
Y1950177D01*
G01X923031Y1950079D02*
Y1951851D01*
G01Y1945079D02*
Y1946851D01*
G01Y1940079D02*
Y1941851D01*
G01Y1935079D02*
Y1936851D01*
G01X919366Y1950177D02*
Y1951752D01*
G01Y1945177D02*
Y1946752D01*
G01Y1940177D02*
Y1941752D01*
G01Y1935177D02*
Y1936752D01*
G01X919120Y1950177D02*
Y1951752D01*
G01Y1945177D02*
Y1946752D01*
G01Y1940177D02*
Y1941752D01*
G01Y1935177D02*
Y1936752D01*
G01X918014D02*
Y1935177D01*
G01Y1941752D02*
Y1940177D01*
G01Y1946752D02*
Y1945177D01*
G01Y1951752D02*
Y1950177D01*
G01X924803Y1954784D02*
X925984Y1955965D01*
G01X927965Y1967007D02*
X927957Y1966944D01*
G01X927973Y1967071D02*
X927965Y1967007D01*
G01X928049Y1967691D02*
X928051Y1967735D01*
G01X928047Y1967645D02*
X928049Y1967691D01*
G01X928043Y1967597D02*
X928047Y1967645D01*
G01X928039Y1967546D02*
X928043Y1967597D01*
G01X928033Y1967493D02*
X928039Y1967546D01*
G01X928027Y1967438D02*
X928033Y1967493D01*
G01X928019Y1967380D02*
X928027Y1967438D01*
G01X928010Y1967321D02*
X928019Y1967380D01*
G01D02*
X928010Y1967321D01*
G01X928027Y1967438D02*
X928019Y1967380D01*
G01X928033Y1967493D02*
X928027Y1967438D01*
G01X928039Y1967546D02*
X928033Y1967493D01*
G01X928043Y1967597D02*
X928039Y1967546D01*
G01X928047Y1967645D02*
X928043Y1967597D01*
G01X928049Y1967691D02*
X928047Y1967645D01*
G01X928051Y1967735D02*
X928049Y1967691D01*
G01X928050Y1967776D02*
X928051Y1967735D01*
G01X928049Y1967814D02*
X928050Y1967776D01*
G01X928046Y1967850D02*
X928049Y1967814D01*
G01X928041Y1967883D02*
X928046Y1967850D01*
G01X928036Y1967913D02*
X928041Y1967883D01*
G01X928028Y1967940D02*
X928036Y1967913D01*
G01X928019Y1967965D02*
X928028Y1967940D01*
G01X928009Y1967986D02*
X928019Y1967965D01*
G01X927997Y1968004D02*
X928009Y1967986D01*
G01X927984Y1968020D02*
X927997Y1968004D01*
G01D02*
X927984Y1968020D01*
G01X925984Y1957736D02*
X924016Y1959705D01*
G01X927953Y1968051D02*
X932677Y1963406D01*
G01Y1962302D02*
X927957Y1966944D01*
G01X909449Y1971988D02*
X936614D01*
G01X925984Y1959705D02*
X929267D01*
G01X928019Y1967965D02*
X928009Y1967986D01*
G01X928049Y1967814D02*
X928045Y1967850D01*
G01X927953Y1966870D02*
Y1959705D01*
G01X909449Y1984941D02*
Y1971988D01*
G01X927983Y1967134D02*
X928002Y1967260D01*
G01X928010Y1967321D02*
X927973Y1967071D01*
G01X936614Y182894D02*
Y349941D01*
G01X932677Y191477D02*
Y193209D01*
G01D02*
X929267Y195177D01*
G01Y337658D02*
X932677Y339626D01*
G01D02*
Y341358D01*
G01X936614Y588406D02*
Y755453D01*
G01X932677Y596988D02*
Y598721D01*
G01D02*
X929267Y600689D01*
G01Y743169D02*
X932677Y745138D01*
G01D02*
Y746870D01*
G01X936614Y993917D02*
Y1160965D01*
G01X932677Y1002500D02*
Y1004232D01*
G01D02*
X929267Y1006201D01*
G01X932677Y1150650D02*
Y1152382D01*
G01X929267Y1148681D02*
X932677Y1150650D01*
G01X936614Y1399429D02*
Y1566477D01*
G01X932677Y1409744D02*
X929267Y1411713D01*
G01X932677Y1408012D02*
Y1409744D01*
G01Y1556162D02*
Y1557894D01*
G01X929267Y1554193D02*
X932677Y1556162D01*
G01X936614Y1804941D02*
Y1971988D01*
G01X932677Y1815256D02*
X929267Y1817225D01*
G01X932677Y1813524D02*
Y1815256D01*
G01Y1961673D02*
Y1963406D01*
G01X929267Y1959705D02*
X932677Y1961673D01*
G01X1009842Y149606D02*
G03I-15748J0D01*
G01X1001082D02*
G03I-6988J0D01*
G01X1009842Y673228D02*
G03I-15748J0D01*
G01X1001082D02*
G03I-6988J0D01*
G01Y1068898D02*
G03I-6988J0D01*
G01X1009842D02*
G03I-15748J0D01*
G01X989816Y1436583D02*
X989564Y1436912D01*
G01X990067Y1436993D02*
X990234Y1436829D01*
G01X991072Y1435599D02*
X991658Y1435107D01*
G01X990988D02*
X990402Y1435599D01*
G01X990151Y1436337D02*
X989816Y1436583D01*
G01X989564Y1436912D02*
X989480Y1437321D01*
G01X989983Y1437240D02*
X990067Y1436993D01*
G01X990234Y1436829D02*
X990486Y1436747D01*
G01X990402Y1436255D02*
X990151Y1436337D01*
G01X991240Y1437240D02*
Y1438798D01*
G01X989983D02*
Y1437240D01*
G01X989480Y1437321D02*
Y1438798D01*
G01X987721D02*
Y1439290D01*
G01Y1434615D02*
Y1435107D01*
G01Y1439290D02*
X991658D01*
G01X989480Y1438798D02*
X987721D01*
G01X991240D02*
X989983D01*
G01X990486Y1436747D02*
X990737D01*
G01Y1436255D02*
X990402D01*
G01Y1435599D02*
X991072D01*
G01X987721Y1435107D02*
X990988D01*
G01X991658Y1434615D02*
X987721D01*
G01X991156Y1436993D02*
X991240Y1437240D01*
G01X991575Y1436912D02*
X991323Y1436583D01*
G01X990988Y1436829D02*
X991156Y1436993D01*
G01X991323Y1436583D02*
X990988Y1436337D01*
G01D02*
X990737Y1436255D01*
G01Y1436747D02*
X990988Y1436829D01*
G01X989744Y1616083D02*
G03Y1611870I0J-2107D01*
G01Y1616083D02*
G03Y1611870I0J-2107D01*
G01X991732Y1616083D02*
X989744D01*
G01X991732D02*
X989744D01*
G01Y1611870D02*
X991732D01*
G01X989744D02*
X991732D01*
G01X1001968Y1889764D02*
G03I-7874J0D01*
G01X1009842D02*
G03I-15748J0D01*
G01X1015889Y-66238D02*
X1016174Y-63767D01*
X1016602Y-61675D01*
X1017172Y-59774D01*
X1017885Y-57683D01*
X1019026Y-54831D01*
X1013322D01*
G01X1004488Y1403228D02*
G03X1006456Y1401260I1968J0D01*
G01X1008425D02*
Y1430788D01*
G01X1004488Y1428819D02*
Y1403228D01*
G01X1006456Y1401260D02*
X1032047D01*
G01X1026575Y1416024D02*
G03I-7284J0D01*
G01D02*
G03I-7284J0D01*
G01X1026968D02*
G03I-7677J0D01*
G01X992782Y1438844D02*
X992716Y1438465D01*
G01X992966Y1439160D02*
X992782Y1438844D01*
G01X993240Y1439373D02*
X992966Y1439160D01*
G01X993569Y1439449D02*
X993240Y1439373D01*
G01X994421D02*
X994750Y1439449D01*
G01X994147Y1439160D02*
X994421Y1439373D01*
G01X993964Y1438844D02*
X994147Y1439160D01*
G01X993897Y1438465D02*
X993964Y1438844D01*
G01Y1435802D02*
X993897Y1436181D01*
G01X994147Y1435485D02*
X993964Y1435802D01*
G01X994421Y1435273D02*
X994147Y1435485D01*
G01X994750Y1435197D02*
X994421Y1435273D01*
G01X993240D02*
X993569Y1435197D01*
G01X992966Y1435485D02*
X993240Y1435273D01*
G01X992782Y1435802D02*
X992966Y1435485D01*
G01X992716Y1436181D02*
X992782Y1435802D01*
G01X993240Y1445273D02*
X993569Y1445197D01*
G01X992966Y1445485D02*
X993240Y1445273D01*
G01X992782Y1445802D02*
X992966Y1445485D01*
G01X992716Y1446181D02*
X992782Y1445802D01*
G01X993964D02*
X993897Y1446181D01*
G01X994147Y1445485D02*
X993964Y1445802D01*
G01X994421Y1445273D02*
X994147Y1445485D01*
G01X994750Y1445197D02*
X994421Y1445273D01*
G01X1006456Y1430788D02*
G03X1004488Y1428819I1J-1969D01*
G01X1011726Y1439449D02*
Y1435197D01*
G01Y1449449D02*
Y1445197D01*
G01X1011123Y1439449D02*
Y1435197D01*
G01Y1449449D02*
Y1445197D01*
G01X1010520D02*
Y1449449D01*
G01Y1435197D02*
Y1439449D01*
G01X1001398D02*
Y1435197D01*
G01Y1449449D02*
Y1445197D01*
G01X1000795Y1439449D02*
Y1435197D01*
G01Y1449449D02*
Y1445197D01*
G01X999606D02*
Y1449449D01*
G01Y1435197D02*
Y1439449D01*
G01X998425D02*
Y1435197D01*
G01Y1449449D02*
Y1445197D01*
G01X993897Y1438465D02*
Y1436181D01*
G01Y1448465D02*
Y1446181D01*
G01X992716Y1438465D02*
Y1436181D01*
G01Y1448465D02*
Y1446181D01*
G01X991658Y1435107D02*
Y1434615D01*
G01Y1439290D02*
Y1437321D01*
G01X992716Y1446181D02*
X993897D01*
G01X993569Y1445197D02*
X1019291D01*
G01Y1439449D02*
X993569D01*
G01X993897Y1438465D02*
X992716D01*
G01Y1436181D02*
X993897D01*
G01X993569Y1435197D02*
X1019291D01*
G01X1006456Y1430788D02*
X1019291D01*
G01X991658Y1437321D02*
X991575Y1436912D01*
G01X994147Y1469160D02*
X994421Y1469373D01*
G01X993964Y1468844D02*
X994147Y1469160D01*
G01X993897Y1468465D02*
X993964Y1468844D01*
G01X994421Y1459373D02*
X994750Y1459449D01*
G01X994147Y1459160D02*
X994421Y1459373D01*
G01X993964Y1458844D02*
X994147Y1459160D01*
G01X993897Y1458465D02*
X993964Y1458844D01*
G01X994421Y1449373D02*
X994750Y1449449D01*
G01X994147Y1449160D02*
X994421Y1449373D01*
G01X993964Y1448844D02*
X994147Y1449160D01*
G01X993897Y1448465D02*
X993964Y1448844D01*
G01X992782D02*
X992716Y1448465D01*
G01X992966Y1449160D02*
X992782Y1448844D01*
G01X993240Y1449373D02*
X992966Y1449160D01*
G01X993569Y1449449D02*
X993240Y1449373D01*
G01X992782Y1458844D02*
X992716Y1458465D01*
G01X992966Y1459160D02*
X992782Y1458844D01*
G01X993240Y1459373D02*
X992966Y1459160D01*
G01X993569Y1459449D02*
X993240Y1459373D01*
G01X992782Y1468844D02*
X992716Y1468465D01*
G01X992966Y1469160D02*
X992782Y1468844D01*
G01X993240Y1469373D02*
X992966Y1469160D01*
G01X993964Y1455802D02*
X993897Y1456181D01*
G01X994147Y1455485D02*
X993964Y1455802D01*
G01X994421Y1455273D02*
X994147Y1455485D01*
G01X994750Y1455197D02*
X994421Y1455273D01*
G01X993964Y1465802D02*
X993897Y1466181D01*
G01X994147Y1465485D02*
X993964Y1465802D01*
G01X994421Y1465273D02*
X994147Y1465485D01*
G01X994750Y1465197D02*
X994421Y1465273D01*
G01X993240Y1455273D02*
X993569Y1455197D01*
G01X992966Y1455485D02*
X993240Y1455273D01*
G01X992782Y1455802D02*
X992966Y1455485D01*
G01X992716Y1456181D02*
X992782Y1455802D01*
G01X993240Y1465273D02*
X993569Y1465197D01*
G01X992966Y1465485D02*
X993240Y1465273D01*
G01X992782Y1465802D02*
X992966Y1465485D01*
G01X992716Y1466181D02*
X992782Y1465802D01*
G01X993897Y1468465D02*
X992716D01*
G01Y1466181D02*
X993897D01*
G01X993569Y1465197D02*
X1019291D01*
G01X1011726Y1459449D02*
Y1455197D01*
G01Y1469449D02*
Y1465197D01*
G01X1011123Y1459449D02*
Y1455197D01*
G01Y1469449D02*
Y1465197D01*
G01X1010520D02*
Y1469449D01*
G01Y1455197D02*
Y1459449D01*
G01X1001398D02*
Y1455197D01*
G01Y1469449D02*
Y1465197D01*
G01X1000795Y1459449D02*
Y1455197D01*
G01Y1469449D02*
Y1465197D01*
G01X999606D02*
Y1469449D01*
G01Y1455197D02*
Y1459449D01*
G01X998425D02*
Y1455197D01*
G01Y1469449D02*
Y1465197D01*
G01X993897Y1458465D02*
Y1456181D01*
G01Y1468465D02*
Y1466181D01*
G01X992716Y1458465D02*
Y1456181D01*
G01Y1468465D02*
Y1466181D01*
G01X1019291Y1459449D02*
X993569D01*
G01X993897Y1458465D02*
X992716D01*
G01Y1456181D02*
X993897D01*
G01X993569Y1455197D02*
X1019291D01*
G01Y1449449D02*
X993569D01*
G01X993897Y1448465D02*
X992716D01*
G01X994421Y1489373D02*
X994750Y1489449D01*
G01X994147Y1489160D02*
X994421Y1489373D01*
G01X993964Y1488844D02*
X994147Y1489160D01*
G01X993897Y1488465D02*
X993964Y1488844D01*
G01X994421Y1479373D02*
X994750Y1479449D01*
G01X994147Y1479160D02*
X994421Y1479373D01*
G01X993964Y1478844D02*
X994147Y1479160D01*
G01X993897Y1478465D02*
X993964Y1478844D01*
G01X994421Y1469373D02*
X994750Y1469449D01*
G01X993569D02*
X993240Y1469373D01*
G01X992782Y1478844D02*
X992716Y1478465D01*
G01X992966Y1479160D02*
X992782Y1478844D01*
G01X993240Y1479373D02*
X992966Y1479160D01*
G01X993569Y1479449D02*
X993240Y1479373D01*
G01X992782Y1488844D02*
X992716Y1488465D01*
G01X992966Y1489160D02*
X992782Y1488844D01*
G01X993240Y1489373D02*
X992966Y1489160D01*
G01X993569Y1489449D02*
X993240Y1489373D01*
G01X993964Y1475802D02*
X993897Y1476181D01*
G01X994147Y1475485D02*
X993964Y1475802D01*
G01X994421Y1475273D02*
X994147Y1475485D01*
G01X994750Y1475197D02*
X994421Y1475273D01*
G01X993964Y1485802D02*
X993897Y1486181D01*
G01X994147Y1485485D02*
X993964Y1485802D01*
G01X994421Y1485273D02*
X994147Y1485485D01*
G01X994750Y1485197D02*
X994421Y1485273D01*
G01X993240Y1475273D02*
X993569Y1475197D01*
G01X992966Y1475485D02*
X993240Y1475273D01*
G01X992782Y1475802D02*
X992966Y1475485D01*
G01X992716Y1476181D02*
X992782Y1475802D01*
G01X993240Y1485273D02*
X993569Y1485197D01*
G01X992966Y1485485D02*
X993240Y1485273D01*
G01X992782Y1485802D02*
X992966Y1485485D01*
G01X992716Y1486181D02*
X992782Y1485802D01*
G01X1019291Y1489449D02*
X993569D01*
G01X993897Y1488465D02*
X992716D01*
G01Y1486181D02*
X993897D01*
G01X993569Y1485197D02*
X1019291D01*
G01Y1479449D02*
X993569D01*
G01X993897Y1478465D02*
X992716D01*
G01Y1476181D02*
X993897D01*
G01X993569Y1475197D02*
X1019291D01*
G01Y1469449D02*
X993569D01*
G01X1011726Y1479449D02*
Y1475197D01*
G01Y1489449D02*
Y1485197D01*
G01X1011123Y1479449D02*
Y1475197D01*
G01Y1489449D02*
Y1485197D01*
G01X1010520D02*
Y1489449D01*
G01Y1475197D02*
Y1479449D01*
G01X1001398D02*
Y1475197D01*
G01Y1489449D02*
Y1485197D01*
G01X1000795Y1479449D02*
Y1475197D01*
G01Y1489449D02*
Y1485197D01*
G01X999606D02*
Y1489449D01*
G01Y1475197D02*
Y1479449D01*
G01X998425D02*
Y1475197D01*
G01Y1489449D02*
Y1485197D01*
G01X993897Y1478465D02*
Y1476181D01*
G01Y1488465D02*
Y1486181D01*
G01X992716Y1478465D02*
Y1476181D01*
G01Y1488465D02*
Y1486181D01*
G01X994421Y1509373D02*
X994750Y1509449D01*
G01X994147Y1509160D02*
X994421Y1509373D01*
G01X993964Y1508844D02*
X994147Y1509160D01*
G01X993897Y1508465D02*
X993964Y1508844D01*
G01X994421Y1499373D02*
X994750Y1499449D01*
G01X994147Y1499160D02*
X994421Y1499373D01*
G01X993964Y1498844D02*
X994147Y1499160D01*
G01X993897Y1498465D02*
X993964Y1498844D01*
G01X992782D02*
X992716Y1498465D01*
G01X992966Y1499160D02*
X992782Y1498844D01*
G01X993240Y1499373D02*
X992966Y1499160D01*
G01X993569Y1499449D02*
X993240Y1499373D01*
G01X992782Y1508844D02*
X992716Y1508465D01*
G01X992966Y1509160D02*
X992782Y1508844D01*
G01X993240Y1509373D02*
X992966Y1509160D01*
G01X993569Y1509449D02*
X993240Y1509373D01*
G01X993964Y1495802D02*
X993897Y1496181D01*
G01X994147Y1495485D02*
X993964Y1495802D01*
G01X994421Y1495273D02*
X994147Y1495485D01*
G01X994750Y1495197D02*
X994421Y1495273D01*
G01X993964Y1505802D02*
X993897Y1506181D01*
G01X994147Y1505485D02*
X993964Y1505802D01*
G01X994421Y1505273D02*
X994147Y1505485D01*
G01X994750Y1505197D02*
X994421Y1505273D01*
G01X993240Y1495273D02*
X993569Y1495197D01*
G01X992966Y1495485D02*
X993240Y1495273D01*
G01X992782Y1495802D02*
X992966Y1495485D01*
G01X992716Y1496181D02*
X992782Y1495802D01*
G01X993240Y1505273D02*
X993569Y1505197D01*
G01X992966Y1505485D02*
X993240Y1505273D01*
G01X992782Y1505802D02*
X992966Y1505485D01*
G01X992716Y1506181D02*
X992782Y1505802D01*
G01X1019291Y1509449D02*
X993569D01*
G01X993897Y1508465D02*
X992716D01*
G01Y1506181D02*
X993897D01*
G01X993569Y1505197D02*
X1019291D01*
G01Y1499449D02*
X993569D01*
G01X993897Y1498465D02*
X992716D01*
G01Y1496181D02*
X993897D01*
G01X993569Y1495197D02*
X1019291D01*
G01X1011726Y1499449D02*
Y1495197D01*
G01Y1509449D02*
Y1505197D01*
G01X1011123Y1499449D02*
Y1495197D01*
G01Y1509449D02*
Y1505197D01*
G01X1010520D02*
Y1509449D01*
G01Y1495197D02*
Y1499449D01*
G01X1001398D02*
Y1495197D01*
G01Y1509449D02*
Y1505197D01*
G01X1000795Y1499449D02*
Y1495197D01*
G01Y1509449D02*
Y1505197D01*
G01X999606D02*
Y1509449D01*
G01Y1495197D02*
Y1499449D01*
G01X998425D02*
Y1495197D01*
G01Y1509449D02*
Y1505197D01*
G01X993897Y1498465D02*
Y1496181D01*
G01Y1508465D02*
Y1506181D01*
G01X992716Y1498465D02*
Y1496181D01*
G01Y1508465D02*
Y1506181D01*
G01X994421Y1529373D02*
X994750Y1529449D01*
G01X994147Y1529160D02*
X994421Y1529373D01*
G01X993964Y1528844D02*
X994147Y1529160D01*
G01X993897Y1528465D02*
X993964Y1528844D01*
G01X994421Y1519373D02*
X994750Y1519449D01*
G01X994147Y1519160D02*
X994421Y1519373D01*
G01X993964Y1518844D02*
X994147Y1519160D01*
G01X993897Y1518465D02*
X993964Y1518844D01*
G01X992782D02*
X992716Y1518465D01*
G01X992966Y1519160D02*
X992782Y1518844D01*
G01X993240Y1519373D02*
X992966Y1519160D01*
G01X993569Y1519449D02*
X993240Y1519373D01*
G01X992782Y1528844D02*
X992716Y1528465D01*
G01X992966Y1529160D02*
X992782Y1528844D01*
G01X993240Y1529373D02*
X992966Y1529160D01*
G01X993569Y1529449D02*
X993240Y1529373D01*
G01X993964Y1515802D02*
X993897Y1516181D01*
G01X994147Y1515485D02*
X993964Y1515802D01*
G01X994421Y1515273D02*
X994147Y1515485D01*
G01X994750Y1515197D02*
X994421Y1515273D01*
G01X993240D02*
X993569Y1515197D01*
G01X992966Y1515485D02*
X993240Y1515273D01*
G01X992782Y1515802D02*
X992966Y1515485D01*
G01X992716Y1516181D02*
X992782Y1515802D01*
G01X993240Y1525273D02*
X993569Y1525197D01*
G01X992966Y1525485D02*
X993240Y1525273D01*
G01X992782Y1525802D02*
X992966Y1525485D01*
G01X992716Y1526181D02*
X992782Y1525802D01*
G01X993964D02*
X993897Y1526181D01*
G01X994147Y1525485D02*
X993964Y1525802D01*
G01X994421Y1525273D02*
X994147Y1525485D01*
G01X994750Y1525197D02*
X994421Y1525273D01*
G01X1019291Y1529449D02*
X993569D01*
G01X993897Y1528465D02*
X992716D01*
G01Y1526181D02*
X993897D01*
G01X993569Y1525197D02*
X1019291D01*
G01Y1519449D02*
X993569D01*
G01X993897Y1518465D02*
X992716D01*
G01Y1516181D02*
X993897D01*
G01X993569Y1515197D02*
X1019291D01*
G01X1011726Y1519449D02*
Y1515197D01*
G01Y1529449D02*
Y1525197D01*
G01X1011123Y1519449D02*
Y1515197D01*
G01Y1529449D02*
Y1525197D01*
G01X1010520D02*
Y1529449D01*
G01Y1515197D02*
Y1519449D01*
G01X1001398D02*
Y1515197D01*
G01Y1529449D02*
Y1525197D01*
G01X1000795Y1519449D02*
Y1515197D01*
G01Y1529449D02*
Y1525197D01*
G01X999606D02*
Y1529449D01*
G01Y1515197D02*
Y1519449D01*
G01X998425D02*
Y1515197D01*
G01Y1529449D02*
Y1525197D01*
G01X993897Y1518465D02*
Y1516181D01*
G01Y1528465D02*
Y1526181D01*
G01X992716Y1518465D02*
Y1516181D01*
G01Y1528465D02*
Y1526181D01*
G01X994421Y1549373D02*
X994750Y1549449D01*
G01X994147Y1549160D02*
X994421Y1549373D01*
G01X993964Y1548844D02*
X994147Y1549160D01*
G01X993897Y1548465D02*
X993964Y1548844D01*
G01X994421Y1539373D02*
X994750Y1539449D01*
G01X994147Y1539160D02*
X994421Y1539373D01*
G01X993964Y1538844D02*
X994147Y1539160D01*
G01X993897Y1538465D02*
X993964Y1538844D01*
G01X992782D02*
X992716Y1538465D01*
G01X992966Y1539160D02*
X992782Y1538844D01*
G01X993240Y1539373D02*
X992966Y1539160D01*
G01X993569Y1539449D02*
X993240Y1539373D01*
G01X992782Y1548844D02*
X992716Y1548465D01*
G01X992966Y1549160D02*
X992782Y1548844D01*
G01X993240Y1549373D02*
X992966Y1549160D01*
G01X993569Y1549449D02*
X993240Y1549373D01*
G01Y1535273D02*
X993569Y1535197D01*
G01X992966Y1535485D02*
X993240Y1535273D01*
G01X992782Y1535802D02*
X992966Y1535485D01*
G01X992716Y1536181D02*
X992782Y1535802D01*
G01X993240Y1545273D02*
X993569Y1545197D01*
G01X992966Y1545485D02*
X993240Y1545273D01*
G01X992782Y1545802D02*
X992966Y1545485D01*
G01X992716Y1546181D02*
X992782Y1545802D01*
G01X993964Y1535802D02*
X993897Y1536181D01*
G01X994147Y1535485D02*
X993964Y1535802D01*
G01X994421Y1535273D02*
X994147Y1535485D01*
G01X994750Y1535197D02*
X994421Y1535273D01*
G01X993964Y1545802D02*
X993897Y1546181D01*
G01X994147Y1545485D02*
X993964Y1545802D01*
G01X994421Y1545273D02*
X994147Y1545485D01*
G01X994750Y1545197D02*
X994421Y1545273D01*
G01X1019291Y1549449D02*
X993569D01*
G01X993897Y1548465D02*
X992716D01*
G01Y1546181D02*
X993897D01*
G01X993569Y1545197D02*
X1019291D01*
G01Y1539449D02*
X993569D01*
G01X993897Y1538465D02*
X992716D01*
G01Y1536181D02*
X993897D01*
G01X993569Y1535197D02*
X1019291D01*
G01X1011726Y1539449D02*
Y1535197D01*
G01Y1549449D02*
Y1545197D01*
G01X1011123Y1539449D02*
Y1535197D01*
G01Y1549449D02*
Y1545197D01*
G01X1010520D02*
Y1549449D01*
G01Y1535197D02*
Y1539449D01*
G01X1001398D02*
Y1535197D01*
G01Y1549449D02*
Y1545197D01*
G01X1000795Y1539449D02*
Y1535197D01*
G01Y1549449D02*
Y1545197D01*
G01X999606D02*
Y1549449D01*
G01Y1535197D02*
Y1539449D01*
G01X998425D02*
Y1535197D01*
G01Y1549449D02*
Y1545197D01*
G01X993897Y1538465D02*
Y1536181D01*
G01Y1548465D02*
Y1546181D01*
G01X992716Y1538465D02*
Y1536181D01*
G01Y1548465D02*
Y1546181D01*
G01X994421Y1569373D02*
X994750Y1569449D01*
G01X994147Y1569160D02*
X994421Y1569373D01*
G01X993964Y1568844D02*
X994147Y1569160D01*
G01X993897Y1568465D02*
X993964Y1568844D01*
G01X994421Y1559373D02*
X994750Y1559449D01*
G01X994147Y1559160D02*
X994421Y1559373D01*
G01X993964Y1558844D02*
X994147Y1559160D01*
G01X993897Y1558465D02*
X993964Y1558844D01*
G01X992782D02*
X992716Y1558465D01*
G01X992966Y1559160D02*
X992782Y1558844D01*
G01X993240Y1559373D02*
X992966Y1559160D01*
G01X993569Y1559449D02*
X993240Y1559373D01*
G01X992782Y1568844D02*
X992716Y1568465D01*
G01X992966Y1569160D02*
X992782Y1568844D01*
G01X993240Y1569373D02*
X992966Y1569160D01*
G01X993569Y1569449D02*
X993240Y1569373D01*
G01Y1555273D02*
X993569Y1555197D01*
G01X992966Y1555485D02*
X993240Y1555273D01*
G01X992782Y1555802D02*
X992966Y1555485D01*
G01X992716Y1556181D02*
X992782Y1555802D01*
G01X993240Y1565273D02*
X993569Y1565197D01*
G01X992966Y1565485D02*
X993240Y1565273D01*
G01X992782Y1565802D02*
X992966Y1565485D01*
G01X992716Y1566181D02*
X992782Y1565802D01*
G01X993964Y1555802D02*
X993897Y1556181D01*
G01X994147Y1555485D02*
X993964Y1555802D01*
G01X994421Y1555273D02*
X994147Y1555485D01*
G01X994750Y1555197D02*
X994421Y1555273D01*
G01X993964Y1565802D02*
X993897Y1566181D01*
G01X994147Y1565485D02*
X993964Y1565802D01*
G01X994421Y1565273D02*
X994147Y1565485D01*
G01X994750Y1565197D02*
X994421Y1565273D01*
G01X1019291Y1569449D02*
X993569D01*
G01X993897Y1568465D02*
X992716D01*
G01Y1566181D02*
X993897D01*
G01X993569Y1565197D02*
X1019291D01*
G01Y1559449D02*
X993569D01*
G01X993897Y1558465D02*
X992716D01*
G01Y1556181D02*
X993897D01*
G01X993569Y1555197D02*
X1019291D01*
G01X1011726Y1559449D02*
Y1555197D01*
G01Y1569449D02*
Y1565197D01*
G01X1011123Y1559449D02*
Y1555197D01*
G01Y1569449D02*
Y1565197D01*
G01X1010520D02*
Y1569449D01*
G01Y1555197D02*
Y1559449D01*
G01X1001398D02*
Y1555197D01*
G01Y1569449D02*
Y1565197D01*
G01X1000795Y1559449D02*
Y1555197D01*
G01Y1569449D02*
Y1565197D01*
G01X999606D02*
Y1569449D01*
G01Y1555197D02*
Y1559449D01*
G01X998425D02*
Y1555197D01*
G01Y1569449D02*
Y1565197D01*
G01X993897Y1558465D02*
Y1556181D01*
G01Y1568465D02*
Y1566181D01*
G01X992716Y1558465D02*
Y1556181D01*
G01Y1568465D02*
Y1566181D01*
G01X994421Y1589373D02*
X994750Y1589449D01*
G01X994147Y1589160D02*
X994421Y1589373D01*
G01X993964Y1588844D02*
X994147Y1589160D01*
G01X993897Y1588465D02*
X993964Y1588844D01*
G01X994421Y1579373D02*
X994750Y1579449D01*
G01X994147Y1579160D02*
X994421Y1579373D01*
G01X993964Y1578844D02*
X994147Y1579160D01*
G01X993897Y1578465D02*
X993964Y1578844D01*
G01X992782D02*
X992716Y1578465D01*
G01X992966Y1579160D02*
X992782Y1578844D01*
G01X993240Y1579373D02*
X992966Y1579160D01*
G01X993569Y1579449D02*
X993240Y1579373D01*
G01X992782Y1588844D02*
X992716Y1588465D01*
G01X992966Y1589160D02*
X992782Y1588844D01*
G01X993240Y1589373D02*
X992966Y1589160D01*
G01X993569Y1589449D02*
X993240Y1589373D01*
G01Y1575273D02*
X993569Y1575197D01*
G01X992966Y1575485D02*
X993240Y1575273D01*
G01X992782Y1575802D02*
X992966Y1575485D01*
G01X992716Y1576181D02*
X992782Y1575802D01*
G01X993240Y1585273D02*
X993569Y1585197D01*
G01X992966Y1585485D02*
X993240Y1585273D01*
G01X992782Y1585802D02*
X992966Y1585485D01*
G01X992716Y1586181D02*
X992782Y1585802D01*
G01X993240Y1595273D02*
X993569Y1595197D01*
G01X992966Y1595485D02*
X993240Y1595273D01*
G01X992782Y1595802D02*
X992966Y1595485D01*
G01X992716Y1596181D02*
X992782Y1595802D01*
G01X993964Y1575802D02*
X993897Y1576181D01*
G01X994147Y1575485D02*
X993964Y1575802D01*
G01X994421Y1575273D02*
X994147Y1575485D01*
G01X994750Y1575197D02*
X994421Y1575273D01*
G01X993964Y1585802D02*
X993897Y1586181D01*
G01X994147Y1585485D02*
X993964Y1585802D01*
G01X994421Y1585273D02*
X994147Y1585485D01*
G01X994750Y1585197D02*
X994421Y1585273D01*
G01X993964Y1595802D02*
X993897Y1596181D01*
G01X994147Y1595485D02*
X993964Y1595802D01*
G01X994421Y1595273D02*
X994147Y1595485D01*
G01X994750Y1595197D02*
X994421Y1595273D01*
G01X993569Y1595197D02*
X1019291D01*
G01Y1589449D02*
X993569D01*
G01X993897Y1588465D02*
X992716D01*
G01Y1586181D02*
X993897D01*
G01X993569Y1585197D02*
X1019291D01*
G01Y1579449D02*
X993569D01*
G01X993897Y1578465D02*
X992716D01*
G01Y1576181D02*
X993897D01*
G01X993569Y1575197D02*
X1019291D01*
G01X1011726Y1579449D02*
Y1575197D01*
G01Y1589449D02*
Y1585197D01*
G01Y1599449D02*
Y1595197D01*
G01X1011123Y1579449D02*
Y1575197D01*
G01Y1589449D02*
Y1585197D01*
G01Y1599449D02*
Y1595197D01*
G01X1010520D02*
Y1599449D01*
G01Y1585197D02*
Y1589449D01*
G01Y1575197D02*
Y1579449D01*
G01X1001398D02*
Y1575197D01*
G01Y1589449D02*
Y1585197D01*
G01Y1599449D02*
Y1595197D01*
G01X1000795Y1579449D02*
Y1575197D01*
G01Y1589449D02*
Y1585197D01*
G01Y1599449D02*
Y1595197D01*
G01X999606D02*
Y1599449D01*
G01Y1585197D02*
Y1589449D01*
G01Y1575197D02*
Y1579449D01*
G01X998425D02*
Y1575197D01*
G01Y1589449D02*
Y1585197D01*
G01Y1599449D02*
Y1595197D01*
G01X993897Y1578465D02*
Y1576181D01*
G01Y1588465D02*
Y1586181D01*
G01X992716Y1578465D02*
Y1576181D01*
G01Y1588465D02*
Y1586181D01*
G01X994421Y1609373D02*
X994750Y1609449D01*
G01X994147Y1609160D02*
X994421Y1609373D01*
G01X993964Y1608844D02*
X994147Y1609160D01*
G01X993897Y1608465D02*
X993964Y1608844D01*
G01X994421Y1599373D02*
X994750Y1599449D01*
G01X994147Y1599160D02*
X994421Y1599373D01*
G01X993964Y1598844D02*
X994147Y1599160D01*
G01X993897Y1598465D02*
X993964Y1598844D01*
G01X992782D02*
X992716Y1598465D01*
G01X992966Y1599160D02*
X992782Y1598844D01*
G01X993240Y1599373D02*
X992966Y1599160D01*
G01X993569Y1599449D02*
X993240Y1599373D01*
G01X992782Y1608844D02*
X992716Y1608465D01*
G01X992966Y1609160D02*
X992782Y1608844D01*
G01X993240Y1609373D02*
X992966Y1609160D01*
G01X993569Y1609449D02*
X993240Y1609373D01*
G01Y1605273D02*
X993569Y1605197D01*
G01X992966Y1605485D02*
X993240Y1605273D01*
G01X992782Y1605802D02*
X992966Y1605485D01*
G01X992716Y1606181D02*
X992782Y1605802D01*
G01X993964D02*
X993897Y1606181D01*
G01X994147Y1605485D02*
X993964Y1605802D01*
G01X994421Y1605273D02*
X994147Y1605485D01*
G01X994750Y1605197D02*
X994421Y1605273D01*
G01X991732Y1613150D02*
X992716Y1612166D01*
G01X1015354Y1616083D02*
X991732D01*
G01X1015354D02*
X991732D01*
G01X1019291Y1615788D02*
X992716D01*
G01X991732Y1615394D02*
X1029527D01*
G01X992716Y1612166D02*
X1019291D01*
G01X991732Y1611870D02*
X1015354D01*
G01X991732D02*
X1015354D01*
G01X991732Y1611358D02*
X1039921D01*
G01X995242Y1610965D02*
X1072855D01*
G01X991732Y1610197D02*
X1015354D01*
G01X1017611Y1609449D02*
X993569D01*
G01X993897Y1608465D02*
X992716D01*
G01Y1606181D02*
X993897D01*
G01X993569Y1605197D02*
X1019291D01*
G01Y1599449D02*
X993569D01*
G01X993897Y1598465D02*
X992716D01*
G01Y1596181D02*
X993897D01*
G01X1011726Y1609449D02*
Y1605197D01*
G01X1011123Y1609449D02*
Y1605197D01*
G01X1010520D02*
Y1609449D01*
G01X1001398D02*
Y1605197D01*
G01X1000795Y1609449D02*
Y1605197D01*
G01X999606D02*
Y1609449D01*
G01X998425D02*
Y1605197D01*
G01X995669Y1617756D02*
Y1615788D01*
G01Y1612166D02*
Y1610965D01*
G01X995242Y1611358D02*
Y1610965D01*
G01X993897Y1598465D02*
Y1596181D01*
G01Y1608465D02*
Y1606181D01*
G01X992716Y1610197D02*
Y1615394D01*
G01Y1598465D02*
Y1596181D01*
G01Y1608465D02*
Y1606181D01*
G01X991732Y1617756D02*
Y1610197D01*
G01Y1614803D02*
X992716Y1615788D01*
G01X1004145Y1635315D02*
X1004338Y1635118D01*
G01X1004095D02*
X1003902Y1635315D01*
G01X1004145Y1630315D02*
X1004338Y1630118D01*
G01X1004095D02*
X1003902Y1630315D01*
G01X1004145Y1625315D02*
X1004338Y1625118D01*
G01X1004095D02*
X1003902Y1625315D01*
G01X1004145Y1620315D02*
X1004338Y1620118D01*
G01X1004095D02*
X1003902Y1620315D01*
G01X1029527Y1637087D02*
X1004095D01*
G01X999016Y1636890D02*
X992953D01*
G01X1004145D02*
X999016D01*
G01X1003902Y1635315D02*
X1004145D01*
G01X1000962D02*
X1003902D01*
G01X999016D02*
X1000962D01*
G01X992953D02*
X999016D01*
G01X1004095Y1635118D02*
X1029527D01*
G01Y1632087D02*
X1004095D01*
G01X999016Y1631890D02*
X992953D01*
G01X1004145D02*
X999016D01*
G01X1003902Y1630315D02*
X1004145D01*
G01X1000962D02*
X1003902D01*
G01X999016D02*
X1000962D01*
G01X992953D02*
X999016D01*
G01X1004095Y1630118D02*
X1029527D01*
G01Y1627087D02*
X1004095D01*
G01X999016Y1626890D02*
X992953D01*
G01X1004145D02*
X999016D01*
G01X1003902Y1625315D02*
X1004145D01*
G01X1000962D02*
X1003902D01*
G01X999016D02*
X1000962D01*
G01X992953D02*
X999016D01*
G01X1004095Y1625118D02*
X1029527D01*
G01X1004095Y1622087D02*
X1029527D01*
G01X992953Y1621890D02*
X999016D01*
G01X1004145D02*
X999016D01*
G01Y1620315D02*
X1004145D01*
G01X992953D02*
X999016D01*
G01X1004095Y1620118D02*
X1029527D01*
G01Y1617756D02*
X991732D01*
G01X1001205Y1621890D02*
Y1620315D01*
G01Y1626890D02*
Y1625315D01*
G01Y1631890D02*
Y1630315D01*
G01Y1636890D02*
Y1635315D01*
G01X1000962Y1621890D02*
Y1620315D01*
G01Y1626890D02*
Y1625315D01*
G01Y1631890D02*
Y1630315D01*
G01Y1636890D02*
Y1635315D01*
G01X999016Y1621890D02*
Y1620315D01*
G01Y1626890D02*
Y1625315D01*
G01Y1631890D02*
Y1630315D01*
G01Y1636890D02*
Y1635315D01*
G01X998425Y1621890D02*
Y1620315D01*
G01Y1626890D02*
Y1625315D01*
G01Y1631890D02*
Y1630315D01*
G01Y1636890D02*
Y1635315D01*
G01X993543D02*
Y1636890D01*
G01Y1630315D02*
Y1631890D01*
G01Y1625315D02*
Y1626890D01*
G01Y1620315D02*
Y1621890D01*
G01X992953D02*
Y1620315D01*
G01Y1626890D02*
Y1625315D01*
G01Y1631890D02*
Y1630315D01*
G01Y1636890D02*
Y1635315D01*
G01X1004338Y1622087D02*
X1004145Y1621890D01*
G01X1003902D02*
X1004095Y1622087D01*
G01X1004338Y1627087D02*
X1004145Y1626890D01*
G01X1003902D02*
X1004095Y1627087D01*
G01X1004338Y1632087D02*
X1004145Y1631890D01*
G01X1003902D02*
X1004095Y1632087D01*
G01X1004338Y1637087D02*
X1004145Y1636890D01*
G01X1003902D02*
X1004095Y1637087D01*
G01X1004145Y1655315D02*
X1004338Y1655118D01*
G01X1004095D02*
X1003902Y1655315D01*
G01X1004145Y1650315D02*
X1004338Y1650118D01*
G01X1004095D02*
X1003902Y1650315D01*
G01X1004145Y1645315D02*
X1004338Y1645118D01*
G01X1004095D02*
X1003902Y1645315D01*
G01X1004145Y1640315D02*
X1004338Y1640118D01*
G01X1004095D02*
X1003902Y1640315D01*
G01X1004095Y1657087D02*
X1029527D01*
G01X992953Y1656890D02*
X999016D01*
G01X1004145D02*
X999016D01*
G01Y1655315D02*
X1004145D01*
G01X992953D02*
X999016D01*
G01X1004095Y1655118D02*
X1029527D01*
G01Y1652087D02*
X1004095D01*
G01X999016Y1651890D02*
X992953D01*
G01X1004145D02*
X999016D01*
G01X1003902Y1650315D02*
X1004145D01*
G01X1000962D02*
X1003902D01*
G01X999016D02*
X1000962D01*
G01X992953D02*
X999016D01*
G01X1004095Y1650118D02*
X1029527D01*
G01X1004095Y1647087D02*
X1029527D01*
G01X992953Y1646890D02*
X999016D01*
G01X1004145D02*
X999016D01*
G01Y1645315D02*
X1004145D01*
G01X992953D02*
X999016D01*
G01X1004095Y1645118D02*
X1029527D01*
G01Y1642087D02*
X1004095D01*
G01X999016Y1641890D02*
X992953D01*
G01X1004145D02*
X999016D01*
G01X1003902Y1640315D02*
X1004145D01*
G01X1000962D02*
X1003902D01*
G01X999016D02*
X1000962D01*
G01X992953D02*
X999016D01*
G01X1004095Y1640118D02*
X1029527D01*
G01X1001205Y1641890D02*
Y1640315D01*
G01Y1646890D02*
Y1645315D01*
G01Y1651890D02*
Y1650315D01*
G01Y1656890D02*
Y1655315D01*
G01X1000962Y1641890D02*
Y1640315D01*
G01Y1646890D02*
Y1645315D01*
G01Y1651890D02*
Y1650315D01*
G01Y1656890D02*
Y1655315D01*
G01X999016Y1641890D02*
Y1640315D01*
G01Y1646890D02*
Y1645315D01*
G01Y1651890D02*
Y1650315D01*
G01Y1656890D02*
Y1655315D01*
G01X998425Y1641890D02*
Y1640315D01*
G01Y1646890D02*
Y1645315D01*
G01Y1651890D02*
Y1650315D01*
G01Y1656890D02*
Y1655315D01*
G01X993543D02*
Y1656890D01*
G01Y1650315D02*
Y1651890D01*
G01Y1645315D02*
Y1646890D01*
G01Y1640315D02*
Y1641890D01*
G01X992953D02*
Y1640315D01*
G01Y1646890D02*
Y1645315D01*
G01Y1651890D02*
Y1650315D01*
G01Y1656890D02*
Y1655315D01*
G01X1004338Y1642087D02*
X1004145Y1641890D01*
G01X1003902D02*
X1004095Y1642087D01*
G01X1004338Y1647087D02*
X1004145Y1646890D01*
G01X1003902D02*
X1004095Y1647087D01*
G01X1004338Y1652087D02*
X1004145Y1651890D01*
G01X1003902D02*
X1004095Y1652087D01*
G01X1004338Y1657087D02*
X1004145Y1656890D01*
G01X1003902D02*
X1004095Y1657087D01*
G01X1004488Y1681417D02*
G03X1006456Y1679449I1968J0D01*
G01X1004145Y1675315D02*
X1004338Y1675118D01*
G01X1004095D02*
X1003902Y1675315D01*
G01X1004145Y1670315D02*
X1004338Y1670118D01*
G01X1004095D02*
X1003902Y1670315D01*
G01X1004145Y1665315D02*
X1004338Y1665118D01*
G01X1004095D02*
X1003902Y1665315D01*
G01X1004145Y1660315D02*
X1004338Y1660118D01*
G01X1004095D02*
X1003902Y1660315D01*
G01X1006456Y1679449D02*
X1020380D01*
G01X1004095Y1677087D02*
X1029527D01*
G01X992953Y1676890D02*
X999016D01*
G01X1004145D02*
X999016D01*
G01Y1675315D02*
X1004145D01*
G01X992953D02*
X999016D01*
G01X1004095Y1675118D02*
X1029527D01*
G01Y1672087D02*
X1004095D01*
G01X999016Y1671890D02*
X992953D01*
G01X1004145D02*
X999016D01*
G01X1003902Y1670315D02*
X1004145D01*
G01X1000962D02*
X1003902D01*
G01X999016D02*
X1000962D01*
G01X992953D02*
X999016D01*
G01X1004095Y1670118D02*
X1029527D01*
G01X1004095Y1667087D02*
X1029527D01*
G01X992953Y1666890D02*
X999016D01*
G01X1004145D02*
X999016D01*
G01Y1665315D02*
X1004145D01*
G01X992953D02*
X999016D01*
G01X1004095Y1665118D02*
X1029527D01*
G01Y1662087D02*
X1004095D01*
G01X999016Y1661890D02*
X992953D01*
G01X1004145D02*
X999016D01*
G01X1003902Y1660315D02*
X1004145D01*
G01X1000962D02*
X1003902D01*
G01X999016D02*
X1000962D01*
G01X992953D02*
X999016D01*
G01X1004095Y1660118D02*
X1029527D01*
G01X1008425Y1679449D02*
Y1708977D01*
G01X1001205Y1661890D02*
Y1660315D01*
G01Y1666890D02*
Y1665315D01*
G01Y1671890D02*
Y1670315D01*
G01Y1676890D02*
Y1675315D01*
G01X1000962Y1661890D02*
Y1660315D01*
G01Y1666890D02*
Y1665315D01*
G01Y1671890D02*
Y1670315D01*
G01Y1676890D02*
Y1675315D01*
G01X999016Y1661890D02*
Y1660315D01*
G01Y1666890D02*
Y1665315D01*
G01Y1671890D02*
Y1670315D01*
G01Y1676890D02*
Y1675315D01*
G01X998425Y1661890D02*
Y1660315D01*
G01Y1666890D02*
Y1665315D01*
G01Y1671890D02*
Y1670315D01*
G01Y1676890D02*
Y1675315D01*
G01X993543D02*
Y1676890D01*
G01Y1670315D02*
Y1671890D01*
G01Y1665315D02*
Y1666890D01*
G01Y1660315D02*
Y1661890D01*
G01X992953D02*
Y1660315D01*
G01Y1666890D02*
Y1665315D01*
G01Y1671890D02*
Y1670315D01*
G01Y1676890D02*
Y1675315D01*
G01X1004338Y1662087D02*
X1004145Y1661890D01*
G01X1003902D02*
X1004095Y1662087D01*
G01X1004338Y1667087D02*
X1004145Y1666890D01*
G01X1003902D02*
X1004095Y1667087D01*
G01X1004338Y1672087D02*
X1004145Y1671890D01*
G01X1003902D02*
X1004095Y1672087D01*
G01X1004338Y1677087D02*
X1004145Y1676890D01*
G01X1003902D02*
X1004095Y1677087D01*
G01X1026575Y1694213D02*
G03I-7284J0D01*
G01D02*
G03I-7284J0D01*
G01X1026968D02*
G03I-7677J0D01*
G01X1004488Y1681811D02*
X1029527D01*
G01X1004488Y1707008D02*
Y1681417D01*
G01X1006456Y1708977D02*
G03X1004488Y1707008I1J-1969D01*
G01X1032047Y1708977D02*
X1006456D01*
G01X1015889Y2111517D02*
X1016174Y2113988D01*
X1016602Y2116080D01*
X1017172Y2117981D01*
X1017885Y2120072D01*
X1019026Y2122924D01*
X1013322D01*
G01X1029527Y0D02*
G03X1033464Y3937I0J3937D01*
G01X1029527Y0D02*
G03X1033464Y3937I0J3937D01*
G01Y1424882D02*
Y3937D01*
G01Y1424882D02*
Y3937D01*
G01X1041338Y24677D02*
G03X1033464I-3937J0D01*
G01X1041338D02*
G03X1033464I-3937J0D01*
G01Y48297D02*
G03X1041338I3937J0D01*
G01X1033464D02*
G03X1041338I3937J0D01*
G01Y217343D02*
G03X1033464I-3937J0D01*
G01X1041338D02*
G03X1033464I-3937J0D01*
G01Y240964D02*
G03X1041338I3937J0D01*
G01X1033464D02*
G03X1041338I3937J0D01*
G01Y445039D02*
G03X1033464I-3937J0D01*
G01X1041338D02*
G03X1033464I-3937J0D01*
G01Y468659D02*
G03X1041338I3937J0D01*
G01X1033464D02*
G03X1041338I3937J0D01*
G01Y697473D02*
G03X1033464I-3937J0D01*
G01X1041338D02*
G03X1033464I-3937J0D01*
G01Y721093D02*
G03X1041338I3937J0D01*
G01X1033464D02*
G03X1041338I3937J0D01*
G01Y996852D02*
G03X1033464I-3937J0D01*
G01X1041338D02*
G03X1033464I-3937J0D01*
G01Y1020472D02*
G03X1041338I3937J0D01*
G01X1033464D02*
G03X1041338I3937J0D01*
G01Y1344060D02*
G03X1033464I-3937J0D01*
G01X1041338D02*
G03X1033464I-3937J0D01*
G01Y1367680D02*
G03X1041338I3937J0D01*
G01X1033464D02*
G03X1041338I3937J0D01*
G01X1033481Y1401880D02*
G03X1034016Y1403228I-1434J1349D01*
G01X1032047Y1401260D02*
G03X1033481Y1401880I0J1969D01*
G01X1033464Y1424882D02*
X1029527Y1428819D01*
G01X1033464Y1424882D02*
X1029527Y1428819D01*
G01X1028149Y1447244D02*
G03X1027165Y1446260I0J-984D01*
G01Y1438386D02*
G03X1028149Y1437402I984J0D01*
G01X1019360Y1432922D02*
G03X1024212Y1428819I4853J818D01*
G01X1019456Y1432478D02*
G03X1024212Y1428819I4757J1262D01*
G01X1019291Y1433740D02*
G03X1019360Y1432922I4921J3D01*
G01X1019291Y1433740D02*
G03X1019456Y1432478I4921J2D01*
G01X1021260Y1430788D02*
X1019291Y1432756D01*
G01X1030921Y1439370D02*
Y1445276D01*
G01X1030118D02*
Y1439370D01*
G01X1028362D02*
Y1445276D01*
G01X1027559D02*
Y1439370D01*
G01X1027165Y1438386D02*
Y1446260D01*
G01X1025197Y1445276D02*
Y1439370D01*
G01X1023228Y1443484D02*
Y1441162D01*
G01X1022441Y1439449D02*
Y1445197D01*
G01Y1435197D02*
Y1433288D01*
G01X1021653Y1439449D02*
Y1435197D01*
G01Y1449449D02*
Y1445197D01*
G01X1020472Y1439449D02*
Y1435197D01*
G01Y1449449D02*
Y1445197D01*
G01X1019685Y1433288D02*
Y1434449D01*
G01X1019291Y1432756D02*
Y1606260D01*
G01Y1432756D02*
Y1430788D01*
G01Y1607933D02*
Y1433740D01*
G01Y1607933D02*
Y1433740D01*
G01X1018025Y1439449D02*
Y1435197D01*
G01Y1449449D02*
Y1445197D01*
G01X1016844Y1439449D02*
Y1435197D01*
G01Y1449449D02*
Y1445197D01*
G01X1015663D02*
Y1449449D01*
G01Y1435197D02*
Y1439449D01*
G01X1035787Y1447244D02*
X1019291D01*
G01Y1445276D02*
X1027165D01*
G01X1030921D02*
X1027165D01*
G01X1019291Y1445197D02*
X1022441D01*
G01X1039921Y1443484D02*
X1019291D01*
G01Y1441162D02*
X1039921D01*
G01X1022441Y1439449D02*
X1019291D01*
G01X1027165Y1439370D02*
X1030921D01*
G01X1019291D02*
X1027165D01*
G01X1019291Y1437402D02*
X1035787D01*
G01X1019291Y1435197D02*
X1022441D01*
G01X1039921Y1434449D02*
X1019291D01*
G01Y1433681D02*
X1072855D01*
G01X1019685Y1433288D02*
X1039921D01*
G01X1034016Y1430788D02*
X1021260D01*
G01X1029527Y1428819D02*
X1024212D01*
G01X1029527D02*
X1024212D01*
G01X1035984Y1433681D02*
X1032047Y1433288D01*
G01X1019291Y1432894D02*
X1019685Y1433288D01*
G01X1027165Y1458386D02*
G03X1028149Y1457402I984J0D01*
G01Y1467244D02*
G03X1027165Y1466260I0J-984D01*
G01X1035787Y1467244D02*
X1019291D01*
G01Y1465276D02*
X1027165D01*
G01X1030921D02*
X1027165D01*
G01X1019291Y1465197D02*
X1022441D01*
G01X1039921Y1463484D02*
X1019291D01*
G01X1030921Y1459370D02*
Y1465276D01*
G01X1030118D02*
Y1459370D01*
G01X1028362Y1465276D02*
Y1459370D01*
G01X1027559Y1465276D02*
Y1459370D01*
G01X1027165Y1458386D02*
Y1466260D01*
G01X1025197Y1465276D02*
Y1459370D01*
G01X1023228Y1453484D02*
Y1451162D01*
G01Y1463484D02*
Y1461162D01*
G01X1022441Y1459449D02*
Y1465197D01*
G01Y1449449D02*
Y1455197D01*
G01X1021653Y1459449D02*
Y1455197D01*
G01Y1469449D02*
Y1465197D01*
G01X1020472Y1459449D02*
Y1455197D01*
G01Y1469449D02*
Y1465197D01*
G01X1018025Y1459449D02*
Y1455197D01*
G01Y1469449D02*
Y1465197D01*
G01X1016844Y1459449D02*
Y1455197D01*
G01Y1469449D02*
Y1465197D01*
G01X1015663D02*
Y1469449D01*
G01Y1455197D02*
Y1459449D01*
G01X1019291Y1461162D02*
X1039921D01*
G01X1022441Y1459449D02*
X1019291D01*
G01X1027165Y1459370D02*
X1030921D01*
G01X1019291D02*
X1027165D01*
G01X1019291Y1457402D02*
X1035787D01*
G01X1019291Y1455197D02*
X1022441D01*
G01X1019291Y1454449D02*
X1039921D01*
G01Y1453484D02*
X1019291D01*
G01X1039921Y1451162D02*
X1019291D01*
G01X1039921Y1450197D02*
X1019291D01*
G01X1022441Y1449449D02*
X1019291D01*
G01X1027165Y1478386D02*
G03X1028149Y1477402I984J0D01*
G01Y1487244D02*
G03X1027165Y1486260I0J-984D01*
G01X1019291Y1471752D02*
X1019685Y1471358D01*
G01X1032047D02*
X1035984Y1470965D01*
G01X1039921Y1490197D02*
X1019291D01*
G01X1022441Y1489449D02*
X1019291D01*
G01X1035787Y1487244D02*
X1019291D01*
G01Y1485276D02*
X1027165D01*
G01X1030921D02*
X1027165D01*
G01X1019291Y1485197D02*
X1022441D01*
G01X1039921Y1483484D02*
X1019291D01*
G01Y1481162D02*
X1039921D01*
G01X1022441Y1479449D02*
X1019291D01*
G01X1027165Y1479370D02*
X1030921D01*
G01X1019291D02*
X1027165D01*
G01X1019291Y1477402D02*
X1035787D01*
G01X1019291Y1475197D02*
X1022441D01*
G01X1039921Y1474449D02*
X1019291D01*
G01Y1473681D02*
X1072855D01*
G01X1019685Y1473288D02*
X1039921D01*
G01Y1471358D02*
X1019685D01*
G01X1019291Y1470965D02*
X1072855D01*
G01X1039921Y1470197D02*
X1019291D01*
G01Y1469449D02*
X1022441D01*
G01X1030921Y1479370D02*
Y1485276D01*
G01X1030118D02*
Y1479370D01*
G01X1028362D02*
Y1485276D01*
G01X1027559D02*
Y1479370D01*
G01X1027165Y1478386D02*
Y1486260D01*
G01X1025197Y1485276D02*
Y1479370D01*
G01X1023228Y1483484D02*
Y1481162D01*
G01X1022441Y1489449D02*
Y1495197D01*
G01Y1479449D02*
Y1485197D01*
G01Y1471358D02*
Y1469449D01*
G01Y1475197D02*
Y1473288D01*
G01X1021653Y1479449D02*
Y1475197D01*
G01Y1489449D02*
Y1485197D01*
G01X1020472Y1479449D02*
Y1475197D01*
G01Y1489449D02*
Y1485197D01*
G01X1019685Y1473288D02*
Y1474449D01*
G01Y1471358D02*
Y1470197D01*
G01X1018025Y1479449D02*
Y1475197D01*
G01Y1489449D02*
Y1485197D01*
G01X1016844Y1479449D02*
Y1475197D01*
G01Y1489449D02*
Y1485197D01*
G01X1015663D02*
Y1489449D01*
G01Y1475197D02*
Y1479449D01*
G01X1035984Y1473681D02*
X1032047Y1473288D01*
G01X1019291Y1472894D02*
X1019685Y1473288D01*
G01X1027165Y1498386D02*
G03X1028149Y1497402I984J0D01*
G01Y1507244D02*
G03X1027165Y1506260I0J-984D01*
G01X1019291Y1511752D02*
X1019685Y1511358D01*
G01X1032047D02*
X1035984Y1510965D01*
G01X1039921Y1511358D02*
X1019685D01*
G01X1019291Y1510965D02*
X1072855D01*
G01X1039921Y1510197D02*
X1019291D01*
G01Y1509449D02*
X1022441D01*
G01X1035787Y1507244D02*
X1019291D01*
G01Y1505276D02*
X1027165D01*
G01X1030921D02*
X1027165D01*
G01X1019291Y1505197D02*
X1022441D01*
G01X1039921Y1503484D02*
X1019291D01*
G01Y1501162D02*
X1039921D01*
G01X1022441Y1499449D02*
X1019291D01*
G01X1027165Y1499370D02*
X1030921D01*
G01X1019291D02*
X1027165D01*
G01X1019291Y1497402D02*
X1035787D01*
G01X1019291Y1495197D02*
X1022441D01*
G01X1019291Y1494449D02*
X1039921D01*
G01X1019291Y1493484D02*
X1039921D01*
G01X1019291Y1491162D02*
X1039921D01*
G01X1030921Y1499370D02*
Y1505276D01*
G01X1030118D02*
Y1499370D01*
G01X1028362Y1505276D02*
Y1499370D01*
G01X1027559Y1505276D02*
Y1499370D01*
G01X1027165Y1498386D02*
Y1506260D01*
G01X1025197Y1505276D02*
Y1499370D01*
G01X1023228Y1493484D02*
Y1491162D01*
G01Y1503484D02*
Y1501162D01*
G01X1022441Y1499449D02*
Y1505197D01*
G01Y1511358D02*
Y1509449D01*
G01X1021653Y1499449D02*
Y1495197D01*
G01Y1509449D02*
Y1505197D01*
G01X1020472Y1499449D02*
Y1495197D01*
G01Y1509449D02*
Y1505197D01*
G01X1019685Y1511358D02*
Y1510197D01*
G01X1018025Y1499449D02*
Y1495197D01*
G01Y1509449D02*
Y1505197D01*
G01X1016844Y1499449D02*
Y1495197D01*
G01Y1509449D02*
Y1505197D01*
G01X1015663D02*
Y1509449D01*
G01Y1495197D02*
Y1499449D01*
G01X1027165Y1518386D02*
G03X1028149Y1517402I984J0D01*
G01Y1527244D02*
G03X1027165Y1526260I0J-984D01*
G01X1019291Y1531162D02*
X1039921D01*
G01Y1530197D02*
X1019291D01*
G01X1022441Y1529449D02*
X1019291D01*
G01X1035787Y1527244D02*
X1019291D01*
G01Y1525276D02*
X1027165D01*
G01X1030921D02*
X1027165D01*
G01X1019291Y1525197D02*
X1022441D01*
G01X1039921Y1523484D02*
X1019291D01*
G01Y1521162D02*
X1039921D01*
G01X1022441Y1519449D02*
X1019291D01*
G01X1027165Y1519370D02*
X1030921D01*
G01X1019291D02*
X1027165D01*
G01X1019291Y1517402D02*
X1035787D01*
G01X1019291Y1515197D02*
X1022441D01*
G01X1039921Y1514449D02*
X1019291D01*
G01Y1513681D02*
X1072855D01*
G01X1039921Y1513288D02*
X1019685D01*
G01X1030921Y1525276D02*
Y1519370D01*
G01X1030118Y1525276D02*
Y1519370D01*
G01X1028362Y1525276D02*
Y1519370D01*
G01X1027559Y1525276D02*
Y1519370D01*
G01X1027165Y1518386D02*
Y1526260D01*
G01X1025197Y1525276D02*
Y1519370D01*
G01X1023228Y1523484D02*
Y1521162D01*
G01Y1533484D02*
Y1531162D01*
G01X1022441Y1529449D02*
Y1535197D01*
G01Y1519449D02*
Y1525197D01*
G01Y1513288D02*
Y1515197D01*
G01X1021653Y1519449D02*
Y1515197D01*
G01Y1529449D02*
Y1525197D01*
G01X1020472Y1519449D02*
Y1515197D01*
G01Y1529449D02*
Y1525197D01*
G01X1019685Y1513288D02*
Y1514449D01*
G01X1018025Y1519449D02*
Y1515197D01*
G01Y1529449D02*
Y1525197D01*
G01X1016844Y1519449D02*
Y1515197D01*
G01Y1529449D02*
Y1525197D01*
G01X1015663D02*
Y1529449D01*
G01Y1515197D02*
Y1519449D01*
G01X1035984Y1513681D02*
X1032047Y1513288D01*
G01X1019685D02*
X1019291Y1512894D01*
G01X1027165Y1538386D02*
G03X1028149Y1537402I984J0D01*
G01Y1547244D02*
G03X1027165Y1546260I0J-984D01*
G01X1019291Y1551752D02*
X1019685Y1551358D01*
G01X1032047D02*
X1035984Y1550965D01*
G01X1019291Y1553681D02*
X1072855D01*
G01X1019685Y1553288D02*
X1039921D01*
G01Y1551358D02*
X1019685D01*
G01X1019291Y1550965D02*
X1072855D01*
G01X1039921Y1550197D02*
X1019291D01*
G01Y1549449D02*
X1022441D01*
G01X1035787Y1547244D02*
X1019291D01*
G01Y1545276D02*
X1027165D01*
G01X1030921D02*
X1027165D01*
G01X1019291Y1545197D02*
X1022441D01*
G01X1039921Y1543484D02*
X1019291D01*
G01Y1541162D02*
X1039921D01*
G01X1022441Y1539449D02*
X1019291D01*
G01X1027165Y1539370D02*
X1030921D01*
G01X1019291D02*
X1027165D01*
G01X1019291Y1537402D02*
X1035787D01*
G01X1019291Y1535197D02*
X1022441D01*
G01X1019291Y1534449D02*
X1039921D01*
G01X1019291Y1533484D02*
X1039921D01*
G01X1035984Y1553681D02*
X1032047Y1553288D01*
G01X1030921Y1539370D02*
Y1545276D01*
G01X1030118D02*
Y1539370D01*
G01X1028362Y1545276D02*
Y1539370D01*
G01X1027559Y1545276D02*
Y1539370D01*
G01X1027165Y1546260D02*
Y1538386D01*
G01X1025197Y1545276D02*
Y1539370D01*
G01X1023228Y1543484D02*
Y1541162D01*
G01X1022441Y1539449D02*
Y1545197D01*
G01Y1551358D02*
Y1549449D01*
G01Y1555197D02*
Y1553288D01*
G01X1021653Y1539449D02*
Y1535197D01*
G01Y1549449D02*
Y1545197D01*
G01X1020472Y1539449D02*
Y1535197D01*
G01Y1549449D02*
Y1545197D01*
G01X1019685Y1554449D02*
Y1553288D01*
G01Y1551358D02*
Y1550197D01*
G01X1018025Y1539449D02*
Y1535197D01*
G01Y1549449D02*
Y1545197D01*
G01X1016844Y1539449D02*
Y1535197D01*
G01Y1549449D02*
Y1545197D01*
G01X1015663D02*
Y1549449D01*
G01Y1535197D02*
Y1539449D01*
G01X1019291Y1552894D02*
X1019685Y1553288D01*
G01X1027165Y1558386D02*
G03X1028149Y1557402I984J0D01*
G01Y1567244D02*
G03X1027165Y1566260I0J-984D01*
G01X1019291Y1574449D02*
X1039921D01*
G01Y1573484D02*
X1019291D01*
G01Y1571162D02*
X1039921D01*
G01Y1570197D02*
X1019291D01*
G01X1022441Y1569449D02*
X1019291D01*
G01X1035787Y1567244D02*
X1019291D01*
G01Y1565276D02*
X1027165D01*
G01X1030921D02*
X1027165D01*
G01X1019291Y1565197D02*
X1022441D01*
G01X1019291Y1563484D02*
X1039921D01*
G01Y1561162D02*
X1019291D01*
G01X1022441Y1559449D02*
X1019291D01*
G01X1027165Y1559370D02*
X1030921D01*
G01X1019291D02*
X1027165D01*
G01X1019291Y1557402D02*
X1035787D01*
G01X1019291Y1555197D02*
X1022441D01*
G01X1039921Y1554449D02*
X1019291D01*
G01X1030921Y1559370D02*
Y1565276D01*
G01X1030118D02*
Y1559370D01*
G01X1028362D02*
Y1565276D01*
G01X1027559D02*
Y1559370D01*
G01X1027165Y1558386D02*
Y1566260D01*
G01X1025197Y1565276D02*
Y1559370D01*
G01X1023228Y1563484D02*
Y1561162D01*
G01Y1573484D02*
Y1571162D01*
G01X1022441Y1569449D02*
Y1575197D01*
G01Y1559449D02*
Y1565197D01*
G01X1021653Y1559449D02*
Y1555197D01*
G01Y1569449D02*
Y1565197D01*
G01X1020472Y1559449D02*
Y1555197D01*
G01Y1569449D02*
Y1565197D01*
G01X1018025Y1559449D02*
Y1555197D01*
G01Y1569449D02*
Y1565197D01*
G01X1016844Y1559449D02*
Y1555197D01*
G01Y1569449D02*
Y1565197D01*
G01X1015663D02*
Y1569449D01*
G01Y1555197D02*
Y1559449D01*
G01X1027165Y1578386D02*
G03X1028149Y1577402I984J0D01*
G01Y1587244D02*
G03X1027165Y1586260I0J-984D01*
G01X1019291Y1591752D02*
X1019685Y1591358D01*
G01X1032047D02*
X1035984Y1590965D01*
G01X1019291Y1595197D02*
X1022441D01*
G01X1039921Y1594449D02*
X1019291D01*
G01Y1593681D02*
X1072855D01*
G01X1039921Y1593288D02*
X1019685D01*
G01Y1591358D02*
X1039921D01*
G01X1019291Y1590965D02*
X1072855D01*
G01X1019291Y1590197D02*
X1039921D01*
G01X1019291Y1589449D02*
X1022441D01*
G01X1035787Y1587244D02*
X1019291D01*
G01Y1585276D02*
X1027165D01*
G01X1030921D02*
X1027165D01*
G01X1019291Y1585197D02*
X1022441D01*
G01X1039921Y1583484D02*
X1019291D01*
G01Y1581162D02*
X1039921D01*
G01X1022441Y1579449D02*
X1019291D01*
G01X1027165Y1579370D02*
X1030921D01*
G01X1019291D02*
X1027165D01*
G01X1019291Y1577402D02*
X1035787D01*
G01X1019291Y1575197D02*
X1022441D01*
G01X1035984Y1593681D02*
X1032047Y1593288D01*
G01X1030921Y1579370D02*
Y1585276D01*
G01X1030118D02*
Y1579370D01*
G01X1028362Y1585276D02*
Y1579370D01*
G01X1027559Y1585276D02*
Y1579370D01*
G01X1027165Y1578386D02*
Y1586260D01*
G01X1025197Y1585276D02*
Y1579370D01*
G01X1023228Y1583484D02*
Y1581162D01*
G01X1022441Y1579449D02*
Y1585197D01*
G01Y1591358D02*
Y1589449D01*
G01Y1595197D02*
Y1593288D01*
G01X1021653Y1579449D02*
Y1575197D01*
G01Y1589449D02*
Y1585197D01*
G01Y1599449D02*
Y1595197D01*
G01X1020472Y1579449D02*
Y1575197D01*
G01Y1589449D02*
Y1585197D01*
G01Y1599449D02*
Y1595197D01*
G01X1019685Y1593288D02*
Y1594449D01*
G01Y1591358D02*
Y1590197D01*
G01X1018025Y1579449D02*
Y1575197D01*
G01Y1589449D02*
Y1585197D01*
G01Y1599449D02*
Y1595197D01*
G01X1016844Y1579449D02*
Y1575197D01*
G01Y1589449D02*
Y1585197D01*
G01Y1599449D02*
Y1595197D01*
G01X1015663D02*
Y1599449D01*
G01Y1585197D02*
Y1589449D01*
G01Y1575197D02*
Y1579449D01*
G01X1019291Y1592894D02*
X1019685Y1593288D01*
G01X1028149Y1607244D02*
G03X1027165Y1606260I0J-984D01*
G01X1019291D02*
G03X1015354Y1610197I-3937J0D01*
G01X1027165Y1598386D02*
G03X1028149Y1597402I984J0D01*
G01X1019291Y1607933D02*
X1015354Y1611870D01*
G01X1019291Y1607933D02*
X1015354Y1611870D01*
G01X1032047Y1611358D02*
X1035984Y1610965D01*
G01X1015354Y1610197D02*
X1039921D01*
G01X1022441Y1609449D02*
X1017611D01*
G01X1035787Y1607244D02*
X1019166D01*
G01X1027165Y1605276D02*
X1019291D01*
G01X1030921D02*
X1027165D01*
G01X1019291Y1605197D02*
X1022441D01*
G01X1039921Y1603484D02*
X1019291D01*
G01X1039921Y1601162D02*
X1019291D01*
G01X1022441Y1599449D02*
X1019291D01*
G01X1027165Y1599370D02*
X1030921D01*
G01X1019291D02*
X1027165D01*
G01X1019291Y1597402D02*
X1035787D01*
G01X1030921Y1599370D02*
Y1605276D01*
G01X1030118D02*
Y1599370D01*
G01X1029527Y1615394D02*
Y1679449D01*
G01X1028362Y1599370D02*
Y1605276D01*
G01X1027559D02*
Y1599370D01*
G01X1027165Y1598386D02*
Y1606260D01*
G01X1025197Y1605276D02*
Y1599370D01*
G01X1023228Y1603484D02*
Y1601162D01*
G01X1022441Y1609449D02*
Y1611358D01*
G01Y1599449D02*
Y1605197D01*
G01X1021653Y1609449D02*
Y1605197D01*
G01X1020472Y1609449D02*
Y1605197D01*
G01X1019291Y1612166D02*
Y1606260D01*
G01Y1617756D02*
Y1615788D01*
G01X1018025Y1609128D02*
Y1609449D01*
G01Y1609128D02*
Y1605197D01*
G01X1017762Y1609449D02*
Y1609374D01*
G01X1016844Y1609449D02*
Y1605197D01*
G01X1015663D02*
Y1609449D01*
G01X1015354Y1616083D02*
X1017027Y1617756D01*
G01X1015354Y1616083D02*
X1017027Y1617756D01*
G01X1029586Y1638603D02*
X1030512Y1637677D01*
G01X1029527Y1638071D02*
X1030512Y1637087D01*
G01X1029586Y1633603D02*
X1030512Y1632677D01*
G01X1029527Y1633071D02*
X1030512Y1632087D01*
G01X1029586Y1628603D02*
X1030512Y1627677D01*
G01X1029527Y1628071D02*
X1030512Y1627087D01*
G01X1029586Y1623603D02*
X1030512Y1622677D01*
G01Y1622087D02*
X1029527Y1623071D01*
G01X1033282Y1637677D02*
X1034508Y1636969D01*
G01X1033282Y1632677D02*
X1034508Y1631969D01*
G01X1033282Y1627677D02*
X1034508Y1626969D01*
G01X1033282Y1622677D02*
X1034508Y1621969D01*
G01X1029527Y1637874D02*
X1030315D01*
G01X1048031Y1637677D02*
X1030512D01*
G01Y1637087D02*
X1079291D01*
G01Y1635118D02*
X1030512D01*
G01X1048031Y1634528D02*
X1030512D01*
G01X1030315Y1634331D02*
X1029527D01*
G01X1030315Y1632874D02*
X1029527D01*
G01X1030512Y1632677D02*
X1048031D01*
G01X1030512Y1632087D02*
X1079291D01*
G01X1030512Y1630118D02*
X1079291D01*
G01X1030512Y1629528D02*
X1048031D01*
G01X1030315Y1629331D02*
X1029527D01*
G01Y1627874D02*
X1030315D01*
G01X1048031Y1627677D02*
X1030512D01*
G01Y1627087D02*
X1079291D01*
G01Y1625118D02*
X1030512D01*
G01X1048031Y1624528D02*
X1030512D01*
G01X1030315Y1624331D02*
X1029527D01*
G01X1030315Y1622874D02*
X1029527D01*
G01X1048031Y1622677D02*
X1030512D01*
G01Y1622087D02*
X1079291D01*
G01Y1620118D02*
X1030512D01*
G01X1048031Y1619528D02*
X1030512D01*
G01X1030315Y1619331D02*
X1029527D01*
G01X1030512Y1622677D02*
Y1619528D01*
G01Y1627677D02*
Y1624528D01*
G01Y1632677D02*
Y1629528D01*
G01Y1637677D02*
Y1634528D01*
G01X1029134Y1622087D02*
Y1620118D01*
G01Y1627087D02*
Y1625118D01*
G01Y1632087D02*
Y1630118D01*
G01Y1637087D02*
Y1635118D01*
G01X1028728Y1622087D02*
Y1620118D01*
G01Y1627087D02*
Y1625118D01*
G01Y1632087D02*
Y1630118D01*
G01Y1637087D02*
Y1635118D01*
G01X1028484D02*
Y1637087D01*
G01Y1630118D02*
Y1632087D01*
G01Y1625118D02*
Y1627087D01*
G01Y1620118D02*
Y1622087D01*
G01X1019291Y1625118D02*
Y1622087D01*
G01Y1625118D02*
Y1622087D01*
G01D02*
Y1620020D01*
G01Y1622087D02*
Y1620020D01*
G01Y1630118D02*
Y1627087D01*
G01Y1630118D02*
Y1627087D01*
G01D02*
Y1625118D01*
G01Y1627087D02*
Y1625118D01*
G01Y1632087D02*
Y1630118D01*
G01Y1632087D02*
Y1630118D01*
G01Y1635118D02*
Y1632087D01*
G01Y1635118D02*
Y1632087D01*
G01Y1637087D02*
Y1635118D01*
G01Y1637087D02*
Y1635118D01*
G01Y1640118D02*
Y1637087D01*
G01Y1640118D02*
Y1637087D01*
G01X1029527Y1618543D02*
X1030512Y1619528D01*
G01Y1620118D02*
X1029527Y1619134D01*
G01X1029586Y1623603D02*
X1030512Y1624528D01*
G01Y1625118D02*
X1029527Y1624134D01*
G01X1030512Y1629528D02*
X1029586Y1628603D01*
G01X1029527Y1629134D02*
X1030512Y1630118D01*
G01X1017027Y1617756D02*
X1019291Y1620020D01*
G01X1017027Y1617756D02*
X1019291Y1620020D01*
G01X1029586Y1633603D02*
X1030512Y1634528D01*
G01Y1635118D02*
X1029527Y1634134D01*
G01X1034508Y1620236D02*
X1033282Y1619528D01*
G01X1034508Y1625236D02*
X1033282Y1624528D01*
G01X1034508Y1630236D02*
X1033282Y1629528D01*
G01X1034508Y1635236D02*
X1033282Y1634528D01*
G01X1029586Y1658603D02*
X1030512Y1657677D01*
G01X1029527Y1658071D02*
X1030512Y1657087D01*
G01X1029586Y1653603D02*
X1030512Y1652677D01*
G01X1029527Y1653071D02*
X1030512Y1652087D01*
G01X1029586Y1648603D02*
X1030512Y1647677D01*
G01X1029527Y1648071D02*
X1030512Y1647087D01*
G01X1029586Y1643603D02*
X1030512Y1642677D01*
G01X1029527Y1643071D02*
X1030512Y1642087D01*
G01X1033282Y1657677D02*
X1034508Y1656969D01*
G01X1033282Y1652677D02*
X1034508Y1651969D01*
G01X1033282Y1647677D02*
X1034508Y1646969D01*
G01X1033282Y1642677D02*
X1034508Y1641969D01*
G01X1048031Y1659528D02*
X1030512D01*
G01X1030315Y1659331D02*
X1029527D01*
G01Y1657874D02*
X1030315D01*
G01X1048031Y1657677D02*
X1030512D01*
G01Y1657087D02*
X1079291D01*
G01Y1655118D02*
X1030512D01*
G01X1048031Y1654528D02*
X1030512D01*
G01X1030315Y1654331D02*
X1029527D01*
G01X1030315Y1652874D02*
X1029527D01*
G01X1030512Y1652677D02*
X1048031D01*
G01X1030512Y1652087D02*
X1079291D01*
G01Y1650118D02*
X1030512D01*
G01Y1649528D02*
X1048031D01*
G01X1030315Y1649331D02*
X1029527D01*
G01Y1647874D02*
X1030315D01*
G01X1048031Y1647677D02*
X1030512D01*
G01Y1647087D02*
X1079291D01*
G01Y1645118D02*
X1030512D01*
G01X1048031Y1644528D02*
X1030512D01*
G01X1030315Y1644331D02*
X1029527D01*
G01X1030315Y1642874D02*
X1029527D01*
G01X1030512Y1642677D02*
X1048031D01*
G01X1030512Y1642087D02*
X1079291D01*
G01Y1640118D02*
X1030512D01*
G01Y1639528D02*
X1048031D01*
G01X1030315Y1639331D02*
X1029527D01*
G01X1030512Y1642677D02*
Y1639528D01*
G01Y1647677D02*
Y1644528D01*
G01Y1652677D02*
Y1649528D01*
G01Y1657677D02*
Y1654528D01*
G01Y1662677D02*
Y1659528D01*
G01X1029134Y1642087D02*
Y1640118D01*
G01Y1647087D02*
Y1645118D01*
G01Y1652087D02*
Y1650118D01*
G01Y1657087D02*
Y1655118D01*
G01X1028728Y1642087D02*
Y1640118D01*
G01Y1647087D02*
Y1645118D01*
G01Y1652087D02*
Y1650118D01*
G01Y1657087D02*
Y1655118D01*
G01X1028484D02*
Y1657087D01*
G01Y1650118D02*
Y1652087D01*
G01Y1645118D02*
Y1647087D01*
G01Y1640118D02*
Y1642087D01*
G01X1019291D02*
Y1640118D01*
G01Y1642087D02*
Y1640118D01*
G01Y1645118D02*
Y1642087D01*
G01Y1645118D02*
Y1642087D01*
G01Y1647087D02*
Y1645118D01*
G01Y1647087D02*
Y1645118D01*
G01Y1650118D02*
Y1647087D01*
G01Y1650118D02*
Y1647087D01*
G01Y1652087D02*
Y1650118D01*
G01Y1652087D02*
Y1650118D01*
G01Y1655118D02*
Y1652087D01*
G01Y1655118D02*
Y1652087D01*
G01Y1657087D02*
Y1655118D01*
G01Y1657087D02*
Y1655118D01*
G01Y1660118D02*
Y1657087D01*
G01Y1660118D02*
Y1657087D01*
G01X1030512Y1639528D02*
X1029586Y1638603D01*
G01X1030512Y1640118D02*
X1029527Y1639134D01*
G01X1029586Y1643603D02*
X1030512Y1644528D01*
G01Y1645118D02*
X1029527Y1644134D01*
G01X1030512Y1649528D02*
X1029586Y1648603D01*
G01X1030512Y1650118D02*
X1029527Y1649134D01*
G01X1029586Y1653603D02*
X1030512Y1654528D01*
G01Y1655118D02*
X1029527Y1654134D01*
G01X1030512Y1659528D02*
X1029586Y1658603D01*
G01X1030512Y1660118D02*
X1029527Y1659134D01*
G01X1034508Y1640236D02*
X1033282Y1639528D01*
G01X1034508Y1645236D02*
X1033282Y1644528D01*
G01X1034508Y1650236D02*
X1033282Y1649528D01*
G01X1034508Y1655236D02*
X1033282Y1654528D01*
G01X1034508Y1660236D02*
X1033282Y1659528D01*
G01X1024212Y1681417D02*
G03X1019327Y1677087I0J-4921D01*
G01X1024212Y1681417D02*
G03X1019330Y1677118I0J-4921D01*
G01X1019327Y1677087D02*
G03X1019291Y1676496I4885J-594D01*
G01X1019330Y1677118D02*
G03X1019291Y1676496I4883J-618D01*
G01X1030512Y1677677D02*
X1029527Y1678662D01*
G01Y1678071D02*
X1030512Y1677087D01*
G01X1029586Y1673603D02*
X1030512Y1672677D01*
G01X1029527Y1673071D02*
X1030512Y1672087D01*
G01X1029586Y1668603D02*
X1030512Y1667677D01*
G01X1029527Y1668071D02*
X1030512Y1667087D01*
G01X1029586Y1663603D02*
X1030512Y1662677D01*
G01Y1662087D02*
X1029527Y1663071D01*
G01X1033282Y1677677D02*
X1034508Y1676969D01*
G01X1033282Y1672677D02*
X1034508Y1671969D01*
G01X1033282Y1667677D02*
X1034508Y1666969D01*
G01X1033282Y1662677D02*
X1034508Y1661969D01*
G01X1020380Y1679449D02*
X1034016D01*
G01X1029527Y1677874D02*
X1030315D01*
G01X1048031Y1677677D02*
X1030512D01*
G01Y1677087D02*
X1079291D01*
G01Y1675118D02*
X1030512D01*
G01X1048031Y1674528D02*
X1030512D01*
G01X1030315Y1674331D02*
X1029527D01*
G01X1030315Y1672874D02*
X1029527D01*
G01X1030512Y1672677D02*
X1048031D01*
G01X1030512Y1672087D02*
X1079291D01*
G01Y1670118D02*
X1030512D01*
G01Y1669528D02*
X1048031D01*
G01X1030315Y1669331D02*
X1029527D01*
G01Y1667874D02*
X1030315D01*
G01X1048031Y1667677D02*
X1030512D01*
G01Y1667087D02*
X1079291D01*
G01Y1665118D02*
X1030512D01*
G01X1048031Y1664528D02*
X1030512D01*
G01X1030315Y1664331D02*
X1029527D01*
G01Y1662874D02*
X1030315D01*
G01X1048031Y1662677D02*
X1030512D01*
G01Y1662087D02*
X1079291D01*
G01Y1660118D02*
X1030512D01*
G01Y1674528D02*
Y1677677D01*
G01Y1667677D02*
Y1664528D01*
G01Y1672677D02*
Y1669528D01*
G01X1029527Y1681811D02*
Y1679449D01*
G01X1029134Y1662087D02*
Y1660118D01*
G01Y1667087D02*
Y1665118D01*
G01Y1672087D02*
Y1670118D01*
G01Y1677087D02*
Y1675118D01*
G01X1028728Y1662087D02*
Y1660118D01*
G01Y1667087D02*
Y1665118D01*
G01Y1672087D02*
Y1670118D01*
G01Y1677087D02*
Y1675118D01*
G01X1028484D02*
Y1677087D01*
G01Y1670118D02*
Y1672087D01*
G01Y1665118D02*
Y1667087D01*
G01Y1660118D02*
Y1662087D01*
G01X1019291D02*
Y1660118D01*
G01Y1662087D02*
Y1660118D01*
G01Y1665118D02*
Y1662087D01*
G01Y1665118D02*
Y1662087D01*
G01Y1667087D02*
Y1665118D01*
G01Y1667087D02*
Y1665118D01*
G01Y1670118D02*
Y1667087D01*
G01Y1670118D02*
Y1667087D01*
G01Y1672087D02*
Y1670118D01*
G01Y1672087D02*
Y1670118D01*
G01Y1675118D02*
Y1672087D01*
G01Y1675118D02*
Y1672087D01*
G01Y1676496D02*
Y1675118D01*
G01Y1676496D02*
Y1675118D01*
G01X1029586Y1663603D02*
X1030512Y1664528D01*
G01Y1665118D02*
X1029527Y1664134D01*
G01X1030512Y1669528D02*
X1029586Y1668603D01*
G01X1030512Y1670118D02*
X1029527Y1669134D01*
G01X1030512Y1674528D02*
X1029586Y1673603D01*
G01X1029527Y1674134D02*
X1030512Y1675118D01*
G01X1034508Y1665236D02*
X1033282Y1664528D01*
G01X1034508Y1670236D02*
X1033282Y1669528D01*
G01X1034508Y1675236D02*
X1033282Y1674528D01*
G01X1029527Y1681417D02*
X1024212D01*
G01X1029527D02*
X1024212D01*
G01X1033464Y1988189D02*
Y1685354D01*
G01Y1988189D02*
Y1685354D01*
G01X1029527Y1681417D02*
X1033464Y1685354D01*
G01X1029527Y1681417D02*
X1033464Y1685354D01*
G01X1034016Y1707008D02*
G03X1033481Y1708356I-1969J-1D01*
G01D02*
G03X1032047Y1708977I-1435J-1348D01*
G01X1041338Y1739719D02*
G03X1033464I-3937J0D01*
G01X1041338D02*
G03X1033464I-3937J0D01*
G01Y1763339D02*
G03X1041338I3937J0D01*
G01X1033464D02*
G03X1041338I3937J0D01*
G01Y1959242D02*
G03X1033464I-3937J0D01*
G01X1041338D02*
G03X1033464I-3937J0D01*
G01X1033465Y1986164D02*
Y2064661D01*
G01X1033464Y1982862D02*
G03X1041338I3937J0D01*
G01X1033464D02*
G03X1041338I3937J0D01*
G01X1033464Y1988189D02*
G03X1029527Y1992126I-3937J0D01*
G01X1033464Y1988189D02*
G03X1029527Y1992126I-3937J0D01*
G01X1030748Y2066114D02*
X1029949Y2066713D01*
X1029550Y2067412D01*
X1029417Y2068210D01*
X1029683Y2069208D01*
X1030349Y2069907D01*
X1031147Y2070107D01*
X1031946Y2070007D01*
X1032611Y2069607D01*
X1033942Y2067611D01*
X1034873Y2066713D01*
X1036205Y2066114D01*
X1037402Y2065914D01*
Y2070107D01*
G01Y2075995D02*
X1037269Y2076694D01*
X1036870Y2077493D01*
X1036205Y2077992D01*
X1035273Y2078191D01*
X1034341Y2077992D01*
X1033543Y2077393D01*
X1033143Y2076495D01*
Y2075496D01*
X1032877Y2074897D01*
X1032212Y2074398D01*
X1031280Y2074199D01*
X1030349Y2074498D01*
X1029683Y2075197D01*
X1029417Y2075995D01*
X1029683Y2076794D01*
X1030349Y2077493D01*
X1031280Y2077792D01*
X1032212Y2077592D01*
X1032877Y2077094D01*
X1033143Y2076495D01*
Y2075496D01*
X1033543Y2074598D01*
X1034341Y2073999D01*
X1035273Y2073800D01*
X1036205Y2073999D01*
X1036870Y2074498D01*
X1037269Y2075297D01*
X1037402Y2075995D01*
G01X1030748Y2082084D02*
X1029949Y2082683D01*
X1029550Y2083382D01*
X1029417Y2084180D01*
X1029683Y2085178D01*
X1030349Y2085877D01*
X1031147Y2086077D01*
X1031946Y2085977D01*
X1032611Y2085577D01*
X1033942Y2083581D01*
X1034873Y2082683D01*
X1036205Y2082084D01*
X1037402Y2081884D01*
Y2086077D01*
G01X1037668Y2091965D02*
X1037535Y2091766D01*
X1037269D01*
X1037136Y2091965D01*
X1037269Y2092165D01*
X1037535D01*
X1037668Y2091965D01*
G01X1036205Y2097755D02*
X1036870Y2098353D01*
X1037269Y2099052D01*
X1037402Y2099950D01*
X1037136Y2100849D01*
X1036604Y2101547D01*
X1035672Y2102047D01*
X1034607Y2102146D01*
X1033543Y2101947D01*
X1032877Y2101448D01*
X1032345Y2100749D01*
X1032212Y2100050D01*
X1032345Y2099352D01*
X1032877Y2098453D01*
X1029417Y2098753D01*
Y2101448D01*
G01Y2107935D02*
X1029683Y2107137D01*
X1030349Y2106538D01*
X1031147Y2106139D01*
X1032212Y2105839D01*
X1033410Y2105740D01*
X1034607Y2105839D01*
X1035672Y2106139D01*
X1036471Y2106538D01*
X1037136Y2107137D01*
X1037402Y2107935D01*
X1037136Y2108734D01*
X1036471Y2109333D01*
X1035672Y2109732D01*
X1034607Y2110032D01*
X1033410Y2110131D01*
X1032212Y2110032D01*
X1031147Y2109732D01*
X1030349Y2109333D01*
X1029683Y2108734D01*
X1029417Y2107935D01*
G01X1041338Y24677D02*
Y0D01*
G01D02*
X1097205D01*
G01X1041338Y217343D02*
Y48297D01*
G01Y445039D02*
Y240964D01*
G01Y697473D02*
Y468601D01*
G01Y996852D02*
Y721093D01*
G01Y1344060D02*
Y1020472D01*
G01Y1367680D02*
Y1393701D01*
G01D02*
X1097205D01*
G01X1034016Y1403228D02*
Y1430788D01*
G01Y1423307D02*
X1079291D01*
G01Y1421339D02*
X1034016D01*
G01X1036723Y1443318D02*
X1036678Y1443091D01*
G01X1036771Y1443390D02*
X1036723Y1443318D01*
G01X1037040Y1443636D02*
X1036850Y1443508D01*
G01X1037267Y1443681D02*
X1037040Y1443636D01*
G01Y1441010D02*
X1036850Y1441138D01*
G01X1037267Y1440965D02*
X1037040Y1441010D01*
G01X1036723Y1441327D02*
X1036771Y1441255D01*
G01X1036678Y1441555D02*
X1036723Y1441327D01*
G01X1036594Y1441280D02*
X1036678Y1441162D01*
G01X1036544Y1441411D02*
X1036594Y1441280D01*
G01X1036527Y1441555D02*
X1036544Y1441411D01*
G01X1036951Y1440988D02*
X1037114Y1440965D01*
G01X1036801Y1441055D02*
X1036951Y1440988D01*
G01X1036675Y1441162D02*
X1036801Y1441055D01*
G01X1054685Y1439784D02*
G03X1053701Y1438799I0J-984D01*
G01Y1435847D02*
G03X1054685Y1434862I984J-1D01*
G01X1053701Y1445847D02*
G03X1054685Y1444862I984J-1D01*
G01X1036771Y1441791D02*
G03X1037165Y1441398I394J1D01*
G01Y1443248D02*
G03X1036771Y1442854I0J-394D01*
G01Y1446260D02*
G03X1035787Y1447244I-984J0D01*
G01Y1437402D02*
G03X1036771Y1438386I0J984D01*
G01X1036850Y1441138D02*
X1036771Y1441255D01*
G01X1037114Y1440965D02*
X1036951Y1440988D01*
G01X1053701Y1438799D02*
Y1435847D01*
G01Y1448799D02*
Y1445847D01*
G01X1040708Y1441398D02*
Y1443248D01*
G01X1039921Y1429213D02*
Y1685433D01*
G01X1036771Y1438386D02*
Y1446260D01*
G01X1036678Y1441555D02*
Y1443091D01*
G01X1036527D02*
Y1441555D01*
G01X1036264Y1447103D02*
Y1457543D01*
G01Y1437543D02*
Y1433681D01*
G01Y1447103D02*
Y1437543D01*
G01X1036111Y1441162D02*
Y1433681D01*
G01Y1451162D02*
Y1443484D01*
G01X1035984Y1437441D02*
Y1447204D01*
G01Y1457441D02*
Y1447204D01*
G01Y1437441D02*
Y1433681D01*
G01X1039921Y1445276D02*
X1036771D01*
G01X1054685Y1444862D02*
X1068464D01*
G01X1037114Y1443681D02*
X1072855D01*
G01X1079291Y1443248D02*
X1037165D01*
G01X1036678Y1443091D02*
X1036527D01*
G01X1036678Y1441555D02*
X1036527D01*
G01X1037165Y1441398D02*
X1079291D01*
G01X1037114Y1440965D02*
X1072855D01*
G01X1068464Y1439784D02*
X1054685D01*
G01X1039921Y1439370D02*
X1036771D01*
G01X1054685Y1434862D02*
X1068464D01*
G01X1079291Y1433248D02*
X1039921D01*
G01Y1429213D02*
X1074567D01*
G01X1036527Y1443091D02*
X1036544Y1443234D01*
G01X1037114Y1443681D02*
X1036951Y1443658D01*
G01X1036594Y1443366D02*
X1036544Y1443234D01*
G01X1036594Y1443366D02*
X1036678Y1443484D01*
G01X1036771Y1443390D02*
X1036850Y1443508D01*
G01X1036801Y1443591D02*
X1036675Y1443484D01*
G01X1036951Y1443658D02*
X1036801Y1443591D01*
G01X1036544Y1463234D02*
X1036527Y1463091D01*
G01X1036594Y1463366D02*
X1036544Y1463234D01*
G01X1036678Y1463484D02*
X1036594Y1463366D01*
G01X1036544Y1453234D02*
X1036527Y1453091D01*
G01X1036594Y1453366D02*
X1036544Y1453234D01*
G01X1036678Y1453484D02*
X1036594Y1453366D01*
G01X1036723Y1463318D02*
X1036678Y1463091D01*
G01X1036771Y1463390D02*
X1036723Y1463318D01*
G01Y1453318D02*
X1036678Y1453091D01*
G01X1036850Y1453508D02*
X1036723Y1453318D01*
G01X1037040Y1453636D02*
X1036850Y1453508D01*
G01X1037267Y1453681D02*
X1037040Y1453636D01*
G01Y1463636D02*
X1036850Y1463508D01*
G01X1037267Y1463681D02*
X1037040Y1463636D01*
G01Y1451010D02*
X1036850Y1451138D01*
G01X1037267Y1450965D02*
X1037040Y1451010D01*
G01Y1461010D02*
X1036850Y1461138D01*
G01X1037267Y1460965D02*
X1037040Y1461010D01*
G01X1036723Y1461327D02*
X1036771Y1461255D01*
G01X1036678Y1461555D02*
X1036723Y1461327D01*
G01X1036594Y1451280D02*
X1036678Y1451162D01*
G01X1036544Y1451411D02*
X1036594Y1451280D01*
G01X1036527Y1451555D02*
X1036544Y1451411D01*
G01X1036594Y1461280D02*
X1036678Y1461162D01*
G01X1036544Y1461411D02*
X1036594Y1461280D01*
G01X1036527Y1461555D02*
X1036544Y1461411D01*
G01X1036951Y1450988D02*
X1037114Y1450965D01*
G01X1036801Y1451055D02*
X1036951Y1450988D01*
G01X1036675Y1451162D02*
X1036801Y1451055D01*
G01X1036951Y1460988D02*
X1037114Y1460965D01*
G01X1036801Y1461055D02*
X1036951Y1460988D01*
G01X1036675Y1461162D02*
X1036801Y1461055D01*
G01X1054685Y1449784D02*
G03X1053701Y1448799I0J-984D01*
G01X1054685Y1459784D02*
G03X1053701Y1458799I0J-984D01*
G01Y1455847D02*
G03X1054685Y1454862I984J-1D01*
G01Y1469784D02*
G03X1053701Y1468799I0J-984D01*
G01Y1465847D02*
G03X1054685Y1464862I984J-1D01*
G01X1036771Y1461791D02*
G03X1037165Y1461398I394J1D01*
G01Y1463248D02*
G03X1036771Y1462854I0J-394D01*
G01Y1451791D02*
G03X1037165Y1451398I394J1D01*
G01Y1453248D02*
G03X1036771Y1452854I0J-394D01*
G01Y1466260D02*
G03X1035787Y1467244I-984J0D01*
G01Y1457402D02*
G03X1036771Y1458386I0J984D01*
G01X1036850Y1461138D02*
X1036771Y1461255D01*
G01X1036723Y1451327D02*
X1036850Y1451138D01*
G01X1036678Y1451555D02*
X1036723Y1451327D01*
G01X1037114Y1460965D02*
X1036951Y1460988D01*
G01X1037114Y1450965D02*
X1036951Y1450988D01*
G01X1036771Y1465276D02*
X1039921D01*
G01X1054685Y1464862D02*
X1068464D01*
G01X1037114Y1463681D02*
X1072855D01*
G01X1053701Y1458799D02*
Y1455847D01*
G01Y1468799D02*
Y1465847D01*
G01X1040708Y1461398D02*
Y1463248D01*
G01Y1453248D02*
Y1451398D01*
G01X1036771Y1458386D02*
Y1466260D01*
G01Y1451791D02*
Y1452854D01*
G01X1036678Y1453091D02*
Y1451555D01*
G01Y1463091D02*
Y1461555D01*
G01X1036527Y1453091D02*
Y1451555D01*
G01Y1463091D02*
Y1461555D01*
G01X1036264Y1467103D02*
Y1470965D01*
G01Y1467103D02*
Y1457543D01*
G01X1036111Y1461162D02*
Y1453484D01*
G01Y1470965D02*
Y1463484D01*
G01X1035984Y1457441D02*
Y1467204D01*
G01Y1470965D02*
Y1467204D01*
G01X1079291Y1463248D02*
X1037165D01*
G01X1036678Y1463091D02*
X1036527D01*
G01X1036678Y1461555D02*
X1036527D01*
G01X1037165Y1461398D02*
X1079291D01*
G01X1037114Y1460965D02*
X1072855D01*
G01X1068464Y1459784D02*
X1054685D01*
G01X1039921Y1459370D02*
X1036771D01*
G01X1054685Y1454862D02*
X1068464D01*
G01X1037114Y1453681D02*
X1072855D01*
G01X1079291Y1453248D02*
X1037165D01*
G01X1036678Y1453091D02*
X1036527D01*
G01X1036678Y1451555D02*
X1036527D01*
G01X1037165Y1451398D02*
X1079291D01*
G01X1037114Y1450965D02*
X1072855D01*
G01X1068464Y1449784D02*
X1054685D01*
G01X1037114Y1463681D02*
X1036951Y1463658D01*
G01X1037114Y1453681D02*
X1036951Y1453658D01*
G01X1036771Y1463390D02*
X1036850Y1463508D01*
G01X1036801Y1453591D02*
X1036675Y1453484D01*
G01X1036801Y1463591D02*
X1036675Y1463484D01*
G01X1036951Y1453658D02*
X1036801Y1453591D01*
G01X1036951Y1463658D02*
X1036801Y1463591D01*
G01X1036723Y1483318D02*
X1036678Y1483091D01*
G01X1036771Y1483390D02*
X1036723Y1483318D01*
G01X1037040Y1483636D02*
X1036850Y1483508D01*
G01X1037267Y1483681D02*
X1037040Y1483636D01*
G01Y1481010D02*
X1036850Y1481138D01*
G01X1037267Y1480965D02*
X1037040Y1481010D01*
G01X1036723Y1481327D02*
X1036771Y1481255D01*
G01X1036678Y1481555D02*
X1036723Y1481327D01*
G01X1036594Y1481280D02*
X1036678Y1481162D01*
G01X1036544Y1481411D02*
X1036594Y1481280D01*
G01X1036527Y1481555D02*
X1036544Y1481411D01*
G01X1036951Y1480988D02*
X1037114Y1480965D01*
G01X1036801Y1481055D02*
X1036951Y1480988D01*
G01X1036675Y1481162D02*
X1036801Y1481055D01*
G01X1054685Y1479784D02*
G03X1053701Y1478799I0J-984D01*
G01Y1475847D02*
G03X1054685Y1474862I984J-1D01*
G01Y1489784D02*
G03X1053701Y1488799I0J-984D01*
G01Y1485847D02*
G03X1054685Y1484862I984J-1D01*
G01X1037165Y1483248D02*
G03X1036771Y1482854I0J-394D01*
G01Y1481791D02*
G03X1037165Y1481398I394J1D01*
G01X1036771Y1486260D02*
G03X1035787Y1487244I-984J0D01*
G01Y1477402D02*
G03X1036771Y1478386I0J984D01*
G01X1036850Y1481138D02*
X1036771Y1481255D01*
G01X1037114Y1480965D02*
X1036951Y1480988D01*
G01X1068464Y1489784D02*
X1054685D01*
G01X1039921Y1485276D02*
X1036771D01*
G01X1054685Y1484862D02*
X1068464D01*
G01X1037114Y1483681D02*
X1072855D01*
G01X1079291Y1483248D02*
X1037165D01*
G01X1036678Y1483091D02*
X1036527D01*
G01X1036678Y1481555D02*
X1036527D01*
G01X1037165Y1481398D02*
X1079291D01*
G01X1037114Y1480965D02*
X1072855D01*
G01X1068464Y1479784D02*
X1054685D01*
G01X1039921Y1479370D02*
X1036771D01*
G01X1054685Y1474862D02*
X1068464D01*
G01X1079291Y1473248D02*
X1039921D01*
G01Y1471398D02*
X1079291D01*
G01X1068464Y1469784D02*
X1054685D01*
G01X1053701Y1478799D02*
Y1475847D01*
G01Y1488799D02*
Y1485847D01*
G01X1040708Y1481398D02*
Y1483248D01*
G01X1036771Y1478386D02*
Y1486260D01*
G01X1036678Y1481555D02*
Y1483091D01*
G01X1036527D02*
Y1481555D01*
G01X1036264Y1487103D02*
Y1497543D01*
G01Y1477543D02*
Y1473681D01*
G01Y1487103D02*
Y1477543D01*
G01X1036111Y1481162D02*
Y1473681D01*
G01Y1491162D02*
Y1483484D01*
G01X1035984Y1477441D02*
Y1487204D01*
G01Y1497441D02*
Y1487204D01*
G01Y1477441D02*
Y1473681D01*
G01X1037114Y1483681D02*
X1036951Y1483658D01*
G01X1036544Y1483234D02*
X1036527Y1483091D01*
G01X1036544Y1483234D02*
X1036594Y1483366D01*
G01X1036678Y1483484D02*
X1036594Y1483366D01*
G01X1036771Y1483390D02*
X1036850Y1483508D01*
G01X1036801Y1483591D02*
X1036675Y1483484D01*
G01X1036951Y1483658D02*
X1036801Y1483591D01*
G01X1036723Y1503318D02*
X1036678Y1503091D01*
G01X1036771Y1503390D02*
X1036723Y1503318D01*
G01Y1493318D02*
X1036678Y1493091D01*
G01X1036850Y1493508D02*
X1036723Y1493318D01*
G01X1036544Y1503234D02*
X1036527Y1503091D01*
G01X1036594Y1503366D02*
X1036544Y1503234D01*
G01X1037040Y1493636D02*
X1036850Y1493508D01*
G01X1037267Y1493681D02*
X1037040Y1493636D01*
G01X1036594Y1493366D02*
X1036678Y1493484D01*
G01X1036544Y1493234D02*
X1036594Y1493366D01*
G01X1036527Y1493091D02*
X1036544Y1493234D01*
G01X1036595Y1493365D02*
X1036678Y1493484D01*
G01X1036545Y1493234D02*
X1036595Y1493365D01*
G01X1036527Y1493091D02*
X1036545Y1493234D01*
G01X1037040Y1503636D02*
X1036850Y1503508D01*
G01X1037267Y1503681D02*
X1037040Y1503636D01*
G01Y1491010D02*
X1036850Y1491138D01*
G01X1037267Y1490965D02*
X1037040Y1491010D01*
G01Y1501010D02*
X1036850Y1501138D01*
G01X1037267Y1500965D02*
X1037040Y1501010D01*
G01X1036723Y1501327D02*
X1036771Y1501255D01*
G01X1036678Y1501555D02*
X1036723Y1501327D01*
G01X1036594Y1491280D02*
X1036678Y1491162D01*
G01X1036544Y1491411D02*
X1036594Y1491280D01*
G01X1036527Y1491555D02*
X1036544Y1491411D01*
G01X1036594Y1501280D02*
X1036678Y1501162D01*
G01X1036544Y1501411D02*
X1036594Y1501280D01*
G01X1036527Y1501555D02*
X1036544Y1501411D01*
G01X1036951Y1490988D02*
X1037114Y1490965D01*
G01X1036801Y1491055D02*
X1036951Y1490988D01*
G01X1036675Y1491162D02*
X1036801Y1491055D01*
G01X1036951Y1500988D02*
X1037114Y1500965D01*
G01X1036801Y1501055D02*
X1036951Y1500988D01*
G01X1036675Y1501162D02*
X1036801Y1501055D01*
G01X1054685Y1499784D02*
G03X1053701Y1498799I0J-984D01*
G01Y1495847D02*
G03X1054685Y1494862I984J-1D01*
G01Y1509784D02*
G03X1053701Y1508799I0J-984D01*
G01Y1505847D02*
G03X1054685Y1504862I984J-1D01*
G01X1037165Y1503248D02*
G03X1036771Y1502854I0J-394D01*
G01Y1501791D02*
G03X1037165Y1501398I394J1D01*
G01X1036771Y1506260D02*
G03X1035787Y1507244I-984J0D01*
G01Y1497402D02*
G03X1036771Y1498386I0J984D01*
G01X1037165Y1493248D02*
G03X1036771Y1492854I0J-394D01*
G01Y1491791D02*
G03X1037165Y1491398I394J1D01*
G01X1036850Y1501138D02*
X1036771Y1501255D01*
G01X1036723Y1491327D02*
X1036850Y1491138D01*
G01X1036678Y1491555D02*
X1036723Y1491327D01*
G01X1037114Y1500965D02*
X1036951Y1500988D01*
G01X1037114Y1490965D02*
X1036951Y1490988D01*
G01X1039921Y1511398D02*
X1079291D01*
G01X1068464Y1509784D02*
X1054685D01*
G01X1036771Y1505276D02*
X1039921D01*
G01X1054685Y1504862D02*
X1068464D01*
G01X1037114Y1503681D02*
X1072855D01*
G01X1079291Y1503248D02*
X1037165D01*
G01X1036678Y1503091D02*
X1036527D01*
G01X1036678Y1501555D02*
X1036527D01*
G01X1037165Y1501398D02*
X1079291D01*
G01X1037114Y1500965D02*
X1072855D01*
G01X1068464Y1499784D02*
X1054685D01*
G01X1039921Y1499370D02*
X1036771D01*
G01X1054685Y1494862D02*
X1068464D01*
G01X1037114Y1493681D02*
X1072855D01*
G01X1079291Y1493248D02*
X1037165D01*
G01X1036678Y1493091D02*
X1036527D01*
G01X1036678Y1491555D02*
X1036527D01*
G01X1037165Y1491398D02*
X1079291D01*
G01X1037114Y1490965D02*
X1072855D01*
G01X1053701Y1498799D02*
Y1495847D01*
G01Y1508799D02*
Y1505847D01*
G01X1040708Y1501398D02*
Y1503248D01*
G01Y1493248D02*
Y1491398D01*
G01X1036771Y1498386D02*
Y1506260D01*
G01Y1491791D02*
Y1492854D01*
G01X1036678Y1493091D02*
Y1491555D01*
G01Y1503091D02*
Y1501555D01*
G01X1036527Y1491555D02*
Y1493091D01*
G01Y1503091D02*
Y1501555D01*
G01X1036264Y1507103D02*
Y1510965D01*
G01Y1507103D02*
Y1497543D01*
G01X1036111Y1501162D02*
Y1493484D01*
G01Y1510965D02*
Y1503484D01*
G01X1035984Y1497441D02*
Y1507204D01*
G01Y1510965D02*
Y1507204D01*
G01X1037114Y1503681D02*
X1036951Y1503658D01*
G01X1037114Y1493681D02*
X1036951Y1493658D01*
G01X1036594Y1503366D02*
X1036678Y1503484D01*
G01X1036771Y1503390D02*
X1036850Y1503508D01*
G01X1036801Y1493591D02*
X1036675Y1493484D01*
G01X1036801Y1503591D02*
X1036675Y1503484D01*
G01X1036951Y1493658D02*
X1036801Y1493591D01*
G01X1036951Y1503658D02*
X1036801Y1503591D01*
G01X1036723Y1523318D02*
X1036678Y1523091D01*
G01X1036771Y1523390D02*
X1036723Y1523318D01*
G01X1036544Y1523234D02*
X1036527Y1523091D01*
G01X1036594Y1523366D02*
X1036544Y1523234D01*
G01X1036678Y1523484D02*
X1036594Y1523366D01*
G01X1037040Y1523636D02*
X1036850Y1523508D01*
G01X1037267Y1523681D02*
X1037040Y1523636D01*
G01Y1521010D02*
X1036850Y1521138D01*
G01X1037267Y1520965D02*
X1037040Y1521010D01*
G01X1036723Y1521327D02*
X1036771Y1521255D01*
G01X1036678Y1521555D02*
X1036723Y1521327D01*
G01X1036594Y1521280D02*
X1036678Y1521162D01*
G01X1036544Y1521411D02*
X1036594Y1521280D01*
G01X1036527Y1521555D02*
X1036544Y1521411D01*
G01X1036594Y1531280D02*
X1036678Y1531162D01*
G01X1036544Y1531411D02*
X1036594Y1531280D01*
G01X1036527Y1531555D02*
X1036544Y1531411D01*
G01X1037040Y1531010D02*
X1036850Y1531138D01*
G01X1037267Y1530965D02*
X1037040Y1531010D01*
G01X1036951Y1520988D02*
X1037114Y1520965D01*
G01X1036801Y1521055D02*
X1036951Y1520988D01*
G01X1036675Y1521162D02*
X1036801Y1521055D01*
G01X1036951Y1530988D02*
X1037114Y1530965D01*
G01X1036801Y1531055D02*
X1036951Y1530988D01*
G01X1036675Y1531162D02*
X1036801Y1531055D01*
G01X1054685Y1519784D02*
G03X1053701Y1518799I0J-984D01*
G01Y1515847D02*
G03X1054685Y1514862I984J-1D01*
G01Y1529784D02*
G03X1053701Y1528799I0J-984D01*
G01Y1525847D02*
G03X1054685Y1524862I984J-1D01*
G01X1036771Y1531791D02*
G03X1037165Y1531398I394J1D01*
G01Y1523248D02*
G03X1036771Y1522854I0J-394D01*
G01Y1521791D02*
G03X1037165Y1521398I394J1D01*
G01X1036771Y1526260D02*
G03X1035787Y1527244I-984J0D01*
G01Y1517402D02*
G03X1036771Y1518386I0J984D01*
G01X1036723Y1531327D02*
X1036850Y1531138D01*
G01Y1521138D02*
X1036771Y1521255D01*
G01X1036678Y1531555D02*
X1036723Y1531327D01*
G01X1037114Y1530965D02*
X1036951Y1530988D01*
G01X1037114Y1520965D02*
X1036951Y1520988D01*
G01X1036678Y1531555D02*
X1036527D01*
G01X1037165Y1531398D02*
X1079291D01*
G01X1037114Y1530965D02*
X1072855D01*
G01X1068464Y1529784D02*
X1054685D01*
G01X1039921Y1525276D02*
X1036771D01*
G01X1054685Y1524862D02*
X1068464D01*
G01X1037114Y1523681D02*
X1072855D01*
G01X1079291Y1523248D02*
X1037165D01*
G01X1036678Y1523091D02*
X1036527D01*
G01X1036678Y1521555D02*
X1036527D01*
G01X1037165Y1521398D02*
X1079291D01*
G01X1037114Y1520965D02*
X1072855D01*
G01X1068464Y1519784D02*
X1054685D01*
G01X1039921Y1519370D02*
X1036771D01*
G01X1054685Y1514862D02*
X1068464D01*
G01X1079291Y1513248D02*
X1039921D01*
G01X1053701Y1518799D02*
Y1515847D01*
G01Y1528799D02*
Y1525847D01*
G01X1040708Y1521398D02*
Y1523248D01*
G01Y1533248D02*
Y1531398D01*
G01X1036771Y1531791D02*
Y1532854D01*
G01Y1518386D02*
Y1526260D01*
G01X1036678Y1523091D02*
Y1521555D01*
G01Y1533091D02*
Y1531555D01*
G01X1036527Y1523091D02*
Y1521555D01*
G01Y1533091D02*
Y1531555D01*
G01X1036264Y1527103D02*
Y1537543D01*
G01Y1517543D02*
Y1513681D01*
G01Y1527103D02*
Y1517543D01*
G01X1036111Y1521162D02*
Y1513681D01*
G01Y1531162D02*
Y1523484D01*
G01X1035984Y1517441D02*
Y1527204D01*
G01Y1537441D02*
Y1527204D01*
G01Y1517441D02*
Y1513681D01*
G01X1037114Y1523681D02*
X1036951Y1523658D01*
G01X1036771Y1523390D02*
X1036850Y1523508D01*
G01X1036801Y1523591D02*
X1036675Y1523484D01*
G01X1036951Y1523658D02*
X1036801Y1523591D01*
G01X1036723Y1543318D02*
X1036678Y1543091D01*
G01X1036771Y1543390D02*
X1036723Y1543318D01*
G01Y1533318D02*
X1036678Y1533091D01*
G01X1036850Y1533508D02*
X1036723Y1533318D01*
G01X1036545Y1543234D02*
X1036527Y1543091D01*
G01X1036595Y1543365D02*
X1036545Y1543234D01*
G01X1036678Y1543484D02*
X1036595Y1543365D01*
G01X1036544Y1543234D02*
X1036527Y1543091D01*
G01X1036594Y1543366D02*
X1036544Y1543234D01*
G01X1036678Y1543484D02*
X1036594Y1543366D01*
G01Y1533366D02*
X1036678Y1533484D01*
G01X1036544Y1533234D02*
X1036594Y1533366D01*
G01X1036527Y1533091D02*
X1036544Y1533234D01*
G01X1036595Y1533365D02*
X1036678Y1533484D01*
G01X1036545Y1533234D02*
X1036595Y1533365D01*
G01X1036527Y1533091D02*
X1036545Y1533234D01*
G01X1037040Y1533636D02*
X1036850Y1533508D01*
G01X1037267Y1533681D02*
X1037040Y1533636D01*
G01Y1543636D02*
X1036850Y1543508D01*
G01X1037267Y1543681D02*
X1037040Y1543636D01*
G01X1036723Y1541327D02*
X1036771Y1541255D01*
G01X1036678Y1541555D02*
X1036723Y1541327D01*
G01X1036594Y1541280D02*
X1036678Y1541162D01*
G01X1036544Y1541411D02*
X1036594Y1541280D01*
G01X1036527Y1541555D02*
X1036544Y1541411D01*
G01X1037040Y1541010D02*
X1036850Y1541138D01*
G01X1037267Y1540965D02*
X1037040Y1541010D01*
G01X1036951Y1540988D02*
X1037114Y1540965D01*
G01X1036801Y1541055D02*
X1036951Y1540988D01*
G01X1036675Y1541162D02*
X1036801Y1541055D01*
G01X1054685Y1549784D02*
G03X1053701Y1548799I0J-984D01*
G01X1054685Y1539784D02*
G03X1053701Y1538799I0J-984D01*
G01Y1535847D02*
G03X1054685Y1534862I984J-1D01*
G01X1053701Y1545847D02*
G03X1054685Y1544862I984J-1D01*
G01X1037165Y1533248D02*
G03X1036771Y1532854I0J-394D01*
G01X1037165Y1543248D02*
G03X1036771Y1542854I0J-394D01*
G01Y1541791D02*
G03X1037165Y1541398I394J1D01*
G01X1036771Y1546260D02*
G03X1035787Y1547244I-984J0D01*
G01Y1537402D02*
G03X1036771Y1538386I0J984D01*
G01X1036850Y1541138D02*
X1036771Y1541255D01*
G01X1037114Y1540965D02*
X1036951Y1540988D01*
G01X1079291Y1553248D02*
X1039921D01*
G01Y1551398D02*
X1079291D01*
G01X1068464Y1549784D02*
X1054685D01*
G01X1036771Y1545276D02*
X1039921D01*
G01X1054685Y1544862D02*
X1068464D01*
G01X1037114Y1543681D02*
X1072855D01*
G01X1079291Y1543248D02*
X1037165D01*
G01X1036678Y1543091D02*
X1036527D01*
G01X1036678Y1541555D02*
X1036527D01*
G01X1037165Y1541398D02*
X1079291D01*
G01X1037114Y1540965D02*
X1072855D01*
G01X1068464Y1539784D02*
X1054685D01*
G01X1039921Y1539370D02*
X1036771D01*
G01X1054685Y1534862D02*
X1068464D01*
G01X1037114Y1533681D02*
X1072855D01*
G01X1079291Y1533248D02*
X1037165D01*
G01X1036678Y1533091D02*
X1036527D01*
G01X1037114Y1543681D02*
X1036951Y1543658D01*
G01X1053701Y1538799D02*
Y1535847D01*
G01Y1548799D02*
Y1545847D01*
G01X1040708Y1541398D02*
Y1543248D01*
G01X1036771Y1538386D02*
Y1546260D01*
G01X1036678Y1543091D02*
Y1541555D01*
G01X1036527Y1543091D02*
Y1541555D01*
G01X1036264Y1547103D02*
Y1550965D01*
G01Y1547103D02*
Y1537543D01*
G01Y1557543D02*
Y1553681D01*
G01X1036111Y1541162D02*
Y1533484D01*
G01Y1550965D02*
Y1543484D01*
G01Y1561162D02*
Y1553681D01*
G01X1035984Y1537441D02*
Y1547204D01*
G01Y1550965D02*
Y1547204D01*
G01Y1557441D02*
Y1553681D01*
G01X1037114Y1533681D02*
X1036951Y1533658D01*
G01X1036771Y1543390D02*
X1036850Y1543508D01*
G01X1036801Y1533591D02*
X1036675Y1533484D01*
G01X1036801Y1543591D02*
X1036675Y1543484D01*
G01X1036951Y1533658D02*
X1036801Y1533591D01*
G01X1036951Y1543658D02*
X1036801Y1543591D01*
G01X1036723Y1573318D02*
X1036678Y1573091D01*
G01X1036850Y1573508D02*
X1036723Y1573318D01*
G01Y1563318D02*
X1036678Y1563091D01*
G01X1036771Y1563390D02*
X1036723Y1563318D01*
G01X1036545Y1573234D02*
X1036527Y1573091D01*
G01X1036595Y1573365D02*
X1036545Y1573234D01*
G01X1036678Y1573484D02*
X1036595Y1573365D01*
G01X1036545Y1563234D02*
X1036527Y1563091D01*
G01X1036595Y1563365D02*
X1036545Y1563234D01*
G01X1036678Y1563484D02*
X1036595Y1563365D01*
G01X1036544Y1573234D02*
X1036527Y1573091D01*
G01X1036594Y1573366D02*
X1036544Y1573234D01*
G01X1036678Y1573484D02*
X1036594Y1573366D01*
G01X1036544Y1563234D02*
X1036527Y1563091D01*
G01X1036594Y1563366D02*
X1036544Y1563234D01*
G01X1036678Y1563484D02*
X1036594Y1563366D01*
G01X1037040Y1563636D02*
X1036850Y1563508D01*
G01X1037267Y1563681D02*
X1037040Y1563636D01*
G01Y1573636D02*
X1036850Y1573508D01*
G01X1037267Y1573681D02*
X1037040Y1573636D01*
G01X1036723Y1561327D02*
X1036771Y1561255D01*
G01X1036678Y1561555D02*
X1036723Y1561327D01*
G01X1036594Y1561280D02*
X1036678Y1561162D01*
G01X1036544Y1561411D02*
X1036594Y1561280D01*
G01X1036527Y1561555D02*
X1036544Y1561411D01*
G01X1037040Y1561010D02*
X1036850Y1561138D01*
G01X1037267Y1560965D02*
X1037040Y1561010D01*
G01Y1571010D02*
X1036850Y1571138D01*
G01X1037267Y1570965D02*
X1037040Y1571010D01*
G01X1036951Y1560988D02*
X1037114Y1560965D01*
G01X1036801Y1561055D02*
X1036951Y1560988D01*
G01X1036675Y1561162D02*
X1036801Y1561055D01*
G01X1036544Y1571411D02*
X1036527Y1571555D01*
G01X1036594Y1571280D02*
X1036544Y1571411D01*
G01X1036678Y1571162D02*
X1036594Y1571280D01*
G01X1036545Y1571412D02*
X1036527Y1571555D01*
G01X1036595Y1571280D02*
X1036545Y1571412D01*
G01X1036678Y1571162D02*
X1036595Y1571280D01*
G01X1036951Y1570988D02*
X1037114Y1570965D01*
G01X1036801Y1571055D02*
X1036951Y1570988D01*
G01X1036675Y1571162D02*
X1036801Y1571055D01*
G01X1054685Y1559784D02*
G03X1053701Y1558799I0J-984D01*
G01Y1555847D02*
G03X1054685Y1554862I984J-1D01*
G01Y1569784D02*
G03X1053701Y1568799I0J-984D01*
G01Y1565847D02*
G03X1054685Y1564862I984J-1D01*
G01X1053701Y1575847D02*
G03X1054685Y1574862I984J-1D01*
G01X1037165Y1563248D02*
G03X1036771Y1562854I0J-394D01*
G01Y1571791D02*
G03X1037165Y1571398I394J1D01*
G01Y1573248D02*
G03X1036771Y1572854I0J-394D01*
G01Y1561791D02*
G03X1037165Y1561398I394J1D01*
G01X1036771Y1566260D02*
G03X1035787Y1567244I-984J0D01*
G01Y1557402D02*
G03X1036771Y1558386I0J984D01*
G01X1036723Y1571327D02*
X1036850Y1571138D01*
G01Y1561138D02*
X1036771Y1561255D01*
G01X1036678Y1571555D02*
X1036723Y1571327D01*
G01X1037114Y1570965D02*
X1036951Y1570988D01*
G01X1037114Y1560965D02*
X1036951Y1560988D01*
G01X1054685Y1574862D02*
X1068464D01*
G01X1037114Y1573681D02*
X1072855D01*
G01X1037165Y1573248D02*
X1079291D01*
G01X1036678Y1573091D02*
X1036527D01*
G01X1036678Y1571555D02*
X1036527D01*
G01X1037165Y1571398D02*
X1079291D01*
G01X1037114Y1570965D02*
X1072855D01*
G01X1068464Y1569784D02*
X1054685D01*
G01X1039921Y1565276D02*
X1036771D01*
G01X1054685Y1564862D02*
X1068464D01*
G01X1037114Y1563681D02*
X1072855D01*
G01X1079291Y1563248D02*
X1037165D01*
G01X1036678Y1563091D02*
X1036527D01*
G01X1036678Y1561555D02*
X1036527D01*
G01X1037165Y1561398D02*
X1079291D01*
G01X1037114Y1560965D02*
X1072855D01*
G01X1068464Y1559784D02*
X1054685D01*
G01X1039921Y1559370D02*
X1036771D01*
G01X1054685Y1554862D02*
X1068464D01*
G01X1037114Y1573681D02*
X1036951Y1573658D01*
G01X1037114Y1563681D02*
X1036951Y1563658D01*
G01X1053701Y1558799D02*
Y1555847D01*
G01Y1568799D02*
Y1565847D01*
G01X1040708Y1571398D02*
Y1573248D01*
G01Y1561398D02*
Y1563248D01*
G01X1036771Y1571791D02*
Y1572854D01*
G01Y1558386D02*
Y1566260D01*
G01X1036678Y1563091D02*
Y1561555D01*
G01Y1573091D02*
Y1571555D01*
G01X1036527Y1563091D02*
Y1561555D01*
G01Y1573091D02*
Y1571555D01*
G01X1036264Y1567103D02*
Y1577543D01*
G01Y1567103D02*
Y1557543D01*
G01X1036111Y1571162D02*
Y1563484D01*
G01Y1581162D02*
Y1573484D01*
G01X1035984Y1557441D02*
Y1567204D01*
G01Y1577441D02*
Y1567204D01*
G01X1036771Y1563390D02*
X1036850Y1563508D01*
G01X1036801Y1563591D02*
X1036675Y1563484D01*
G01X1036801Y1573591D02*
X1036675Y1573484D01*
G01X1036951Y1563658D02*
X1036801Y1563591D01*
G01X1036951Y1573658D02*
X1036801Y1573591D01*
G01X1036544Y1583234D02*
X1036527Y1583091D01*
G01X1036594Y1583366D02*
X1036544Y1583234D01*
G01X1036678Y1583484D02*
X1036594Y1583366D01*
G01X1036723Y1583318D02*
X1036678Y1583091D01*
G01X1036771Y1583390D02*
X1036723Y1583318D01*
G01X1037040Y1583636D02*
X1036850Y1583508D01*
G01X1037267Y1583681D02*
X1037040Y1583636D01*
G01Y1581010D02*
X1036850Y1581138D01*
G01X1037267Y1580965D02*
X1037040Y1581010D01*
G01X1036723Y1581327D02*
X1036771Y1581255D01*
G01X1036678Y1581555D02*
X1036723Y1581327D01*
G01X1036544Y1581411D02*
X1036527Y1581555D01*
G01X1036594Y1581280D02*
X1036544Y1581411D01*
G01X1036678Y1581162D02*
X1036594Y1581280D01*
G01X1036545Y1581412D02*
X1036527Y1581555D01*
G01X1036595Y1581280D02*
X1036545Y1581412D01*
G01X1036678Y1581162D02*
X1036595Y1581280D01*
G01X1036951Y1580988D02*
X1037114Y1580965D01*
G01X1036801Y1581055D02*
X1036951Y1580988D01*
G01X1036675Y1581162D02*
X1036801Y1581055D01*
G01X1054685Y1579784D02*
G03X1053701Y1578799I0J-984D01*
G01X1054685Y1589784D02*
G03X1053701Y1588799I0J-984D01*
G01Y1585847D02*
G03X1054685Y1584862I984J-1D01*
G01X1053701Y1595847D02*
G03X1054685Y1594862I984J-1D01*
G01X1037165Y1583248D02*
G03X1036771Y1582854I0J-394D01*
G01Y1581791D02*
G03X1037165Y1581398I394J1D01*
G01X1036771Y1586260D02*
G03X1035787Y1587244I-984J0D01*
G01Y1577402D02*
G03X1036771Y1578386I0J984D01*
G01Y1581255D02*
X1036850Y1581138D01*
G01X1037114Y1580965D02*
X1036951Y1580988D01*
G01X1054685Y1594862D02*
X1068464D01*
G01X1079291Y1593248D02*
X1039921D01*
G01Y1591398D02*
X1079291D01*
G01X1068464Y1589784D02*
X1054685D01*
G01X1036771Y1585276D02*
X1039921D01*
G01X1054685Y1584862D02*
X1068464D01*
G01X1037114Y1583681D02*
X1072855D01*
G01X1079291Y1583248D02*
X1037165D01*
G01X1036678Y1583091D02*
X1036527D01*
G01X1036678Y1581555D02*
X1036527D01*
G01X1037165Y1581398D02*
X1079291D01*
G01X1037114Y1580965D02*
X1072855D01*
G01X1068464Y1579784D02*
X1054685D01*
G01X1039921Y1579370D02*
X1036771D01*
G01X1037114Y1583681D02*
X1036951Y1583658D01*
G01X1053701Y1578799D02*
Y1575847D01*
G01Y1588799D02*
Y1585847D01*
G01Y1598799D02*
Y1595847D01*
G01X1040708Y1581398D02*
Y1583248D01*
G01X1036771Y1578386D02*
Y1586260D01*
G01X1036678Y1583091D02*
Y1581555D01*
G01X1036527Y1583091D02*
Y1581555D01*
G01X1036264Y1587103D02*
Y1590965D01*
G01Y1587103D02*
Y1577543D01*
G01Y1597543D02*
Y1593681D01*
G01X1036111Y1590965D02*
Y1583484D01*
G01Y1601162D02*
Y1593681D01*
G01X1035984Y1577441D02*
Y1587204D01*
G01Y1590965D02*
Y1587204D01*
G01Y1597441D02*
Y1593681D01*
G01X1036771Y1583390D02*
X1036850Y1583508D01*
G01X1036801Y1583591D02*
X1036675Y1583484D01*
G01X1036951Y1583658D02*
X1036801Y1583591D01*
G01X1036723Y1603318D02*
X1036678Y1603091D01*
G01X1036771Y1603390D02*
X1036723Y1603318D01*
G01X1036544Y1603234D02*
X1036527Y1603091D01*
G01X1036594Y1603366D02*
X1036544Y1603234D01*
G01X1037040Y1603636D02*
X1036850Y1603508D01*
G01X1037267Y1603681D02*
X1037040Y1603636D01*
G01Y1601010D02*
X1036850Y1601138D01*
G01X1037267Y1600965D02*
X1037040Y1601010D01*
G01X1036723Y1601327D02*
X1036771Y1601255D01*
G01X1036678Y1601555D02*
X1036723Y1601327D01*
G01X1036544Y1601411D02*
X1036527Y1601555D01*
G01X1036594Y1601280D02*
X1036544Y1601411D01*
G01X1036678Y1601162D02*
X1036594Y1601280D01*
G01X1036545Y1601412D02*
X1036527Y1601555D01*
G01X1036595Y1601280D02*
X1036545Y1601412D01*
G01X1036678Y1601162D02*
X1036595Y1601280D01*
G01X1036951Y1600988D02*
X1037114Y1600965D01*
G01X1036801Y1601055D02*
X1036951Y1600988D01*
G01X1036675Y1601162D02*
X1036801Y1601055D01*
G01X1054685Y1609784D02*
G03X1053701Y1608799I0J-984D01*
G01Y1605847D02*
G03X1054685Y1604862I984J-1D01*
G01Y1599784D02*
G03X1053701Y1598799I0J-984D01*
G01X1037165Y1603248D02*
G03X1036771Y1602854I0J-394D01*
G01Y1601791D02*
G03X1037165Y1601398I394J1D01*
G01X1036771Y1606260D02*
G03X1035787Y1607244I-984J0D01*
G01Y1597402D02*
G03X1036771Y1598386I0J984D01*
G01X1036850Y1601138D02*
X1036771Y1601255D01*
G01X1037114Y1600965D02*
X1036951Y1600988D01*
G01X1078307Y1611398D02*
X1039921D01*
G01X1068464Y1609784D02*
X1054685D01*
G01X1039921Y1605276D02*
X1036771D01*
G01X1054685Y1604862D02*
X1068464D01*
G01X1037114Y1603681D02*
X1072855D01*
G01X1079291Y1603248D02*
X1037165D01*
G01X1036678Y1603091D02*
X1036527D01*
G01X1036678Y1601555D02*
X1036527D01*
G01X1037165Y1601398D02*
X1079291D01*
G01X1037114Y1600965D02*
X1072855D01*
G01X1068464Y1599784D02*
X1054685D01*
G01X1039921Y1599370D02*
X1036771D01*
G01X1037114Y1603681D02*
X1036951Y1603658D01*
G01X1053701Y1608799D02*
Y1605847D01*
G01X1040708Y1601398D02*
Y1603248D01*
G01X1036771Y1598386D02*
Y1606260D01*
G01X1036678Y1601555D02*
Y1603091D01*
G01X1036527D02*
Y1601555D01*
G01X1036264Y1607103D02*
Y1610965D01*
G01Y1607103D02*
Y1597543D01*
G01X1036111Y1610965D02*
Y1603484D01*
G01X1035984Y1597441D02*
Y1607204D01*
G01Y1610965D02*
Y1607204D01*
G01X1036771Y1603390D02*
X1036850Y1603508D01*
G01X1036594Y1603366D02*
X1036678Y1603484D01*
G01X1036801Y1603591D02*
X1036675Y1603484D01*
G01X1036951Y1603658D02*
X1036801Y1603591D01*
G01X1041201Y1626910D02*
G03X1041497Y1626831I295J511D01*
G01X1041201Y1631910D02*
G03X1041497Y1631831I295J511D01*
G01Y1630374D02*
G03X1041201Y1630295I-1J-590D01*
G01Y1636910D02*
G03X1041497Y1636831I295J511D01*
G01Y1635374D02*
G03X1041201Y1635295I-1J-590D01*
G01X1040146Y1632519D02*
G03X1039851Y1632599I-297J-510D01*
G01Y1629606D02*
G03X1040146Y1629686I-2J591D01*
G01Y1637519D02*
G03X1039851Y1637599I-297J-510D01*
G01Y1634606D02*
G03X1040146Y1634686I-2J591D01*
G01Y1622519D02*
G03X1039851Y1622599I-297J-510D01*
G01X1041201Y1621910D02*
G03X1041497Y1621831I295J511D01*
G01Y1620374D02*
G03X1041201Y1620295I-1J-590D01*
G01X1039851Y1619606D02*
G03X1040146Y1619686I-2J591D01*
G01Y1627519D02*
G03X1039851Y1627599I-297J-510D01*
G01X1041497Y1625374D02*
G03X1041201Y1625295I-1J-590D01*
G01X1039851Y1624606D02*
G03X1040146Y1624686I-2J591D01*
G01X1035236Y1631890D02*
G03X1035827Y1632480I0J591D01*
G01Y1629725D02*
G03X1035236Y1630315I-591J-1D01*
G01Y1636890D02*
G03X1035827Y1637480I0J591D01*
G01Y1634725D02*
G03X1035236Y1635315I-591J-1D01*
G01X1034508Y1631969D02*
G03X1034804Y1631890I295J512D01*
G01Y1630315D02*
G03X1034508Y1630236I-1J-590D01*
G01Y1636969D02*
G03X1034804Y1636890I295J512D01*
G01Y1635315D02*
G03X1034508Y1635236I-1J-590D01*
G01Y1621969D02*
G03X1034804Y1621890I295J512D01*
G01X1035236D02*
G03X1035827Y1622480I0J591D01*
G01Y1619725D02*
G03X1035236Y1620315I-591J-1D01*
G01X1034804D02*
G03X1034508Y1620236I-1J-590D01*
G01Y1626969D02*
G03X1034804Y1626890I295J512D01*
G01X1035236D02*
G03X1035827Y1627480I0J591D01*
G01Y1624725D02*
G03X1035236Y1625315I-591J-1D01*
G01X1034804D02*
G03X1034508Y1625236I-1J-590D01*
G01X1040146Y1637519D02*
X1041201Y1636910D01*
G01X1040146Y1632519D02*
X1041201Y1631910D01*
G01X1040146Y1627519D02*
X1041201Y1626910D01*
G01X1040146Y1622519D02*
X1041201Y1621910D01*
G01X1035827Y1637599D02*
X1039851D01*
G01X1034804Y1636890D02*
X1035236D01*
G01X1041497Y1636831D02*
X1075994D01*
G01X1041497Y1635374D02*
X1075994D01*
G01X1035236Y1635315D02*
X1034804D01*
G01X1039851Y1634606D02*
X1035827D01*
G01Y1632599D02*
X1039851D01*
G01X1034804Y1631890D02*
X1035236D01*
G01X1041497Y1631831D02*
X1075994D01*
G01X1041497Y1630374D02*
X1075994D01*
G01X1035236Y1630315D02*
X1034804D01*
G01X1039851Y1629606D02*
X1035827D01*
G01Y1627599D02*
X1039851D01*
G01X1034804Y1626890D02*
X1035236D01*
G01X1041497Y1626831D02*
X1075994D01*
G01X1041497Y1625374D02*
X1075994D01*
G01X1035236Y1625315D02*
X1034804D01*
G01X1039851Y1624606D02*
X1035827D01*
G01Y1622599D02*
X1039851D01*
G01X1034804Y1621890D02*
X1035236D01*
G01X1041497Y1621831D02*
X1075994D01*
G01X1041497Y1620374D02*
X1075994D01*
G01X1035236Y1620315D02*
X1034804D01*
G01X1039851Y1619606D02*
X1035827D01*
G01X1054641Y1621831D02*
Y1620374D01*
G01Y1626831D02*
Y1625374D01*
G01Y1631831D02*
Y1630374D01*
G01Y1636831D02*
Y1635374D01*
G01X1054079Y1621831D02*
Y1620374D01*
G01Y1626831D02*
Y1625374D01*
G01Y1631831D02*
Y1630374D01*
G01Y1636831D02*
Y1635374D01*
G01X1050000Y1622087D02*
Y1620118D01*
G01Y1627087D02*
Y1625118D01*
G01Y1632087D02*
Y1630118D01*
G01Y1637087D02*
Y1635118D01*
G01X1048031Y1634528D02*
Y1637677D01*
G01Y1624528D02*
Y1627677D01*
G01Y1619528D02*
Y1622677D01*
G01Y1632677D02*
Y1629528D01*
G01X1044767Y1621831D02*
Y1620374D01*
G01Y1626831D02*
Y1625374D01*
G01Y1631831D02*
Y1630374D01*
G01Y1636831D02*
Y1635374D01*
G01X1044205Y1621831D02*
Y1620374D01*
G01Y1626831D02*
Y1625374D01*
G01Y1631831D02*
Y1630374D01*
G01Y1636831D02*
Y1635374D01*
G01X1043267Y1621831D02*
Y1620374D01*
G01Y1626831D02*
Y1625374D01*
G01Y1631831D02*
Y1630374D01*
G01Y1636831D02*
Y1635374D01*
G01X1035827Y1637480D02*
Y1637599D01*
G01Y1634606D02*
Y1634725D01*
G01Y1632480D02*
Y1632599D01*
G01Y1629606D02*
Y1629725D01*
G01Y1627480D02*
Y1627599D01*
G01Y1622480D02*
Y1622599D01*
G01Y1624606D02*
Y1624725D01*
G01Y1619606D02*
Y1619725D01*
G01X1041201Y1620295D02*
X1040146Y1619686D01*
G01X1041201Y1625295D02*
X1040146Y1624686D01*
G01X1041201Y1630295D02*
X1040146Y1629686D01*
G01X1041201Y1635295D02*
X1040146Y1634686D01*
G01X1041201Y1656910D02*
G03X1041497Y1656831I295J511D01*
G01Y1655374D02*
G03X1041201Y1655295I-1J-590D01*
G01X1040146Y1657519D02*
G03X1039851Y1657599I-297J-510D01*
G01Y1654606D02*
G03X1040146Y1654686I-2J591D01*
G01X1041201Y1641910D02*
G03X1041497Y1641831I295J511D01*
G01X1041201Y1646910D02*
G03X1041497Y1646831I295J511D01*
G01Y1645374D02*
G03X1041201Y1645295I-1J-590D01*
G01Y1651910D02*
G03X1041497Y1651831I295J511D01*
G01Y1650374D02*
G03X1041201Y1650295I-1J-590D01*
G01X1041497Y1640374D02*
G03X1041201Y1640295I-1J-590D01*
G01X1040146Y1642519D02*
G03X1039851Y1642599I-297J-510D01*
G01Y1639606D02*
G03X1040146Y1639686I-2J591D01*
G01Y1647519D02*
G03X1039851Y1647599I-297J-510D01*
G01Y1644606D02*
G03X1040146Y1644686I-2J591D01*
G01Y1652519D02*
G03X1039851Y1652599I-297J-510D01*
G01Y1649606D02*
G03X1040146Y1649686I-2J591D01*
G01X1035236Y1656890D02*
G03X1035827Y1657480I0J591D01*
G01Y1654725D02*
G03X1035236Y1655315I-591J-1D01*
G01X1034508Y1656969D02*
G03X1034804Y1656890I295J512D01*
G01Y1655315D02*
G03X1034508Y1655236I-1J-590D01*
G01X1035236Y1641890D02*
G03X1035827Y1642480I0J591D01*
G01X1035236Y1646890D02*
G03X1035827Y1647480I0J591D01*
G01Y1644725D02*
G03X1035236Y1645315I-591J-1D01*
G01Y1651890D02*
G03X1035827Y1652480I0J591D01*
G01Y1649725D02*
G03X1035236Y1650315I-591J-1D01*
G01X1035827Y1639725D02*
G03X1035236Y1640315I-591J-1D01*
G01X1034508Y1641969D02*
G03X1034804Y1641890I295J512D01*
G01X1034508Y1646969D02*
G03X1034804Y1646890I295J512D01*
G01Y1645315D02*
G03X1034508Y1645236I-1J-590D01*
G01Y1651969D02*
G03X1034804Y1651890I295J512D01*
G01Y1650315D02*
G03X1034508Y1650236I-1J-590D01*
G01X1034804Y1640315D02*
G03X1034508Y1640236I-1J-590D01*
G01X1040146Y1657519D02*
X1041201Y1656910D01*
G01X1040146Y1652519D02*
X1041201Y1651910D01*
G01X1040146Y1647519D02*
X1041201Y1646910D01*
G01X1040146Y1642519D02*
X1041201Y1641910D01*
G01X1035827Y1657599D02*
X1039851D01*
G01X1034804Y1656890D02*
X1035236D01*
G01X1041497Y1656831D02*
X1075994D01*
G01X1041497Y1655374D02*
X1075994D01*
G01X1035236Y1655315D02*
X1034804D01*
G01X1039851Y1654606D02*
X1035827D01*
G01Y1652599D02*
X1039851D01*
G01X1034804Y1651890D02*
X1035236D01*
G01X1041497Y1651831D02*
X1075994D01*
G01X1041497Y1650374D02*
X1075994D01*
G01X1035236Y1650315D02*
X1034804D01*
G01X1039851Y1649606D02*
X1035827D01*
G01Y1647599D02*
X1039851D01*
G01X1034804Y1646890D02*
X1035236D01*
G01X1041497Y1646831D02*
X1075994D01*
G01X1041497Y1645374D02*
X1075994D01*
G01X1035236Y1645315D02*
X1034804D01*
G01X1039851Y1644606D02*
X1035827D01*
G01Y1642599D02*
X1039851D01*
G01X1034804Y1641890D02*
X1035236D01*
G01X1041497Y1641831D02*
X1075994D01*
G01X1041497Y1640374D02*
X1075994D01*
G01X1035236Y1640315D02*
X1034804D01*
G01X1039851Y1639606D02*
X1035827D01*
G01X1054641Y1641831D02*
Y1640374D01*
G01Y1646831D02*
Y1645374D01*
G01Y1651831D02*
Y1650374D01*
G01Y1656831D02*
Y1655374D01*
G01X1054079Y1641831D02*
Y1640374D01*
G01Y1646831D02*
Y1645374D01*
G01Y1651831D02*
Y1650374D01*
G01Y1656831D02*
Y1655374D01*
G01X1050000Y1642087D02*
Y1640118D01*
G01Y1647087D02*
Y1645118D01*
G01Y1652087D02*
Y1650118D01*
G01Y1657087D02*
Y1655118D01*
G01X1048031Y1659528D02*
Y1662677D01*
G01Y1654528D02*
Y1657677D01*
G01Y1649528D02*
Y1652677D01*
G01Y1644528D02*
Y1647677D01*
G01Y1639528D02*
Y1642677D01*
G01X1044767Y1641831D02*
Y1640374D01*
G01Y1646831D02*
Y1645374D01*
G01Y1651831D02*
Y1650374D01*
G01Y1656831D02*
Y1655374D01*
G01X1044205Y1641831D02*
Y1640374D01*
G01Y1646831D02*
Y1645374D01*
G01Y1651831D02*
Y1650374D01*
G01Y1656831D02*
Y1655374D01*
G01X1043267Y1641831D02*
Y1640374D01*
G01Y1646831D02*
Y1645374D01*
G01Y1651831D02*
Y1650374D01*
G01Y1656831D02*
Y1655374D01*
G01X1035827Y1657480D02*
Y1657599D01*
G01Y1654606D02*
Y1654725D01*
G01Y1652480D02*
Y1652599D01*
G01Y1649606D02*
Y1649725D01*
G01Y1647480D02*
Y1647599D01*
G01Y1644606D02*
Y1644725D01*
G01Y1642480D02*
Y1642599D01*
G01Y1639606D02*
Y1639725D01*
G01X1041201Y1640295D02*
X1040146Y1639686D01*
G01X1041201Y1645295D02*
X1040146Y1644686D01*
G01X1041201Y1650295D02*
X1040146Y1649686D01*
G01X1041201Y1655295D02*
X1040146Y1654686D01*
G01X1041201Y1676910D02*
G03X1041497Y1676831I295J511D01*
G01Y1675374D02*
G03X1041201Y1675295I-1J-590D01*
G01Y1666910D02*
G03X1041497Y1666831I295J511D01*
G01X1041201Y1671910D02*
G03X1041497Y1671831I295J511D01*
G01Y1670374D02*
G03X1041201Y1670295I-1J-590D01*
G01Y1661910D02*
G03X1041497Y1661831I295J511D01*
G01Y1660374D02*
G03X1041201Y1660295I-1J-590D01*
G01X1041497Y1665374D02*
G03X1041201Y1665295I-1J-590D01*
G01X1040146Y1677519D02*
G03X1039851Y1677599I-297J-510D01*
G01Y1674606D02*
G03X1040146Y1674686I-2J591D01*
G01Y1667519D02*
G03X1039851Y1667599I-297J-510D01*
G01X1040146Y1672519D02*
G03X1039851Y1672599I-297J-510D01*
G01Y1669606D02*
G03X1040146Y1669686I-2J591D01*
G01Y1662519D02*
G03X1039851Y1662599I-297J-510D01*
G01Y1659606D02*
G03X1040146Y1659686I-2J591D01*
G01X1039851Y1664606D02*
G03X1040146Y1664686I-2J591D01*
G01X1035236Y1676890D02*
G03X1035827Y1677480I0J591D01*
G01Y1674725D02*
G03X1035236Y1675315I-591J-1D01*
G01Y1666890D02*
G03X1035827Y1667480I0J591D01*
G01X1035236Y1671890D02*
G03X1035827Y1672480I0J591D01*
G01Y1669725D02*
G03X1035236Y1670315I-591J-1D01*
G01Y1661890D02*
G03X1035827Y1662480I0J591D01*
G01Y1659725D02*
G03X1035236Y1660315I-591J-1D01*
G01X1035827Y1664725D02*
G03X1035236Y1665315I-591J-1D01*
G01X1034508Y1676969D02*
G03X1034804Y1676890I295J512D01*
G01Y1675315D02*
G03X1034508Y1675236I-1J-590D01*
G01Y1666969D02*
G03X1034804Y1666890I295J512D01*
G01X1034508Y1671969D02*
G03X1034804Y1671890I295J512D01*
G01Y1670315D02*
G03X1034508Y1670236I-1J-590D01*
G01Y1661969D02*
G03X1034804Y1661890I295J512D01*
G01Y1660315D02*
G03X1034508Y1660236I-1J-590D01*
G01X1034804Y1665315D02*
G03X1034508Y1665236I-1J-590D01*
G01X1040146Y1677519D02*
X1041201Y1676910D01*
G01X1040146Y1672519D02*
X1041201Y1671910D01*
G01X1040146Y1667519D02*
X1041201Y1666910D01*
G01X1040146Y1662519D02*
X1041201Y1661910D01*
G01X1035827Y1677599D02*
X1039851D01*
G01X1034804Y1676890D02*
X1035236D01*
G01X1041497Y1676831D02*
X1075994D01*
G01X1041497Y1675374D02*
X1075994D01*
G01X1035236Y1675315D02*
X1034804D01*
G01X1039851Y1674606D02*
X1035827D01*
G01Y1672599D02*
X1039851D01*
G01X1034804Y1671890D02*
X1035236D01*
G01X1041497Y1671831D02*
X1075994D01*
G01X1041497Y1670374D02*
X1075994D01*
G01X1035236Y1670315D02*
X1034804D01*
G01X1039851Y1669606D02*
X1035827D01*
G01Y1667599D02*
X1039851D01*
G01X1034804Y1666890D02*
X1035236D01*
G01X1041497Y1666831D02*
X1075994D01*
G01X1041497Y1665374D02*
X1075994D01*
G01X1035236Y1665315D02*
X1034804D01*
G01X1039851Y1664606D02*
X1035827D01*
G01Y1662599D02*
X1039851D01*
G01X1034804Y1661890D02*
X1035236D01*
G01X1041497Y1661831D02*
X1075994D01*
G01X1041497Y1660374D02*
X1075994D01*
G01X1035236Y1660315D02*
X1034804D01*
G01X1039851Y1659606D02*
X1035827D01*
G01X1054641Y1661831D02*
Y1660374D01*
G01Y1666831D02*
Y1665374D01*
G01Y1671831D02*
Y1670374D01*
G01Y1676831D02*
Y1675374D01*
G01X1054079Y1661831D02*
Y1660374D01*
G01Y1666831D02*
Y1665374D01*
G01Y1671831D02*
Y1670374D01*
G01Y1676831D02*
Y1675374D01*
G01X1050000Y1662087D02*
Y1660118D01*
G01Y1667087D02*
Y1665118D01*
G01Y1672087D02*
Y1670118D01*
G01Y1677087D02*
Y1675118D01*
G01X1048031Y1674528D02*
Y1677677D01*
G01Y1669528D02*
Y1672677D01*
G01Y1664528D02*
Y1667677D01*
G01X1044767Y1661831D02*
Y1660374D01*
G01Y1666831D02*
Y1665374D01*
G01Y1671831D02*
Y1670374D01*
G01Y1676831D02*
Y1675374D01*
G01X1044205Y1661831D02*
Y1660374D01*
G01Y1666831D02*
Y1665374D01*
G01Y1671831D02*
Y1670374D01*
G01Y1676831D02*
Y1675374D01*
G01X1043267Y1661831D02*
Y1660374D01*
G01Y1666831D02*
Y1665374D01*
G01Y1671831D02*
Y1670374D01*
G01Y1676831D02*
Y1675374D01*
G01X1035827Y1677480D02*
Y1677599D01*
G01Y1674606D02*
Y1674725D01*
G01Y1672480D02*
Y1672599D01*
G01Y1669606D02*
Y1669725D01*
G01Y1667480D02*
Y1667599D01*
G01Y1664606D02*
Y1664725D01*
G01Y1662480D02*
Y1662599D01*
G01Y1659606D02*
Y1659725D01*
G01X1034016Y1679449D02*
Y1707008D01*
G01X1041201Y1660295D02*
X1040146Y1659686D01*
G01X1041201Y1665295D02*
X1040146Y1664686D01*
G01X1041201Y1670295D02*
X1040146Y1669686D01*
G01X1041201Y1675295D02*
X1040146Y1674686D01*
G01X1034016Y1693307D02*
X1079291D01*
G01Y1691339D02*
X1034016D01*
G01X1074567Y1685433D02*
X1039921D01*
G01X1041338Y1733129D02*
Y1716536D01*
G01X1065043D02*
X1041338D01*
G01Y1739719D02*
Y1731536D01*
G01Y1959242D02*
Y1763310D01*
G01Y1987740D02*
Y2061827D01*
G01Y1992126D02*
X1097205D01*
G01X1041338Y1982862D02*
Y1992126D01*
G01X1042397Y2066114D02*
X1041598Y2066713D01*
X1041199Y2067412D01*
X1041066Y2068210D01*
X1041332Y2069208D01*
X1041998Y2069907D01*
X1042796Y2070107D01*
X1043595Y2070007D01*
X1044260Y2069607D01*
X1045591Y2067611D01*
X1046522Y2066713D01*
X1047854Y2066114D01*
X1049051Y2065914D01*
Y2070107D01*
G01Y2075995D02*
X1048918Y2076694D01*
X1048519Y2077493D01*
X1047854Y2077992D01*
X1046922Y2078191D01*
X1045990Y2077992D01*
X1045192Y2077393D01*
X1044792Y2076495D01*
Y2075496D01*
X1044526Y2074897D01*
X1043861Y2074398D01*
X1042929Y2074199D01*
X1041998Y2074498D01*
X1041332Y2075197D01*
X1041066Y2075995D01*
X1041332Y2076794D01*
X1041998Y2077493D01*
X1042929Y2077792D01*
X1043861Y2077592D01*
X1044526Y2077094D01*
X1044792Y2076495D01*
Y2075496D01*
X1045192Y2074598D01*
X1045990Y2073999D01*
X1046922Y2073800D01*
X1047854Y2073999D01*
X1048519Y2074498D01*
X1048918Y2075297D01*
X1049051Y2075995D01*
G01Y2085178D02*
X1041066D01*
X1046789Y2081485D01*
Y2086476D01*
G01X1049317Y2091965D02*
X1049184Y2091766D01*
X1048918D01*
X1048785Y2091965D01*
X1048918Y2092165D01*
X1049184D01*
X1049317Y2091965D01*
G01X1047854Y2097755D02*
X1048519Y2098353D01*
X1048918Y2099052D01*
X1049051Y2099950D01*
X1048785Y2100849D01*
X1048253Y2101547D01*
X1047321Y2102047D01*
X1046256Y2102146D01*
X1045192Y2101947D01*
X1044526Y2101448D01*
X1043994Y2100749D01*
X1043861Y2100050D01*
X1043994Y2099352D01*
X1044526Y2098453D01*
X1041066Y2098753D01*
Y2101448D01*
G01Y2107935D02*
X1041332Y2107137D01*
X1041998Y2106538D01*
X1042796Y2106139D01*
X1043861Y2105839D01*
X1045059Y2105740D01*
X1046256Y2105839D01*
X1047321Y2106139D01*
X1048120Y2106538D01*
X1048785Y2107137D01*
X1049051Y2107935D01*
X1048785Y2108734D01*
X1048120Y2109333D01*
X1047321Y2109732D01*
X1046256Y2110032D01*
X1045059Y2110131D01*
X1043861Y2110032D01*
X1042796Y2109732D01*
X1041998Y2109333D01*
X1041332Y2108734D01*
X1041066Y2107935D01*
G01X1045114Y2063244D02*
Y2064661D01*
G01X1041338Y2061827D02*
X1045114Y2063244D01*
G01X1076784Y21507D02*
G03I-4291J0D01*
G01X1065242Y42048D02*
X1081242D01*
G01X1065242Y58048D02*
Y42048D01*
G01X1070742Y47548D02*
X1075742D01*
G01X1070742D02*
Y52548D01*
G01X1075742D02*
Y47548D01*
G01X1073242Y52548D02*
Y47548D01*
G01X1070742Y50048D02*
X1075742D01*
G01X1065242Y58048D02*
X1081242D01*
G01X1075742Y52548D02*
X1070742D01*
G01X1073211Y1440888D02*
X1072855Y1440965D01*
G01X1073508Y1440676D02*
X1073211Y1440888D01*
G01X1073708Y1440360D02*
X1073779Y1439980D01*
G01X1073508Y1440676D02*
X1073708Y1440360D01*
G01X1069449Y1438799D02*
G03X1068464Y1439784I-985J0D01*
G01Y1434862D02*
G03X1069449Y1435847I0J985D01*
G01X1068464Y1444862D02*
G03X1069449Y1445847I0J985D01*
G01X1079291Y1424488D02*
X1074567Y1429213D01*
G01X1075945Y1427835D02*
Y1433248D01*
G01X1073779Y1439980D02*
Y1434666D01*
G01Y1449980D02*
Y1444666D01*
G01X1073375Y1434666D02*
Y1439980D01*
G01Y1449980D02*
Y1444666D01*
G01X1071417Y1686221D02*
Y1428425D01*
G01X1069922Y1433681D02*
Y1440965D01*
G01Y1450965D02*
Y1443681D01*
G01X1069449Y1445847D02*
Y1448799D01*
G01Y1435847D02*
Y1438799D01*
G01X1068464Y1434862D02*
Y1433248D01*
G01Y1441398D02*
Y1439784D01*
G01Y1444862D02*
Y1443248D01*
G01X1067921Y1440965D02*
Y1433681D01*
G01Y1450965D02*
Y1443681D01*
G01X1067480Y1434862D02*
Y1433248D01*
G01Y1441398D02*
Y1439784D01*
G01Y1444862D02*
Y1443248D01*
G01X1067113Y1439784D02*
Y1440965D01*
G01Y1434862D02*
Y1433681D01*
G01Y1439784D02*
Y1434862D01*
G01Y1444862D02*
Y1443681D01*
G01Y1449784D02*
Y1444862D01*
G01X1066473D02*
Y1449784D01*
G01Y1434862D02*
Y1439784D01*
G01Y1434862D02*
Y1433681D01*
G01Y1440965D02*
Y1439784D01*
G01Y1444862D02*
Y1443681D01*
G01X1066320Y1440965D02*
Y1433681D01*
G01Y1450965D02*
Y1443681D01*
G01X1073779Y1444666D02*
X1073375D01*
G01X1073779Y1439980D02*
X1073375D01*
G01X1073779Y1434666D02*
X1073375D01*
G01X1071417Y1428425D02*
X1079291D01*
G01X1073779Y1434666D02*
X1073708Y1434286D01*
G01X1073779Y1444666D02*
X1073708Y1444286D01*
G01X1073211Y1443757D02*
X1072855Y1443681D01*
G01X1073211Y1433757D02*
X1072855Y1433681D01*
G01X1073708Y1434286D02*
X1073508Y1433969D01*
G01X1073708Y1444286D02*
X1073508Y1443969D01*
G01Y1433969D02*
X1073211Y1433757D01*
G01X1073508Y1443969D02*
X1073211Y1443757D01*
G01Y1450888D02*
X1072855Y1450965D01*
G01X1073508Y1450676D02*
X1073211Y1450888D01*
G01Y1460888D02*
X1072855Y1460965D01*
G01X1073508Y1460676D02*
X1073211Y1460888D01*
G01X1073708Y1450360D02*
X1073779Y1449980D01*
G01X1073508Y1450676D02*
X1073708Y1450360D01*
G01Y1460360D02*
X1073779Y1459980D01*
G01X1073508Y1460676D02*
X1073708Y1460360D01*
G01X1069449Y1448799D02*
G03X1068464Y1449784I-985J0D01*
G01X1069449Y1458799D02*
G03X1068464Y1459784I-985J0D01*
G01Y1454862D02*
G03X1069449Y1455847I0J985D01*
G01Y1468799D02*
G03X1068464Y1469784I-985J0D01*
G01Y1464862D02*
G03X1069449Y1465847I0J985D01*
G01X1073779Y1454666D02*
Y1459980D01*
G01Y1469980D02*
Y1464666D01*
G01X1073375Y1454666D02*
Y1459980D01*
G01Y1469980D02*
Y1464666D01*
G01X1069922Y1453681D02*
Y1460965D01*
G01Y1470965D02*
Y1463681D01*
G01X1069449Y1465847D02*
Y1468799D01*
G01Y1455847D02*
Y1458799D01*
G01X1068464Y1463248D02*
Y1464862D01*
G01Y1451398D02*
Y1449784D01*
G01Y1454862D02*
Y1453248D01*
G01Y1461398D02*
Y1459784D01*
G01X1067921Y1460965D02*
Y1453681D01*
G01Y1470965D02*
Y1463681D01*
G01X1067480Y1451398D02*
Y1449784D01*
G01Y1454862D02*
Y1453248D01*
G01Y1461398D02*
Y1459784D01*
G01Y1464862D02*
Y1463248D01*
G01X1067113Y1459784D02*
Y1460965D01*
G01Y1449784D02*
Y1450965D01*
G01Y1454862D02*
Y1453681D01*
G01Y1459784D02*
Y1454862D01*
G01Y1464862D02*
Y1463681D01*
G01Y1469784D02*
Y1464862D01*
G01X1066473D02*
Y1469784D01*
G01Y1454862D02*
Y1459784D01*
G01Y1450965D02*
Y1449784D01*
G01Y1454862D02*
Y1453681D01*
G01Y1460965D02*
Y1459784D01*
G01Y1464862D02*
Y1463681D01*
G01X1066320Y1460965D02*
Y1453681D01*
G01Y1470965D02*
Y1463681D01*
G01X1073779Y1464666D02*
X1073375D01*
G01X1073779Y1459980D02*
X1073375D01*
G01X1073779Y1454666D02*
X1073375D01*
G01X1073779Y1449980D02*
X1073375D01*
G01X1073779Y1454666D02*
X1073708Y1454286D01*
G01X1073779Y1464666D02*
X1073708Y1464286D01*
G01X1073211Y1463757D02*
X1072855Y1463681D01*
G01X1073211Y1453757D02*
X1072855Y1453681D01*
G01X1073708Y1454286D02*
X1073508Y1453969D01*
G01X1073708Y1464286D02*
X1073508Y1463969D01*
G01Y1453969D02*
X1073211Y1453757D01*
G01X1073508Y1463969D02*
X1073211Y1463757D01*
G01Y1470888D02*
X1072855Y1470965D01*
G01X1073508Y1470676D02*
X1073211Y1470888D01*
G01Y1480888D02*
X1072855Y1480965D01*
G01X1073508Y1480676D02*
X1073211Y1480888D01*
G01X1073708Y1470360D02*
X1073779Y1469980D01*
G01X1073508Y1470676D02*
X1073708Y1470360D01*
G01Y1480360D02*
X1073779Y1479980D01*
G01X1073508Y1480676D02*
X1073708Y1480360D01*
G01Y1490360D02*
X1073779Y1489980D01*
G01X1073508Y1490676D02*
X1073708Y1490360D01*
G01X1069449Y1478799D02*
G03X1068464Y1479784I-985J0D01*
G01Y1474862D02*
G03X1069449Y1475847I0J985D01*
G01Y1488799D02*
G03X1068464Y1489784I-985J0D01*
G01Y1484862D02*
G03X1069449Y1485847I0J985D01*
G01X1075945Y1473248D02*
Y1471398D01*
G01X1073779Y1479980D02*
Y1474666D01*
G01Y1489980D02*
Y1484666D01*
G01X1073375Y1474666D02*
Y1479980D01*
G01Y1489980D02*
Y1484666D01*
G01X1069922Y1473681D02*
Y1480965D01*
G01Y1490965D02*
Y1483681D01*
G01X1069449Y1485847D02*
Y1488799D01*
G01Y1475847D02*
Y1478799D01*
G01X1068464Y1471398D02*
Y1469784D01*
G01Y1474862D02*
Y1473248D01*
G01Y1484862D02*
Y1483248D01*
G01Y1481398D02*
Y1479784D01*
G01Y1491398D02*
Y1489784D01*
G01X1067921Y1480965D02*
Y1473681D01*
G01Y1490965D02*
Y1483681D01*
G01X1067480Y1471398D02*
Y1469784D01*
G01Y1474862D02*
Y1473248D01*
G01Y1484862D02*
Y1483248D01*
G01Y1481398D02*
Y1479784D01*
G01Y1491398D02*
Y1489784D01*
G01X1067113D02*
Y1490965D01*
G01Y1479784D02*
Y1480965D01*
G01Y1469784D02*
Y1470965D01*
G01Y1474862D02*
Y1473681D01*
G01Y1479784D02*
Y1474862D01*
G01Y1484862D02*
Y1483681D01*
G01Y1489784D02*
Y1484862D01*
G01X1066473D02*
Y1489784D01*
G01Y1474862D02*
Y1479784D01*
G01Y1470965D02*
Y1469784D01*
G01Y1474862D02*
Y1473681D01*
G01Y1480965D02*
Y1479784D01*
G01Y1484862D02*
Y1483681D01*
G01Y1490965D02*
Y1489784D01*
G01X1066320Y1480965D02*
Y1473681D01*
G01Y1490965D02*
Y1483681D01*
G01X1073779Y1489980D02*
X1073375D01*
G01X1073779Y1484666D02*
X1073375D01*
G01X1073779Y1479980D02*
X1073375D01*
G01X1073779Y1474666D02*
X1073375D01*
G01X1073779Y1469980D02*
X1073375D01*
G01X1073779Y1474666D02*
X1073708Y1474286D01*
G01X1073779Y1484666D02*
X1073708Y1484286D01*
G01X1073211Y1483757D02*
X1072855Y1483681D01*
G01X1073211Y1473757D02*
X1072855Y1473681D01*
G01X1073708Y1474286D02*
X1073508Y1473969D01*
G01X1073708Y1484286D02*
X1073508Y1483969D01*
G01Y1473969D02*
X1073211Y1473757D01*
G01X1073508Y1483969D02*
X1073211Y1483757D01*
G01Y1490888D02*
X1072855Y1490965D01*
G01X1073508Y1490676D02*
X1073211Y1490888D01*
G01Y1500888D02*
X1072855Y1500965D01*
G01X1073508Y1500676D02*
X1073211Y1500888D01*
G01Y1510888D02*
X1072855Y1510965D01*
G01X1073508Y1510676D02*
X1073211Y1510888D01*
G01X1073708Y1500360D02*
X1073779Y1499980D01*
G01X1073508Y1500676D02*
X1073708Y1500360D01*
G01Y1510360D02*
X1073779Y1509980D01*
G01X1073508Y1510676D02*
X1073708Y1510360D01*
G01X1069449Y1498799D02*
G03X1068464Y1499784I-985J0D01*
G01Y1494862D02*
G03X1069449Y1495847I0J985D01*
G01Y1508799D02*
G03X1068464Y1509784I-985J0D01*
G01Y1504862D02*
G03X1069449Y1505847I0J985D01*
G01X1075945Y1513248D02*
Y1511398D01*
G01X1073779Y1494666D02*
Y1499980D01*
G01Y1509980D02*
Y1504666D01*
G01X1073375Y1494666D02*
Y1499980D01*
G01Y1509980D02*
Y1504666D01*
G01X1069922Y1493681D02*
Y1500965D01*
G01Y1510965D02*
Y1503681D01*
G01X1069449Y1505847D02*
Y1508799D01*
G01Y1495847D02*
Y1498799D01*
G01X1068464Y1503248D02*
Y1504862D01*
G01Y1494862D02*
Y1493248D01*
G01Y1501398D02*
Y1499784D01*
G01Y1511398D02*
Y1509784D01*
G01X1067921Y1500965D02*
Y1493681D01*
G01Y1510965D02*
Y1503681D01*
G01X1067480Y1494862D02*
Y1493248D01*
G01Y1501398D02*
Y1499784D01*
G01Y1504862D02*
Y1503248D01*
G01Y1511398D02*
Y1509784D01*
G01X1067113D02*
Y1510965D01*
G01Y1499784D02*
Y1500965D01*
G01Y1494862D02*
Y1493681D01*
G01Y1499784D02*
Y1494862D01*
G01Y1504862D02*
Y1503681D01*
G01Y1509784D02*
Y1504862D01*
G01X1066473D02*
Y1509784D01*
G01Y1494862D02*
Y1499784D01*
G01Y1494862D02*
Y1493681D01*
G01Y1500965D02*
Y1499784D01*
G01Y1504862D02*
Y1503681D01*
G01Y1510965D02*
Y1509784D01*
G01X1066320Y1500965D02*
Y1493681D01*
G01Y1510965D02*
Y1503681D01*
G01X1073779Y1509980D02*
X1073375D01*
G01X1073779Y1504666D02*
X1073375D01*
G01X1073779Y1499980D02*
X1073375D01*
G01X1073779Y1494666D02*
X1073375D01*
G01X1073779D02*
X1073708Y1494286D01*
G01X1073779Y1504666D02*
X1073708Y1504286D01*
G01X1073211Y1503757D02*
X1072855Y1503681D01*
G01X1073211Y1493757D02*
X1072855Y1493681D01*
G01X1073708Y1494286D02*
X1073508Y1493969D01*
G01X1073708Y1504286D02*
X1073508Y1503969D01*
G01Y1493969D02*
X1073211Y1493757D01*
G01X1073508Y1503969D02*
X1073211Y1503757D01*
G01Y1520888D02*
X1072855Y1520965D01*
G01X1073508Y1520676D02*
X1073211Y1520888D01*
G01Y1530888D02*
X1072855Y1530965D01*
G01X1073508Y1530676D02*
X1073211Y1530888D01*
G01X1073708Y1520360D02*
X1073779Y1519980D01*
G01X1073508Y1520676D02*
X1073708Y1520360D01*
G01Y1530360D02*
X1073779Y1529980D01*
G01X1073508Y1530676D02*
X1073708Y1530360D01*
G01X1069449Y1518799D02*
G03X1068464Y1519784I-985J0D01*
G01Y1514862D02*
G03X1069449Y1515847I0J985D01*
G01Y1528799D02*
G03X1068464Y1529784I-985J0D01*
G01Y1524862D02*
G03X1069449Y1525847I0J985D01*
G01X1073779Y1519980D02*
Y1514666D01*
G01Y1529980D02*
Y1524666D01*
G01X1073375Y1514666D02*
Y1519980D01*
G01Y1529980D02*
Y1524666D01*
G01X1069922Y1513681D02*
Y1520965D01*
G01Y1530965D02*
Y1523681D01*
G01X1069449Y1525847D02*
Y1528799D01*
G01Y1515847D02*
Y1518799D01*
G01X1068464Y1514862D02*
Y1513248D01*
G01Y1521398D02*
Y1519784D01*
G01Y1524862D02*
Y1523248D01*
G01Y1531398D02*
Y1529784D01*
G01X1067921Y1520965D02*
Y1513681D01*
G01Y1530965D02*
Y1523681D01*
G01X1067480Y1514862D02*
Y1513248D01*
G01Y1521398D02*
Y1519784D01*
G01Y1524862D02*
Y1523248D01*
G01Y1531398D02*
Y1529784D01*
G01X1067113D02*
Y1530965D01*
G01Y1519784D02*
Y1520965D01*
G01Y1514862D02*
Y1513681D01*
G01Y1519784D02*
Y1514862D01*
G01Y1524862D02*
Y1523681D01*
G01Y1529784D02*
Y1524862D01*
G01X1066473D02*
Y1529784D01*
G01Y1514862D02*
Y1519784D01*
G01Y1514862D02*
Y1513681D01*
G01Y1520965D02*
Y1519784D01*
G01Y1524862D02*
Y1523681D01*
G01Y1530965D02*
Y1529784D01*
G01X1066320Y1520965D02*
Y1513681D01*
G01Y1530965D02*
Y1523681D01*
G01X1073779Y1529980D02*
X1073375D01*
G01X1073779Y1524666D02*
X1073375D01*
G01X1073779Y1519980D02*
X1073375D01*
G01X1073779Y1514666D02*
X1073375D01*
G01X1073211Y1523757D02*
X1072855Y1523681D01*
G01X1073779Y1514666D02*
X1073708Y1514286D01*
G01X1073779Y1524666D02*
X1073708Y1524286D01*
G01X1073211Y1513757D02*
X1072855Y1513681D01*
G01X1073708Y1514286D02*
X1073508Y1513969D01*
G01X1073708Y1524286D02*
X1073508Y1523969D01*
G01Y1513969D02*
X1073211Y1513757D01*
G01X1073508Y1523969D02*
X1073211Y1523757D01*
G01Y1540888D02*
X1072855Y1540965D01*
G01X1073508Y1540676D02*
X1073211Y1540888D01*
G01X1073708Y1540360D02*
X1073779Y1539980D01*
G01X1073508Y1540676D02*
X1073708Y1540360D01*
G01Y1550360D02*
X1073779Y1549980D01*
G01X1073508Y1550676D02*
X1073708Y1550360D01*
G01X1073211Y1550888D02*
X1072855Y1550965D01*
G01X1073508Y1550676D02*
X1073211Y1550888D01*
G01X1069449Y1548799D02*
G03X1068464Y1549784I-985J0D01*
G01X1069449Y1538799D02*
G03X1068464Y1539784I-985J0D01*
G01Y1534862D02*
G03X1069449Y1535847I0J985D01*
G01X1068464Y1544862D02*
G03X1069449Y1545847I0J985D01*
G01X1073779Y1549980D02*
X1073375D01*
G01X1073779Y1544666D02*
X1073375D01*
G01X1073779Y1539980D02*
X1073375D01*
G01X1075945Y1553248D02*
Y1551398D01*
G01X1073779Y1534666D02*
Y1539980D01*
G01Y1549980D02*
Y1544666D01*
G01X1073375Y1534666D02*
Y1539980D01*
G01Y1549980D02*
Y1544666D01*
G01X1069922Y1553681D02*
Y1560965D01*
G01Y1533681D02*
Y1540965D01*
G01Y1550965D02*
Y1543681D01*
G01X1069449Y1545847D02*
Y1548799D01*
G01Y1535847D02*
Y1538799D01*
G01X1068464Y1543248D02*
Y1544862D01*
G01Y1534862D02*
Y1533248D01*
G01Y1541398D02*
Y1539784D01*
G01Y1551398D02*
Y1549784D01*
G01Y1554862D02*
Y1553248D01*
G01X1067921Y1540965D02*
Y1533681D01*
G01Y1550965D02*
Y1543681D01*
G01Y1560965D02*
Y1553681D01*
G01X1067480Y1534862D02*
Y1533248D01*
G01Y1541398D02*
Y1539784D01*
G01Y1544862D02*
Y1543248D01*
G01Y1554862D02*
Y1553248D01*
G01Y1551398D02*
Y1549784D01*
G01X1067113D02*
Y1550965D01*
G01Y1539784D02*
Y1540965D01*
G01Y1534862D02*
Y1533681D01*
G01Y1539784D02*
Y1534862D01*
G01Y1544862D02*
Y1543681D01*
G01Y1549784D02*
Y1544862D01*
G01Y1554862D02*
Y1553681D01*
G01X1066473Y1544862D02*
Y1549784D01*
G01Y1534862D02*
Y1539784D01*
G01Y1534862D02*
Y1533681D01*
G01Y1540965D02*
Y1539784D01*
G01Y1544862D02*
Y1543681D01*
G01Y1550965D02*
Y1549784D01*
G01Y1554862D02*
Y1553681D01*
G01X1066320Y1540965D02*
Y1533681D01*
G01Y1550965D02*
Y1543681D01*
G01Y1560965D02*
Y1553681D01*
G01X1073779Y1534666D02*
X1073375D01*
G01X1073211Y1553757D02*
X1072855Y1553681D01*
G01X1073211Y1543757D02*
X1072855Y1543681D01*
G01X1073211Y1533757D02*
X1072855Y1533681D01*
G01X1073779Y1534666D02*
X1073708Y1534286D01*
G01X1073779Y1544666D02*
X1073708Y1544286D01*
G01Y1534286D02*
X1073508Y1533969D01*
G01X1073708Y1544286D02*
X1073508Y1543969D01*
G01Y1533969D02*
X1073211Y1533757D01*
G01X1073508Y1543969D02*
X1073211Y1543757D01*
G01X1073508Y1553969D02*
X1073211Y1553757D01*
G01X1073708Y1560360D02*
X1073779Y1559980D01*
G01X1073508Y1560676D02*
X1073708Y1560360D01*
G01X1073211Y1560888D02*
X1073508Y1560676D01*
G01X1073708Y1570360D02*
X1073779Y1569980D01*
G01X1073508Y1570676D02*
X1073708Y1570360D01*
G01X1073211Y1570888D02*
X1073508Y1570676D01*
G01X1069449Y1558799D02*
G03X1068464Y1559784I-985J0D01*
G01Y1554862D02*
G03X1069449Y1555847I0J985D01*
G01Y1568799D02*
G03X1068464Y1569784I-985J0D01*
G01Y1564862D02*
G03X1069449Y1565847I0J985D01*
G01X1068464Y1574862D02*
G03X1069449Y1575847I0J985D01*
G01X1073211Y1570888D02*
X1072855Y1570965D01*
G01X1073211Y1560888D02*
X1072855Y1560965D01*
G01X1073779Y1574666D02*
X1073375D01*
G01X1073779Y1569980D02*
X1073375D01*
G01X1073779Y1564666D02*
X1073375D01*
G01X1073779Y1559980D02*
X1073375D01*
G01X1073779Y1554666D02*
X1073375D01*
G01X1073779Y1559980D02*
Y1554666D01*
G01Y1569980D02*
Y1564666D01*
G01Y1579980D02*
Y1574666D01*
G01X1073375Y1554666D02*
Y1559980D01*
G01Y1569980D02*
Y1564666D01*
G01Y1579980D02*
Y1574666D01*
G01X1069922Y1570965D02*
Y1563681D01*
G01Y1580965D02*
Y1573681D01*
G01X1069449Y1565847D02*
Y1568799D01*
G01Y1555847D02*
Y1558799D01*
G01X1068464Y1563248D02*
Y1564862D01*
G01Y1561398D02*
Y1559784D01*
G01Y1571398D02*
Y1569784D01*
G01Y1574862D02*
Y1573248D01*
G01X1067921Y1570965D02*
Y1563681D01*
G01Y1580965D02*
Y1573681D01*
G01X1067480Y1561398D02*
Y1559784D01*
G01Y1564862D02*
Y1563248D01*
G01Y1571398D02*
Y1569784D01*
G01Y1574862D02*
Y1573248D01*
G01X1067113Y1569784D02*
Y1570965D01*
G01Y1559784D02*
Y1560965D01*
G01Y1559784D02*
Y1554862D01*
G01Y1564862D02*
Y1563681D01*
G01Y1569784D02*
Y1564862D01*
G01Y1574862D02*
Y1573681D01*
G01Y1579784D02*
Y1574862D01*
G01X1066473D02*
Y1579784D01*
G01Y1564862D02*
Y1569784D01*
G01Y1554862D02*
Y1559784D01*
G01Y1560965D02*
Y1559784D01*
G01Y1564862D02*
Y1563681D01*
G01Y1570965D02*
Y1569784D01*
G01Y1574862D02*
Y1573681D01*
G01X1066320Y1570965D02*
Y1563681D01*
G01Y1580965D02*
Y1573681D01*
G01X1073211Y1573757D02*
X1072855Y1573681D01*
G01X1073211Y1563757D02*
X1072855Y1563681D01*
G01X1073779Y1554666D02*
X1073708Y1554286D01*
G01X1073779Y1564666D02*
X1073708Y1564286D01*
G01X1073779Y1574666D02*
X1073708Y1574286D01*
G01Y1554286D02*
X1073508Y1553969D01*
G01X1073708Y1564286D02*
X1073508Y1563969D01*
G01X1073708Y1574286D02*
X1073508Y1573969D01*
G01Y1563969D02*
X1073211Y1563757D01*
G01X1073508Y1573969D02*
X1073211Y1573757D01*
G01X1073708Y1580360D02*
X1073779Y1579980D01*
G01X1073508Y1580676D02*
X1073708Y1580360D01*
G01X1073211Y1580888D02*
X1073508Y1580676D01*
G01X1073708Y1590360D02*
X1073779Y1589980D01*
G01X1073508Y1590676D02*
X1073708Y1590360D01*
G01X1073211Y1590888D02*
X1073508Y1590676D01*
G01X1069449Y1578799D02*
G03X1068464Y1579784I-985J0D01*
G01X1069449Y1588799D02*
G03X1068464Y1589784I-985J0D01*
G01Y1584862D02*
G03X1069449Y1585847I0J985D01*
G01X1068464Y1594862D02*
G03X1069449Y1595847I0J985D01*
G01X1073211Y1590888D02*
X1072855Y1590965D01*
G01X1073211Y1580888D02*
X1072855Y1580965D01*
G01X1073779Y1594666D02*
X1073375D01*
G01X1073779Y1589980D02*
X1073375D01*
G01X1073779Y1584666D02*
X1073375D01*
G01X1073779Y1579980D02*
X1073375D01*
G01X1075945Y1593248D02*
Y1591398D01*
G01X1073779Y1594666D02*
Y1599980D01*
G01Y1589980D02*
Y1584666D01*
G01X1073375Y1594666D02*
Y1599980D01*
G01Y1589980D02*
Y1584666D01*
G01X1069922Y1593681D02*
Y1600965D01*
G01Y1590965D02*
Y1583681D01*
G01X1069449Y1595847D02*
Y1598799D01*
G01Y1585847D02*
Y1588799D01*
G01Y1575847D02*
Y1578799D01*
G01X1068464Y1583248D02*
Y1584862D01*
G01Y1581398D02*
Y1579784D01*
G01Y1591398D02*
Y1589784D01*
G01Y1594862D02*
Y1593248D01*
G01X1067921Y1590965D02*
Y1583681D01*
G01Y1600965D02*
Y1593681D01*
G01X1067480Y1581398D02*
Y1579784D01*
G01Y1584862D02*
Y1583248D01*
G01Y1591398D02*
Y1589784D01*
G01Y1594862D02*
Y1593248D01*
G01X1067113Y1589784D02*
Y1590965D01*
G01Y1579784D02*
Y1580965D01*
G01Y1584862D02*
Y1583681D01*
G01Y1589784D02*
Y1584862D01*
G01Y1594862D02*
Y1593681D01*
G01Y1599784D02*
Y1594862D01*
G01X1066473D02*
Y1599784D01*
G01Y1584862D02*
Y1589784D01*
G01Y1580965D02*
Y1579784D01*
G01Y1584862D02*
Y1583681D01*
G01Y1590965D02*
Y1589784D01*
G01Y1594862D02*
Y1593681D01*
G01X1066320Y1590965D02*
Y1583681D01*
G01Y1600965D02*
Y1593681D01*
G01X1073211Y1593757D02*
X1072855Y1593681D01*
G01X1073211Y1583757D02*
X1072855Y1583681D01*
G01X1073779Y1584666D02*
X1073708Y1584286D01*
G01X1073779Y1594666D02*
X1073708Y1594286D01*
G01Y1584286D02*
X1073508Y1583969D01*
G01X1073708Y1594286D02*
X1073508Y1593969D01*
G01Y1583969D02*
X1073211Y1583757D01*
G01X1073508Y1593969D02*
X1073211Y1593757D01*
G01X1073708Y1600360D02*
X1073779Y1599980D01*
G01X1073508Y1600676D02*
X1073708Y1600360D01*
G01X1073211Y1600888D02*
X1073508Y1600676D01*
G01X1069449Y1608799D02*
G03X1068464Y1609784I-985J0D01*
G01Y1604862D02*
G03X1069449Y1605847I0J985D01*
G01Y1598799D02*
G03X1068464Y1599784I-985J0D01*
G01X1073508Y1610676D02*
X1073708Y1610360D01*
G01X1073211Y1610888D02*
X1073508Y1610676D01*
G01X1073211Y1610888D02*
X1072855Y1610965D01*
G01X1073211Y1600888D02*
X1072855Y1600965D01*
G01X1073708Y1610360D02*
X1073779Y1609980D01*
G01X1078307Y1614744D02*
X1075945D01*
G01X1073779Y1609980D02*
X1073375D01*
G01X1073779Y1604666D02*
X1073375D01*
G01X1073779Y1599980D02*
X1073375D01*
G01X1075945Y1614744D02*
Y1686811D01*
G01X1073779Y1609980D02*
Y1604666D01*
G01X1073375Y1609980D02*
Y1604666D01*
G01X1069922Y1610965D02*
Y1603681D01*
G01X1069449Y1605847D02*
Y1608799D01*
G01X1068464Y1601398D02*
Y1599784D01*
G01Y1604862D02*
Y1603248D01*
G01Y1611398D02*
Y1609784D01*
G01X1067921Y1610965D02*
Y1603681D01*
G01X1067480Y1601398D02*
Y1599784D01*
G01Y1604862D02*
Y1603248D01*
G01Y1611398D02*
Y1609784D01*
G01X1067113D02*
Y1610965D01*
G01Y1599784D02*
Y1600965D01*
G01Y1604862D02*
Y1603681D01*
G01Y1609784D02*
Y1604862D01*
G01X1066473D02*
Y1609784D01*
G01Y1600965D02*
Y1599784D01*
G01Y1604862D02*
Y1603681D01*
G01Y1610965D02*
Y1609784D01*
G01X1066320Y1610965D02*
Y1603681D01*
G01X1073211Y1603757D02*
X1072855Y1603681D01*
G01X1073779Y1604666D02*
X1073708Y1604286D01*
G01D02*
X1073508Y1603969D01*
G01D02*
X1073211Y1603757D01*
G01X1075994Y1636831D02*
X1076535Y1636634D01*
G01X1075994Y1631831D02*
X1076535Y1631634D01*
G01X1075994Y1626831D02*
X1076535Y1626634D01*
G01X1075994Y1621831D02*
X1076535Y1621634D01*
G01X1075157Y1635118D02*
Y1637087D01*
G01Y1625118D02*
Y1627087D01*
G01Y1622087D02*
Y1620118D01*
G01Y1632087D02*
Y1630118D01*
G01X1073779Y1635118D02*
Y1637087D01*
G01Y1630118D02*
Y1632087D01*
G01Y1625118D02*
Y1627087D01*
G01Y1620118D02*
Y1622087D01*
G01X1072800Y1621831D02*
Y1620374D01*
G01Y1626831D02*
Y1625374D01*
G01Y1631831D02*
Y1630374D01*
G01Y1636831D02*
Y1635374D01*
G01X1071816Y1621831D02*
Y1620374D01*
G01Y1626831D02*
Y1625374D01*
G01Y1631831D02*
Y1630374D01*
G01Y1636831D02*
Y1635374D01*
G01X1071225Y1621831D02*
Y1620374D01*
G01Y1626831D02*
Y1625374D01*
G01Y1631831D02*
Y1630374D01*
G01Y1636831D02*
Y1635374D01*
G01X1069449Y1621831D02*
Y1620374D01*
G01Y1626831D02*
Y1625374D01*
G01Y1631831D02*
Y1630374D01*
G01Y1636831D02*
Y1635374D01*
G01X1068858Y1621831D02*
Y1620374D01*
G01Y1626831D02*
Y1625374D01*
G01Y1631831D02*
Y1630374D01*
G01Y1636831D02*
Y1635374D01*
G01X1076535Y1620571D02*
X1075994Y1620374D01*
G01X1076535Y1625571D02*
X1075994Y1625374D01*
G01X1076535Y1630571D02*
X1075994Y1630374D01*
G01X1076535Y1635571D02*
X1075994Y1635374D01*
G01Y1656831D02*
X1076535Y1656634D01*
G01X1075994Y1651831D02*
X1076535Y1651634D01*
G01X1075994Y1646831D02*
X1076535Y1646634D01*
G01X1075994Y1641831D02*
X1076535Y1641634D01*
G01X1075157Y1645118D02*
Y1647087D01*
G01Y1642087D02*
Y1640118D01*
G01Y1652087D02*
Y1650118D01*
G01Y1657087D02*
Y1655118D01*
G01X1073779D02*
Y1657087D01*
G01Y1650118D02*
Y1652087D01*
G01Y1645118D02*
Y1647087D01*
G01Y1640118D02*
Y1642087D01*
G01X1072800Y1641831D02*
Y1640374D01*
G01Y1646831D02*
Y1645374D01*
G01Y1651831D02*
Y1650374D01*
G01Y1656831D02*
Y1655374D01*
G01X1071816Y1641831D02*
Y1640374D01*
G01Y1646831D02*
Y1645374D01*
G01Y1651831D02*
Y1650374D01*
G01Y1656831D02*
Y1655374D01*
G01X1071225Y1641831D02*
Y1640374D01*
G01Y1646831D02*
Y1645374D01*
G01Y1651831D02*
Y1650374D01*
G01Y1656831D02*
Y1655374D01*
G01X1069449Y1641831D02*
Y1640374D01*
G01Y1646831D02*
Y1645374D01*
G01Y1651831D02*
Y1650374D01*
G01Y1656831D02*
Y1655374D01*
G01X1068858Y1641831D02*
Y1640374D01*
G01Y1646831D02*
Y1645374D01*
G01Y1651831D02*
Y1650374D01*
G01Y1656831D02*
Y1655374D01*
G01X1076535Y1640571D02*
X1075994Y1640374D01*
G01X1076535Y1645571D02*
X1075994Y1645374D01*
G01X1076535Y1650571D02*
X1075994Y1650374D01*
G01X1076535Y1655571D02*
X1075994Y1655374D01*
G01Y1676831D02*
X1076535Y1676634D01*
G01X1075994Y1671831D02*
X1076535Y1671634D01*
G01X1075994Y1666831D02*
X1076535Y1666634D01*
G01X1075994Y1661831D02*
X1076535Y1661634D01*
G01X1075157Y1662087D02*
Y1660118D01*
G01Y1667087D02*
Y1665118D01*
G01Y1672087D02*
Y1670118D01*
G01Y1677087D02*
Y1675118D01*
G01X1073779D02*
Y1677087D01*
G01Y1670118D02*
Y1672087D01*
G01Y1665118D02*
Y1667087D01*
G01Y1660118D02*
Y1662087D01*
G01X1072800Y1661831D02*
Y1660374D01*
G01Y1666831D02*
Y1665374D01*
G01Y1671831D02*
Y1670374D01*
G01Y1676831D02*
Y1675374D01*
G01X1071816Y1661831D02*
Y1660374D01*
G01Y1666831D02*
Y1665374D01*
G01Y1671831D02*
Y1670374D01*
G01Y1676831D02*
Y1675374D01*
G01X1071225Y1661831D02*
Y1660374D01*
G01Y1666831D02*
Y1665374D01*
G01Y1671831D02*
Y1670374D01*
G01Y1676831D02*
Y1675374D01*
G01X1069449Y1661831D02*
Y1660374D01*
G01Y1666831D02*
Y1665374D01*
G01Y1671831D02*
Y1670374D01*
G01Y1676831D02*
Y1675374D01*
G01X1068858Y1661831D02*
Y1660374D01*
G01Y1666831D02*
Y1665374D01*
G01Y1671831D02*
Y1670374D01*
G01Y1676831D02*
Y1675374D01*
G01X1076535Y1660571D02*
X1075994Y1660374D01*
G01X1076535Y1665571D02*
X1075994Y1665374D01*
G01X1076535Y1670571D02*
X1075994Y1670374D01*
G01X1076535Y1675571D02*
X1075994Y1675374D01*
G01X1079291Y1686221D02*
X1071417D01*
G01X1074567Y1685433D02*
X1079291Y1690158D01*
G01X1056338Y1716536D02*
X1097205D01*
G01X1080232Y1769359D02*
G03I-4291J0D01*
G01X1097205Y0D02*
G03X1112205Y15000I0J15000D01*
G01X1081242Y42048D02*
Y58048D01*
G01X1112205Y1378701D02*
G03X1097205Y1393701I-15000J0D01*
G01X1079291Y1421339D02*
Y1693307D01*
G01X1078715Y1433248D02*
Y1425065D01*
G01Y1443248D02*
Y1441398D01*
G01X1076732Y1443248D02*
Y1441398D01*
G01X1078715Y1453248D02*
Y1451398D01*
G01Y1463248D02*
Y1461398D01*
G01X1076732Y1453248D02*
Y1451398D01*
G01Y1463248D02*
Y1461398D01*
G01X1078715Y1473248D02*
Y1471398D01*
G01Y1483248D02*
Y1481398D01*
G01X1076732Y1483248D02*
Y1481398D01*
G01X1078715Y1493248D02*
Y1491398D01*
G01Y1503248D02*
Y1501398D01*
G01Y1513248D02*
Y1511398D01*
G01X1076732Y1493248D02*
Y1491398D01*
G01Y1503248D02*
Y1501398D01*
G01X1078715Y1523248D02*
Y1521398D01*
G01Y1533248D02*
Y1531398D01*
G01X1076732Y1523248D02*
Y1521398D01*
G01Y1533248D02*
Y1531398D01*
G01X1078715Y1543248D02*
Y1541398D01*
G01Y1553248D02*
Y1551398D01*
G01X1076732Y1543248D02*
Y1541398D01*
G01X1078715Y1563248D02*
Y1561398D01*
G01Y1573248D02*
Y1571398D01*
G01X1076732Y1563248D02*
Y1561398D01*
G01Y1573248D02*
Y1571398D01*
G01X1078715Y1583248D02*
Y1581398D01*
G01Y1593248D02*
Y1591398D01*
G01X1076732Y1583248D02*
Y1581398D01*
G01X1078307Y1614744D02*
X1079291Y1613760D01*
G01X1078715Y1603248D02*
Y1601398D01*
G01Y1620118D02*
Y1614336D01*
G01X1076732Y1603248D02*
Y1601398D01*
G01X1079291Y1612382D02*
X1078307Y1611398D01*
G01X1078715Y1625118D02*
Y1622087D01*
G01Y1630118D02*
Y1627087D01*
G01Y1635118D02*
Y1632087D01*
G01Y1640118D02*
Y1637087D01*
G01X1078307Y1622087D02*
Y1620118D01*
G01Y1627087D02*
Y1625118D01*
G01Y1632087D02*
Y1630118D01*
G01Y1637087D02*
Y1635118D01*
G01X1076535Y1621634D02*
Y1620571D01*
G01Y1626634D02*
Y1625571D01*
G01Y1631634D02*
Y1630571D01*
G01Y1636634D02*
Y1635571D01*
G01X1078715Y1645118D02*
Y1642087D01*
G01Y1650118D02*
Y1647087D01*
G01Y1655118D02*
Y1652087D01*
G01Y1660118D02*
Y1657087D01*
G01X1078307Y1655118D02*
Y1657087D01*
G01Y1642087D02*
Y1640118D01*
G01Y1647087D02*
Y1645118D01*
G01Y1652087D02*
Y1650118D01*
G01X1076535Y1641634D02*
Y1640571D01*
G01Y1646634D02*
Y1645571D01*
G01Y1651634D02*
Y1650571D01*
G01Y1656634D02*
Y1655571D01*
G01X1078715Y1665118D02*
Y1662087D01*
G01Y1670118D02*
Y1667087D01*
G01Y1675118D02*
Y1672087D01*
G01Y1689581D02*
Y1677087D01*
G01X1078307Y1662087D02*
Y1660118D01*
G01Y1667087D02*
Y1665118D01*
G01Y1672087D02*
Y1670118D01*
G01Y1677087D02*
Y1675118D01*
G01X1076535Y1661634D02*
Y1660571D01*
G01Y1666634D02*
Y1665571D01*
G01Y1671634D02*
Y1670571D01*
G01Y1676634D02*
Y1675571D01*
G01X1097205Y1716536D02*
G03X1112205Y1731536I0J15000D01*
G01Y1977126D02*
G03X1097205Y1992126I-15000J0D01*
G01X1112205Y648419D02*
Y15000D01*
G01X1110805Y463385D02*
X1113605D01*
G01X1110805Y494880D02*
X1113605D01*
G01X1110805Y526375D02*
X1113605D01*
G01X1110805Y557871D02*
X1113605D01*
G01X1110805Y589366D02*
X1113605D01*
G01X1110805Y620861D02*
X1113605D01*
G01X1112205Y656293D02*
G03Y648419I0J-3937D01*
G01Y1378701D02*
Y656293D01*
G01Y1977126D02*
Y1731536D01*
G01Y1941443D02*
Y2064661D01*
G01X1114545Y2065815D02*
X1115477Y2066413D01*
X1116009Y2067212D01*
X1116142Y2068110D01*
X1116009Y2068909D01*
X1115344Y2069707D01*
X1114545Y2070206D01*
X1113747Y2070306D01*
X1112815Y2070107D01*
X1112150Y2069408D01*
X1111883Y2068709D01*
Y2067811D01*
G01Y2068709D02*
X1111484Y2069308D01*
X1110819Y2069807D01*
X1110020Y2070007D01*
X1109222Y2069807D01*
X1108556Y2069308D01*
X1108157Y2068410D01*
X1108290Y2067511D01*
X1108823Y2066613D01*
G01X1108157Y2075995D02*
X1108423Y2075197D01*
X1109089Y2074598D01*
X1109887Y2074199D01*
X1110952Y2073899D01*
X1112150Y2073800D01*
X1113347Y2073899D01*
X1114412Y2074199D01*
X1115211Y2074598D01*
X1115876Y2075197D01*
X1116142Y2075995D01*
X1115876Y2076794D01*
X1115211Y2077393D01*
X1114412Y2077792D01*
X1113347Y2078092D01*
X1112150Y2078191D01*
X1110952Y2078092D01*
X1109887Y2077792D01*
X1109089Y2077393D01*
X1108423Y2076794D01*
X1108157Y2075995D01*
G01X1109488Y2082084D02*
X1108689Y2082683D01*
X1108290Y2083382D01*
X1108157Y2084180D01*
X1108423Y2085178D01*
X1109089Y2085877D01*
X1109887Y2086077D01*
X1110686Y2085977D01*
X1111351Y2085577D01*
X1112682Y2083581D01*
X1113613Y2082683D01*
X1114945Y2082084D01*
X1116142Y2081884D01*
Y2086077D01*
G01X1116408Y2091965D02*
X1116275Y2091766D01*
X1116009D01*
X1115876Y2091965D01*
X1116009Y2092165D01*
X1116275D01*
X1116408Y2091965D01*
G01X1114945Y2097755D02*
X1115610Y2098353D01*
X1116009Y2099052D01*
X1116142Y2099950D01*
X1115876Y2100849D01*
X1115344Y2101547D01*
X1114412Y2102047D01*
X1113347Y2102146D01*
X1112283Y2101947D01*
X1111617Y2101448D01*
X1111085Y2100749D01*
X1110952Y2100050D01*
X1111085Y2099352D01*
X1111617Y2098453D01*
X1108157Y2098753D01*
Y2101448D01*
G01Y2107935D02*
X1108423Y2107137D01*
X1109089Y2106538D01*
X1109887Y2106139D01*
X1110952Y2105839D01*
X1112150Y2105740D01*
X1113347Y2105839D01*
X1114412Y2106139D01*
X1115211Y2106538D01*
X1115876Y2107137D01*
X1116142Y2107935D01*
X1115876Y2108734D01*
X1115211Y2109333D01*
X1114412Y2109732D01*
X1113347Y2110032D01*
X1112150Y2110131D01*
X1110952Y2110032D01*
X1109887Y2109732D01*
X1109089Y2109333D01*
X1108423Y2108734D01*
X1108157Y2107935D01*
G01X1125518Y-51088D02*
Y-70025D01*
G01Y2126667D02*
Y2107730D01*
G01X1235844Y-66238D02*
X1236842Y-66048D01*
X1237983Y-65478D01*
X1238696Y-64527D01*
X1238981Y-63196D01*
X1238696Y-61866D01*
X1237840Y-60725D01*
X1236557Y-60154D01*
X1235131D01*
X1234275Y-59774D01*
X1233562Y-58824D01*
X1233277Y-57493D01*
X1233705Y-56162D01*
X1234703Y-55211D01*
X1235844Y-54831D01*
X1236985Y-55211D01*
X1237983Y-56162D01*
X1238411Y-57493D01*
X1238126Y-58824D01*
X1237413Y-59774D01*
X1236557Y-60154D01*
X1235131D01*
X1233848Y-60725D01*
X1232992Y-61866D01*
X1232707Y-63196D01*
X1232992Y-64527D01*
X1233705Y-65478D01*
X1234846Y-66048D01*
X1235844Y-66238D01*
G01Y2111517D02*
X1236842Y2111707D01*
X1237983Y2112277D01*
X1238696Y2113228D01*
X1238981Y2114559D01*
X1238696Y2115889D01*
X1237840Y2117030D01*
X1236557Y2117601D01*
X1235131D01*
X1234275Y2117981D01*
X1233562Y2118931D01*
X1233277Y2120262D01*
X1233705Y2121593D01*
X1234703Y2122544D01*
X1235844Y2122924D01*
X1236985Y2122544D01*
X1237983Y2121593D01*
X1238411Y2120262D01*
X1238126Y2118931D01*
X1237413Y2117981D01*
X1236557Y2117601D01*
X1235131D01*
X1233848Y2117030D01*
X1232992Y2115889D01*
X1232707Y2114559D01*
X1232992Y2113228D01*
X1233705Y2112277D01*
X1234846Y2111707D01*
X1235844Y2111517D01*
G01X1345188Y-51088D02*
Y-70025D01*
G01Y2126667D02*
Y2107730D01*
G01X1453089Y-64907D02*
X1454087Y-65858D01*
X1455228Y-66238D01*
X1456369Y-65858D01*
X1457367Y-64717D01*
X1458080Y-63006D01*
X1458365Y-61295D01*
Y-59204D01*
X1458080Y-57493D01*
X1457367Y-55972D01*
X1456511Y-55211D01*
X1455513Y-54831D01*
X1454372Y-55211D01*
X1453517Y-55972D01*
X1452946Y-57112D01*
X1452661Y-58634D01*
X1452946Y-59964D01*
X1453659Y-61295D01*
X1454515Y-62056D01*
X1455513Y-62246D01*
X1456654Y-61866D01*
X1457509Y-60915D01*
X1458365Y-59204D01*
G01X1453089Y2112848D02*
X1454087Y2111897D01*
X1455228Y2111517D01*
X1456369Y2111897D01*
X1457367Y2113038D01*
X1458080Y2114749D01*
X1458365Y2116460D01*
Y2118551D01*
X1458080Y2120262D01*
X1457367Y2121783D01*
X1456511Y2122544D01*
X1455513Y2122924D01*
X1454372Y2122544D01*
X1453517Y2121783D01*
X1452946Y2120643D01*
X1452661Y2119121D01*
X1452946Y2117791D01*
X1453659Y2116460D01*
X1454515Y2115699D01*
X1455513Y2115509D01*
X1456654Y2115889D01*
X1457509Y2116840D01*
X1458365Y2118551D01*
G01X1564857Y-51088D02*
Y-70025D01*
G01Y2126667D02*
Y2107730D01*
G01X1628688Y-51088D02*
X2018451D01*
G01X1672531Y-66238D02*
Y-54831D01*
X1670820Y-57112D01*
G01Y-66238D02*
X1674242D01*
G01X1683939Y-54831D02*
X1682798Y-55211D01*
X1681943Y-56162D01*
X1681372Y-57302D01*
X1680944Y-58824D01*
X1680802Y-60535D01*
X1680944Y-62246D01*
X1681372Y-63767D01*
X1681943Y-64907D01*
X1682798Y-65858D01*
X1683939Y-66238D01*
X1685080Y-65858D01*
X1685935Y-64907D01*
X1686506Y-63767D01*
X1686934Y-62246D01*
X1687076Y-60535D01*
X1686934Y-58824D01*
X1686506Y-57302D01*
X1685935Y-56162D01*
X1685080Y-55211D01*
X1683939Y-54831D01*
G01X1672531Y2111517D02*
Y2122924D01*
X1670820Y2120643D01*
G01Y2111517D02*
X1674242D01*
G01X1683939Y2122924D02*
X1682798Y2122544D01*
X1681943Y2121593D01*
X1681372Y2120453D01*
X1680944Y2118931D01*
X1680802Y2117220D01*
X1680944Y2115509D01*
X1681372Y2113988D01*
X1681943Y2112848D01*
X1682798Y2111897D01*
X1683939Y2111517D01*
X1685080Y2111897D01*
X1685935Y2112848D01*
X1686506Y2113988D01*
X1686934Y2115509D01*
X1687076Y2117220D01*
X1686934Y2118931D01*
X1686506Y2120453D01*
X1685935Y2121593D01*
X1685080Y2122544D01*
X1683939Y2122924D01*
G01X1784526Y-51088D02*
Y-70025D01*
G01Y2126667D02*
Y2107730D01*
G01X1830302D02*
X2338176D01*
G01X1862777Y32964D02*
Y-27204D01*
G01D02*
X2614877D01*
G01X1890315Y60362D02*
X1888815Y61362D01*
X1887065Y62029D01*
X1885065D01*
X1882815Y61029D01*
X1881065Y59362D01*
X1879815Y57362D01*
X1878815Y54029D01*
X1878565Y51029D01*
X1879065Y48029D01*
X1879815Y46029D01*
X1881315Y44029D01*
X1883065Y42696D01*
X1884815Y42029D01*
X1886565D01*
X1888315Y42696D01*
X1889815Y43695D01*
X1891065Y45028D01*
G01X1901315Y42029D02*
Y55362D01*
G01Y52696D02*
X1902565Y54029D01*
X1903815Y55029D01*
X1905565Y55362D01*
X1906815Y55029D01*
X1908315Y54029D01*
G01X1921065Y51029D02*
X1929065D01*
X1928315Y53362D01*
X1927065Y54695D01*
X1925315Y55362D01*
X1923565Y55029D01*
X1922065Y54029D01*
X1921065Y51695D01*
X1920565Y49695D01*
Y47696D01*
X1921065Y45695D01*
X1922315Y43695D01*
X1923815Y42362D01*
X1925565Y42029D01*
X1927315Y42696D01*
X1929065Y44695D01*
G01X1949315Y42029D02*
Y55362D01*
G01Y53029D02*
X1948315Y54362D01*
X1946815Y55029D01*
X1945065Y55362D01*
X1943315Y54695D01*
X1941815Y53362D01*
X1940815Y51362D01*
X1940315Y48695D01*
X1940815Y46029D01*
X1941815Y44029D01*
X1943315Y42696D01*
X1945065Y42029D01*
X1946815Y42362D01*
X1948315Y43362D01*
X1949315Y44695D01*
G01X1964815Y62029D02*
Y42029D01*
G01X1961315Y55362D02*
X1968315D01*
G01X1981065Y51029D02*
X1989065D01*
X1988315Y53362D01*
X1987065Y54695D01*
X1985315Y55362D01*
X1983565Y55029D01*
X1982065Y54029D01*
X1981065Y51695D01*
X1980565Y49695D01*
Y47696D01*
X1981065Y45695D01*
X1982315Y43695D01*
X1983815Y42362D01*
X1985565Y42029D01*
X1987315Y42696D01*
X1989065Y44695D01*
G01X2009315Y62029D02*
Y42029D01*
G01Y45028D02*
X2008315Y43362D01*
X2006815Y42362D01*
X2005065Y42029D01*
X2003065Y42696D01*
X2001565Y44362D01*
X2000565Y46362D01*
X2000315Y48695D01*
X2000565Y51029D01*
X2001565Y53029D01*
X2003065Y54695D01*
X2005065Y55362D01*
X2006815Y55029D01*
X2008065Y54362D01*
X2009315Y53029D01*
G01X1862777Y32964D02*
Y78090D01*
G01X2652482Y32964D02*
X1862777D01*
G01X1875863Y110937D02*
X1882113Y90937D01*
X1888363Y110937D01*
G01X1898363Y99937D02*
X1906363D01*
X1905613Y102270D01*
X1904363Y103603D01*
X1902613Y104270D01*
X1900863Y103937D01*
X1899363Y102937D01*
X1898363Y100603D01*
X1897863Y98603D01*
Y96604D01*
X1898363Y94603D01*
X1899613Y92603D01*
X1901113Y91270D01*
X1902863Y90937D01*
X1904613Y91604D01*
X1906363Y93603D01*
G01X1918613Y90937D02*
Y104270D01*
G01Y101604D02*
X1919863Y102937D01*
X1921113Y103937D01*
X1922863Y104270D01*
X1924113Y103937D01*
X1925613Y102937D01*
G01X1938363Y93270D02*
X1939613Y91937D01*
X1941363Y90937D01*
X1942863D01*
X1944363Y91604D01*
X1945363Y92603D01*
X1945863Y93936D01*
X1945613Y95937D01*
X1944613Y96937D01*
X1940113Y98937D01*
X1939113Y101271D01*
X1939613Y102937D01*
X1940613Y103937D01*
X1942113Y104270D01*
X1943613Y103937D01*
X1945113Y102937D01*
G01X1962113Y104270D02*
Y90937D01*
G01Y109603D02*
X1961613Y109937D01*
Y110604D01*
X1962113Y110937D01*
X1962613Y110604D01*
Y109937D01*
X1962113Y109603D01*
G01X1982113Y90937D02*
X1980613Y91270D01*
X1979113Y92603D01*
X1978113Y94937D01*
X1977613Y97603D01*
X1978113Y100270D01*
X1979113Y102604D01*
X1980613Y103937D01*
X1982113Y104270D01*
X1983613Y103937D01*
X1985113Y102604D01*
X1986113Y100270D01*
X1986363Y97603D01*
X1986113Y94937D01*
X1985113Y92603D01*
X1983613Y91270D01*
X1982113Y90937D01*
G01X1997863D02*
Y104270D01*
G01Y100937D02*
X1998863Y102604D01*
X2000363Y103937D01*
X2002363Y104270D01*
X2004113Y103937D01*
X2005613Y102604D01*
X2006363Y100270D01*
Y90937D01*
G01X1862777Y78090D02*
Y123216D01*
G01Y78090D02*
X2238827D01*
G01X1879815Y134951D02*
Y154951D01*
X1885815D01*
X1887815Y153951D01*
X1889315Y151618D01*
X1889815Y148951D01*
X1889315Y146284D01*
X1888065Y144284D01*
X1885815Y143284D01*
X1879815D01*
G01X1910315Y153284D02*
X1908815Y154284D01*
X1907065Y154951D01*
X1905065D01*
X1902815Y153951D01*
X1901065Y152284D01*
X1899815Y150284D01*
X1898815Y146951D01*
X1898565Y143951D01*
X1899065Y140951D01*
X1899815Y138951D01*
X1901315Y136951D01*
X1903065Y135618D01*
X1904815Y134951D01*
X1906565D01*
X1908315Y135618D01*
X1909815Y136617D01*
X1911065Y137950D01*
G01X1926815Y145618D02*
X1927815Y146618D01*
X1928565Y148284D01*
X1929065Y150618D01*
X1928565Y152618D01*
X1927565Y153951D01*
X1925815Y154951D01*
X1919065D01*
Y134951D01*
X1927315D01*
X1929065Y136284D01*
X1930065Y138284D01*
X1930565Y140618D01*
X1930065Y142951D01*
X1928565Y144951D01*
X1926815Y145618D01*
X1919065D01*
G01X1959065Y134951D02*
Y154951D01*
X1970565Y134951D01*
Y154951D01*
G01X1984815Y134951D02*
X1983315Y135284D01*
X1981815Y136617D01*
X1980815Y138951D01*
X1980315Y141617D01*
X1980815Y144284D01*
X1981815Y146618D01*
X1983315Y147951D01*
X1984815Y148284D01*
X1986315Y147951D01*
X1987815Y146618D01*
X1988815Y144284D01*
X1989065Y141617D01*
X1988815Y138951D01*
X1987815Y136617D01*
X1986315Y135284D01*
X1984815Y134951D01*
G01X2004815Y134284D02*
X2004315Y134618D01*
Y135284D01*
X2004815Y135618D01*
X2005315Y135284D01*
Y134618D01*
X2004815Y134284D01*
G01X1862777Y123216D02*
Y228486D01*
G01Y123216D02*
X2652482D01*
G01X1862777Y168342D02*
X2652482D01*
G01X1862777Y228486D02*
X2652482D01*
G01X1892958Y-66238D02*
Y-54831D01*
X1891247Y-57112D01*
G01Y-66238D02*
X1894669D01*
G01X1904366D02*
Y-54831D01*
X1902655Y-57112D01*
G01Y-66238D02*
X1906077D01*
G01X1888378Y179164D02*
Y206723D01*
X1897334Y183757D01*
X1906291Y206723D01*
Y179164D01*
G01X1924893D02*
X1922827Y179623D01*
X1920760Y181460D01*
X1919381Y184675D01*
X1918693Y188350D01*
X1919381Y192025D01*
X1920760Y195240D01*
X1922827Y197077D01*
X1924893Y197536D01*
X1926960Y197077D01*
X1929027Y195240D01*
X1930405Y192025D01*
X1930750Y188350D01*
X1930405Y184675D01*
X1929027Y181460D01*
X1926960Y179623D01*
X1924893Y179164D01*
G01X1958653Y206723D02*
Y179164D01*
G01Y183297D02*
X1957275Y181001D01*
X1955208Y179623D01*
X1952797Y179164D01*
X1950041Y180082D01*
X1947974Y182379D01*
X1946596Y185135D01*
X1946252Y188350D01*
X1946596Y191565D01*
X1947974Y194322D01*
X1950041Y196618D01*
X1952797Y197536D01*
X1955208Y197077D01*
X1956931Y196158D01*
X1958653Y194322D01*
G01X1974844Y191565D02*
X1985868D01*
X1984834Y194781D01*
X1983112Y196618D01*
X1980701Y197536D01*
X1978289Y197077D01*
X1976222Y195699D01*
X1974844Y192484D01*
X1974155Y189728D01*
Y186972D01*
X1974844Y184216D01*
X1976566Y181460D01*
X1978634Y179623D01*
X1981045Y179164D01*
X1983457Y180082D01*
X1985868Y182838D01*
G01X2007570Y179164D02*
Y206723D01*
G01X1892958Y2111517D02*
Y2122924D01*
X1891247Y2120643D01*
G01Y2111517D02*
X1894669D01*
G01X1904366D02*
Y2122924D01*
X1902655Y2120643D01*
G01Y2111517D02*
X1906077D01*
G01X1944138Y15022D02*
X1949649Y-16474D01*
X1955949Y15022D01*
X1962248Y-16474D01*
X1967760Y15022D01*
G01X1987445Y4523D02*
Y-16474D01*
G01Y12922D02*
X1986657Y13447D01*
Y14497D01*
X1987445Y15022D01*
X1988233Y14497D01*
Y13447D01*
X1987445Y12922D01*
G01X2013036Y-12800D02*
X2015004Y-14900D01*
X2017760Y-16474D01*
X2020122D01*
X2022485Y-15424D01*
X2024059Y-13850D01*
X2024846Y-11751D01*
X2024453Y-8600D01*
X2022878Y-7025D01*
X2015791Y-3876D01*
X2014217Y-201D01*
X2015004Y2423D01*
X2016579Y3998D01*
X2018941Y4523D01*
X2021303Y3998D01*
X2023665Y2423D01*
G01X2050437Y15022D02*
Y-16474D01*
G01X2044925Y4523D02*
X2055949D01*
G01X2076421Y-16474D02*
Y4523D01*
G01Y324D02*
X2078389Y2423D01*
X2080358Y3998D01*
X2083114Y4523D01*
X2085082Y3998D01*
X2087445Y2423D01*
G01X2113429Y-16474D02*
X2111067Y-15949D01*
X2108705Y-13850D01*
X2107129Y-10175D01*
X2106342Y-5976D01*
X2107129Y-1776D01*
X2108705Y1899D01*
X2111067Y3998D01*
X2113429Y4523D01*
X2115791Y3998D01*
X2118153Y1899D01*
X2119728Y-1776D01*
X2120122Y-5976D01*
X2119728Y-10175D01*
X2118153Y-13850D01*
X2115791Y-15949D01*
X2113429Y-16474D01*
G01X2138232D02*
Y4523D01*
G01Y-726D02*
X2139807Y1899D01*
X2142169Y3998D01*
X2145319Y4523D01*
X2148074Y3998D01*
X2150437Y1899D01*
X2151618Y-1776D01*
Y-16474D01*
G01X2216578Y12397D02*
X2214216Y13972D01*
X2211461Y15022D01*
X2208311D01*
X2204767Y13447D01*
X2202012Y10822D01*
X2200043Y7673D01*
X2198468Y2423D01*
X2198074Y-2301D01*
X2198862Y-7025D01*
X2200043Y-10175D01*
X2202405Y-13325D01*
X2205161Y-15424D01*
X2207917Y-16474D01*
X2210673D01*
X2213429Y-15424D01*
X2215791Y-13850D01*
X2217760Y-11751D01*
G01X2239413Y-16474D02*
X2237051Y-15949D01*
X2234689Y-13850D01*
X2233113Y-10175D01*
X2232326Y-5976D01*
X2233113Y-1776D01*
X2234689Y1899D01*
X2237051Y3998D01*
X2239413Y4523D01*
X2241775Y3998D01*
X2244137Y1899D01*
X2245712Y-1776D01*
X2246106Y-5976D01*
X2245712Y-10175D01*
X2244137Y-13850D01*
X2241775Y-15949D01*
X2239413Y-16474D01*
G01X2265397D02*
Y4523D01*
G01Y324D02*
X2267365Y2423D01*
X2269334Y3998D01*
X2272090Y4523D01*
X2274058Y3998D01*
X2276421Y2423D01*
G01X2295318Y-26972D02*
Y4523D01*
G01Y-201D02*
X2297287Y2423D01*
X2299255Y3998D01*
X2302405Y4523D01*
X2305161Y3998D01*
X2307917Y1374D01*
X2309098Y-2301D01*
X2309492Y-5976D01*
X2309098Y-9650D01*
X2307917Y-13325D01*
X2305554Y-15424D01*
X2302405Y-16474D01*
X2299649Y-15949D01*
X2296893Y-14375D01*
X2295318Y-12275D01*
G01X2333901Y-16474D02*
X2331539Y-15949D01*
X2329177Y-13850D01*
X2327601Y-10175D01*
X2326814Y-5976D01*
X2327601Y-1776D01*
X2329177Y1899D01*
X2331539Y3998D01*
X2333901Y4523D01*
X2336263Y3998D01*
X2338625Y1899D01*
X2340200Y-1776D01*
X2340594Y-5976D01*
X2340200Y-10175D01*
X2338625Y-13850D01*
X2336263Y-15949D01*
X2333901Y-16474D01*
G01X2359885D02*
Y4523D01*
G01Y324D02*
X2361853Y2423D01*
X2363822Y3998D01*
X2366578Y4523D01*
X2368546Y3998D01*
X2370909Y2423D01*
G01X2403980Y-16474D02*
Y4523D01*
G01Y849D02*
X2402405Y2948D01*
X2400042Y3998D01*
X2397287Y4523D01*
X2394531Y3473D01*
X2392169Y1374D01*
X2390593Y-1776D01*
X2389806Y-5976D01*
X2390593Y-10175D01*
X2392169Y-13325D01*
X2394531Y-15424D01*
X2397287Y-16474D01*
X2400042Y-15949D01*
X2402405Y-14375D01*
X2403980Y-12275D01*
G01X2428389Y15022D02*
Y-16474D01*
G01X2422877Y4523D02*
X2433901D01*
G01X2459885D02*
Y-16474D01*
G01Y12922D02*
X2459097Y13447D01*
Y14497D01*
X2459885Y15022D01*
X2460673Y14497D01*
Y13447D01*
X2459885Y12922D01*
G01X2491381Y-16474D02*
X2489019Y-15949D01*
X2486657Y-13850D01*
X2485081Y-10175D01*
X2484294Y-5976D01*
X2485081Y-1776D01*
X2486657Y1899D01*
X2489019Y3998D01*
X2491381Y4523D01*
X2493743Y3998D01*
X2496105Y1899D01*
X2497680Y-1776D01*
X2498074Y-5976D01*
X2497680Y-10175D01*
X2496105Y-13850D01*
X2493743Y-15949D01*
X2491381Y-16474D01*
G01X2516184D02*
Y4523D01*
G01Y-726D02*
X2517759Y1899D01*
X2520121Y3998D01*
X2523271Y4523D01*
X2526026Y3998D01*
X2528389Y1899D01*
X2529570Y-1776D01*
Y-16474D01*
G01X2003249Y-51088D02*
Y-70025D01*
G01X2004195Y2126667D02*
Y2107730D01*
G01X2018451Y-51088D02*
X2668885D01*
G01X2050802Y32964D02*
Y228486D01*
G01X2082269Y44004D02*
Y64004D01*
X2088519D01*
X2090519Y63004D01*
X2091769Y61671D01*
X2092269Y59004D01*
X2091769Y56337D01*
X2090269Y54671D01*
X2088519Y53670D01*
X2082269D01*
G01X2088519D02*
X2092269Y44004D01*
G01X2107269D02*
X2105769Y44337D01*
X2104269Y45670D01*
X2103269Y48004D01*
X2102769Y50670D01*
X2103269Y53337D01*
X2104269Y55671D01*
X2105769Y57004D01*
X2107269Y57337D01*
X2108769Y57004D01*
X2110269Y55671D01*
X2111269Y53337D01*
X2111519Y50670D01*
X2111269Y48004D01*
X2110269Y45670D01*
X2108769Y44337D01*
X2107269Y44004D01*
G01X2122769D02*
Y64004D01*
G01Y54004D02*
X2124019Y56004D01*
X2125519Y57004D01*
X2127019Y57337D01*
X2129269Y56670D01*
X2130769Y55337D01*
X2131769Y53004D01*
Y50337D01*
X2131269Y47670D01*
X2130269Y45670D01*
X2128519Y44337D01*
X2127019Y44004D01*
X2125519Y44337D01*
X2124019Y45337D01*
X2122769Y47003D01*
G01X2093017Y136925D02*
Y156925D01*
X2090017Y152925D01*
G01Y136925D02*
X2096017D01*
G01X2108267Y153592D02*
X2109767Y155591D01*
X2111517Y156592D01*
X2113517Y156925D01*
X2116017Y156258D01*
X2117767Y154592D01*
X2118267Y152592D01*
X2118017Y150591D01*
X2117017Y148925D01*
X2112017Y145592D01*
X2109767Y143258D01*
X2108267Y139924D01*
X2107767Y136925D01*
X2118267D01*
G01X2136017D02*
Y156925D01*
X2126767Y142592D01*
X2139267D01*
G01X2147517Y140925D02*
X2149017Y138591D01*
X2151017Y137258D01*
X2153267Y136925D01*
X2155267Y137258D01*
X2157267Y138925D01*
X2158517Y140925D01*
X2158767Y142925D01*
X2158267Y145258D01*
X2156517Y146925D01*
X2154767Y147592D01*
X2152517D01*
G01X2154767D02*
X2156267Y148592D01*
X2157517Y150258D01*
X2158017Y152258D01*
X2157517Y154258D01*
X2156267Y155925D01*
X2154017Y156925D01*
X2151767Y156592D01*
X2149517Y155258D01*
G01X2168267Y153592D02*
X2169767Y155591D01*
X2171517Y156592D01*
X2173517Y156925D01*
X2176017Y156258D01*
X2177767Y154592D01*
X2178267Y152592D01*
X2178017Y150591D01*
X2177017Y148925D01*
X2172017Y145592D01*
X2169767Y143258D01*
X2168267Y139924D01*
X2167767Y136925D01*
X2178267D01*
G01X2076122Y182870D02*
Y210429D01*
G01X2089212D02*
X2076122Y193434D01*
G01X2091279Y182870D02*
X2081978Y201242D01*
G01X2103336Y182870D02*
Y210429D01*
X2119183Y182870D01*
Y210429D01*
G01X2138818Y182870D02*
X2136062Y183329D01*
X2133651Y185166D01*
X2131584Y187922D01*
X2130206Y191138D01*
X2129517Y194812D01*
Y198487D01*
X2130206Y202161D01*
X2131584Y205377D01*
X2133651Y208132D01*
X2136062Y209970D01*
X2138818Y210429D01*
X2141574Y209970D01*
X2143986Y208132D01*
X2146053Y205377D01*
X2147431Y202161D01*
X2148120Y198487D01*
Y194812D01*
X2147431Y191138D01*
X2146053Y187922D01*
X2143986Y185166D01*
X2141574Y183329D01*
X2138818Y182870D01*
G01X2159143D02*
X2173612Y210429D01*
G01X2159143D02*
X2173612Y182870D01*
G01X2110733Y-66238D02*
Y-54831D01*
X2109022Y-57112D01*
G01Y-66238D02*
X2112444D01*
G01X2119432Y-56732D02*
X2120287Y-55592D01*
X2121285Y-55021D01*
X2122426Y-54831D01*
X2123852Y-55211D01*
X2124850Y-56162D01*
X2125136Y-57302D01*
X2124993Y-58443D01*
X2124423Y-59394D01*
X2121571Y-61295D01*
X2120287Y-62626D01*
X2119432Y-64527D01*
X2119146Y-66238D01*
X2125136D01*
G01X2107047Y86043D02*
Y106043D01*
X2104047Y102043D01*
G01Y86043D02*
X2110047D01*
G01X2110733Y2111517D02*
Y2122924D01*
X2109022Y2120643D01*
G01Y2111517D02*
X2112444D01*
G01X2119432Y2121023D02*
X2120287Y2122163D01*
X2121285Y2122734D01*
X2122426Y2122924D01*
X2123852Y2122544D01*
X2124850Y2121593D01*
X2125136Y2120453D01*
X2124993Y2119312D01*
X2124423Y2118361D01*
X2121571Y2116460D01*
X2120287Y2115129D01*
X2119432Y2113228D01*
X2119146Y2111517D01*
X2125136D01*
G01X2223865Y-51088D02*
Y-70025D01*
G01X2238827Y78090D02*
X2652482D01*
G01X2223865Y2126667D02*
Y2107730D01*
G01X2239927Y123409D02*
Y33279D01*
G01X2255872Y110737D02*
Y90737D01*
G01X2250122Y110737D02*
X2261622D01*
G01X2271622Y90737D02*
Y110737D01*
G01Y101071D02*
X2272872Y102737D01*
X2274122Y103737D01*
X2276122Y104070D01*
X2277622Y103737D01*
X2279372Y102404D01*
X2280122Y100403D01*
Y90737D01*
G01X2295872Y104070D02*
Y90737D01*
G01Y109403D02*
X2295372Y109737D01*
Y110404D01*
X2295872Y110737D01*
X2296372Y110404D01*
Y109737D01*
X2295872Y109403D01*
G01X2319872Y102404D02*
X2318122Y103737D01*
X2316622Y104070D01*
X2314622Y103403D01*
X2313122Y102070D01*
X2312122Y99737D01*
X2311872Y97403D01*
X2312122Y95070D01*
X2313122Y93070D01*
X2314622Y91404D01*
X2316622Y90737D01*
X2318372Y91404D01*
X2319872Y92737D01*
G01X2331622Y90737D02*
Y110737D01*
G01X2339622Y104070D02*
X2331622Y96404D01*
G01X2334872Y99404D02*
X2340122Y90737D01*
G01X2351622D02*
Y104070D01*
G01Y100737D02*
X2352622Y102404D01*
X2354122Y103737D01*
X2356122Y104070D01*
X2357872Y103737D01*
X2359372Y102404D01*
X2360122Y100070D01*
Y90737D01*
G01X2372122Y99737D02*
X2380122D01*
X2379372Y102070D01*
X2378122Y103403D01*
X2376372Y104070D01*
X2374622Y103737D01*
X2373122Y102737D01*
X2372122Y100403D01*
X2371622Y98403D01*
Y96404D01*
X2372122Y94403D01*
X2373372Y92403D01*
X2374872Y91070D01*
X2376622Y90737D01*
X2378372Y91404D01*
X2380122Y93403D01*
G01X2392122Y93070D02*
X2393372Y91737D01*
X2395122Y90737D01*
X2396622D01*
X2398122Y91404D01*
X2399122Y92403D01*
X2399622Y93736D01*
X2399372Y95737D01*
X2398372Y96737D01*
X2393872Y98737D01*
X2392872Y101071D01*
X2393372Y102737D01*
X2394372Y103737D01*
X2395872Y104070D01*
X2397372Y103737D01*
X2398872Y102737D01*
G01X2412122Y93070D02*
X2413372Y91737D01*
X2415122Y90737D01*
X2416622D01*
X2418122Y91404D01*
X2419122Y92403D01*
X2419622Y93736D01*
X2419372Y95737D01*
X2418372Y96737D01*
X2413872Y98737D01*
X2412872Y101071D01*
X2413372Y102737D01*
X2414372Y103737D01*
X2415872Y104070D01*
X2417372Y103737D01*
X2418872Y102737D01*
G01X2292946Y42029D02*
Y62029D01*
X2297946D01*
X2299946Y61029D01*
X2301446Y59696D01*
X2302696Y57696D01*
X2303696Y55362D01*
X2303946Y52029D01*
X2303696Y48695D01*
X2302696Y46362D01*
X2301446Y44362D01*
X2299946Y43029D01*
X2297946Y42029D01*
X2292946D01*
G01X2322946D02*
Y55362D01*
G01Y53029D02*
X2321946Y54362D01*
X2320446Y55029D01*
X2318696Y55362D01*
X2316946Y54695D01*
X2315446Y53362D01*
X2314446Y51362D01*
X2313946Y48695D01*
X2314446Y46029D01*
X2315446Y44029D01*
X2316946Y42696D01*
X2318696Y42029D01*
X2320446Y42362D01*
X2321946Y43362D01*
X2322946Y44695D01*
G01X2338446Y62029D02*
Y42029D01*
G01X2334946Y55362D02*
X2341946D01*
G01X2354696Y51029D02*
X2362696D01*
X2361946Y53362D01*
X2360696Y54695D01*
X2358946Y55362D01*
X2357196Y55029D01*
X2355696Y54029D01*
X2354696Y51695D01*
X2354196Y49695D01*
Y47696D01*
X2354696Y45695D01*
X2355946Y43695D01*
X2357446Y42362D01*
X2359196Y42029D01*
X2360946Y42696D01*
X2362696Y44695D01*
G01X2330403Y-66238D02*
Y-54831D01*
X2328692Y-57112D01*
G01Y-66238D02*
X2332114D01*
G01X2338674Y-63957D02*
X2339529Y-65288D01*
X2340670Y-66048D01*
X2341954Y-66238D01*
X2343095Y-66048D01*
X2344235Y-65098D01*
X2344948Y-63957D01*
X2345091Y-62816D01*
X2344806Y-61485D01*
X2343807Y-60535D01*
X2342809Y-60154D01*
X2341526D01*
G01X2342809D02*
X2343665Y-59584D01*
X2344378Y-58634D01*
X2344663Y-57493D01*
X2344378Y-56352D01*
X2343665Y-55402D01*
X2342381Y-54831D01*
X2341098Y-55021D01*
X2339815Y-55782D01*
G01X2330403Y2111517D02*
Y2122924D01*
X2328692Y2120643D01*
G01Y2111517D02*
X2332114D01*
G01X2338674Y2113798D02*
X2339529Y2112467D01*
X2340670Y2111707D01*
X2341954Y2111517D01*
X2343095Y2111707D01*
X2344235Y2112657D01*
X2344948Y2113798D01*
X2345091Y2114939D01*
X2344806Y2116270D01*
X2343807Y2117220D01*
X2342809Y2117601D01*
X2341526D01*
G01X2342809D02*
X2343665Y2118171D01*
X2344378Y2119121D01*
X2344663Y2120262D01*
X2344378Y2121403D01*
X2343665Y2122353D01*
X2342381Y2122924D01*
X2341098Y2122734D01*
X2339815Y2121973D01*
G01X2338176Y2107730D02*
X2668884D01*
G01X2423525Y123409D02*
Y33279D01*
G01X2443534Y-51088D02*
Y-70025D01*
G01Y2126667D02*
Y2107730D01*
G01X2465071Y62732D02*
X2466571Y64731D01*
X2468321Y65732D01*
X2470321Y66065D01*
X2472821Y65398D01*
X2474571Y63732D01*
X2475071Y61732D01*
X2474821Y59731D01*
X2473821Y58065D01*
X2468821Y54732D01*
X2466571Y52398D01*
X2465071Y49064D01*
X2464571Y46065D01*
X2475071D01*
G01X2489821Y66065D02*
X2487821Y65398D01*
X2486321Y63732D01*
X2485321Y61732D01*
X2484571Y59065D01*
X2484321Y56065D01*
X2484571Y53065D01*
X2485321Y50398D01*
X2486321Y48398D01*
X2487821Y46732D01*
X2489821Y46065D01*
X2491821Y46732D01*
X2493321Y48398D01*
X2494321Y50398D01*
X2495071Y53065D01*
X2495321Y56065D01*
X2495071Y59065D01*
X2494321Y61732D01*
X2493321Y63732D01*
X2491821Y65398D01*
X2489821Y66065D01*
G01X2509821Y46065D02*
Y66065D01*
X2506821Y62065D01*
G01Y46065D02*
X2512821D01*
G01X2525071Y62732D02*
X2526571Y64731D01*
X2528321Y65732D01*
X2530321Y66065D01*
X2532821Y65398D01*
X2534571Y63732D01*
X2535071Y61732D01*
X2534821Y59731D01*
X2533821Y58065D01*
X2528821Y54732D01*
X2526571Y52398D01*
X2525071Y49064D01*
X2524571Y46065D01*
X2535071D01*
G01X2546571Y52731D02*
X2553071D01*
G01X2569821Y46065D02*
Y66065D01*
X2566821Y62065D01*
G01Y46065D02*
X2572821D01*
G01X2589821Y66065D02*
X2587821Y65398D01*
X2586321Y63732D01*
X2585321Y61732D01*
X2584571Y59065D01*
X2584321Y56065D01*
X2584571Y53065D01*
X2585321Y50398D01*
X2586321Y48398D01*
X2587821Y46732D01*
X2589821Y46065D01*
X2591821Y46732D01*
X2593321Y48398D01*
X2594321Y50398D01*
X2595071Y53065D01*
X2595321Y56065D01*
X2595071Y59065D01*
X2594321Y61732D01*
X2593321Y63732D01*
X2591821Y65398D01*
X2589821Y66065D01*
G01X2606571Y52731D02*
X2613071D01*
G01X2629821Y46065D02*
Y66065D01*
X2626821Y62065D01*
G01Y46065D02*
X2632821D01*
G01X2649821D02*
Y66065D01*
X2646821Y62065D01*
G01Y46065D02*
X2652821D01*
G01X2465071Y109379D02*
X2466571Y111378D01*
X2468321Y112379D01*
X2470321Y112712D01*
X2472821Y112045D01*
X2474571Y110379D01*
X2475071Y108379D01*
X2474821Y106378D01*
X2473821Y104712D01*
X2468821Y101379D01*
X2466571Y99045D01*
X2465071Y95711D01*
X2464571Y92712D01*
X2475071D01*
G01X2489821Y92045D02*
X2489321Y92379D01*
Y93045D01*
X2489821Y93379D01*
X2490321Y93045D01*
Y92379D01*
X2489821Y92045D01*
G01X2509821Y92712D02*
Y112712D01*
X2506821Y108712D01*
G01Y92712D02*
X2512821D01*
G01X2525071Y101045D02*
X2526821Y103379D01*
X2528321Y104712D01*
X2530321Y105378D01*
X2532071Y104712D01*
X2533321Y103379D01*
X2534321Y101379D01*
X2534571Y99045D01*
X2534321Y97045D01*
X2533321Y95045D01*
X2531821Y93379D01*
X2530071Y92712D01*
X2528071Y93379D01*
X2526321Y95378D01*
X2525321Y98379D01*
X2525071Y101712D01*
X2525571Y106045D01*
X2526321Y108379D01*
X2527571Y110712D01*
X2529321Y112379D01*
X2531071Y112712D01*
X2532821Y112045D01*
X2534071Y110379D01*
G01X2562321Y92712D02*
Y106045D01*
G01Y102378D02*
X2563071Y104045D01*
X2564321Y105378D01*
X2566071Y106045D01*
X2567821Y105378D01*
X2569071Y104045D01*
X2569821Y102378D01*
Y92712D01*
G01Y102378D02*
X2570571Y104045D01*
X2571821Y105378D01*
X2573571Y106045D01*
X2575321Y105378D01*
X2576571Y104045D01*
X2577321Y102045D01*
Y92712D01*
G01X2582321D02*
Y106045D01*
G01Y102378D02*
X2583071Y104045D01*
X2584321Y105378D01*
X2586071Y106045D01*
X2587821Y105378D01*
X2589071Y104045D01*
X2589821Y102378D01*
Y92712D01*
G01Y102378D02*
X2590571Y104045D01*
X2591821Y105378D01*
X2593571Y106045D01*
X2595321Y105378D01*
X2596571Y104045D01*
X2597321Y102045D01*
Y92712D01*
G01X2550072Y-66238D02*
Y-54831D01*
X2548361Y-57112D01*
G01Y-66238D02*
X2551783D01*
G01X2563191D02*
Y-54831D01*
X2557915Y-63006D01*
X2565045D01*
G01X2550072Y2111517D02*
Y2122924D01*
X2548361Y2120643D01*
G01Y2111517D02*
X2551783D01*
G01X2563191D02*
Y2122924D01*
X2557915Y2114749D01*
X2565045D01*
G01X2614877Y-27204D02*
X2652482D01*
G01D02*
Y170115D01*
G01D02*
Y228486D01*
G01X2668884Y2107730D02*
Y-51088D01*
G01X2668885Y93596D02*
Y-51088D01*
G01X2675802Y53452D02*
X2676515Y52311D01*
X2677370Y51551D01*
X2678369Y51171D01*
X2679510Y51551D01*
X2680365Y52311D01*
X2681221Y53452D01*
X2681506Y54973D01*
Y62578D01*
G01X2668884Y164793D02*
X2687821D01*
G01X2676943Y278460D02*
X2680365D01*
G01X2678654D02*
Y267053D01*
G01X2676943D02*
X2680365D01*
G01X2668884Y380675D02*
X2687821D01*
G01X2675659Y482745D02*
Y494152D01*
G01X2681649D02*
Y482745D01*
G01Y488448D02*
X2675659D01*
G01X2668884Y596557D02*
X2687821D01*
G01X2679510Y704330D02*
X2682362D01*
Y700908D01*
X2681506Y699767D01*
X2680508Y699007D01*
X2679082Y698627D01*
X2677656Y699007D01*
X2676658Y699767D01*
X2675802Y700908D01*
X2675231Y702239D01*
X2674946Y703760D01*
Y705091D01*
X2675231Y706231D01*
X2675802Y707563D01*
X2676658Y708703D01*
X2677513Y709463D01*
X2678654Y710034D01*
X2679652D01*
X2680793Y709654D01*
X2681649Y708893D01*
G01X2668884Y812440D02*
X2687821D01*
G01X2675566Y914699D02*
Y926106D01*
X2680984D01*
G01X2678988Y920593D02*
X2675566D01*
G01X2668884Y1028321D02*
X2687821D01*
G01X2681506Y1130770D02*
X2675802D01*
Y1142177D01*
X2681506D01*
G01X2679224Y1136664D02*
X2675802D01*
G01X2668884Y1244203D02*
X2687821D01*
G01X2675517Y1346462D02*
Y1357869D01*
X2678369D01*
X2679510Y1357298D01*
X2680365Y1356538D01*
X2681078Y1355398D01*
X2681649Y1354066D01*
X2681791Y1352165D01*
X2681649Y1350264D01*
X2681078Y1348933D01*
X2680365Y1347793D01*
X2679510Y1347032D01*
X2678369Y1346462D01*
X2675517D01*
G01X2668884Y1460084D02*
X2687821D01*
G01X2681791Y1572990D02*
X2680936Y1573561D01*
X2679938Y1573941D01*
X2678797D01*
X2677513Y1573370D01*
X2676515Y1572420D01*
X2675802Y1571279D01*
X2675231Y1569378D01*
X2675089Y1567667D01*
X2675374Y1565956D01*
X2675802Y1564815D01*
X2676658Y1563674D01*
X2677656Y1562914D01*
X2678654Y1562534D01*
X2679652D01*
X2680650Y1562914D01*
X2681506Y1563484D01*
X2682219Y1564245D01*
G01X2668884Y1675966D02*
X2687821D01*
G01X2679795Y1784311D02*
X2680365Y1784881D01*
X2680793Y1785831D01*
X2681078Y1787163D01*
X2680793Y1788303D01*
X2680223Y1789063D01*
X2679224Y1789634D01*
X2675374D01*
Y1778227D01*
X2680080D01*
X2681078Y1778987D01*
X2681649Y1780128D01*
X2681934Y1781459D01*
X2681649Y1782790D01*
X2680793Y1783930D01*
X2679795Y1784311D01*
X2675374D01*
G01X2668695Y1891848D02*
X2687632D01*
G01X2675089Y1994108D02*
X2678654Y2005515D01*
X2682219Y1994108D01*
G01X2680936Y1998100D02*
X2676372D01*
G01X2668884Y2107730D02*
Y2013242D01*
G01X2687821Y2126667D02*
Y-70025D01*
M02*
